G04 ================== begin FILE IDENTIFICATION RECORD ==================*
G04 Layout Name:  E:/<user>/9332_F0TG_MB_C/brd/0417/9332_F0TG_MB_C_V02_0417_0820.brd*
G04 Film Name:    gnd4*
G04 File Format:  Gerber RS274X*
G04 File Origin:  Cadence Allegro 17.2-S081*
G04 Origin Date:  Wed Apr 19 14:50:09 2023*
G04 *
G04 Layer:  DRAWING FORMAT/TITLE_BLOCK_A*
G04 Layer:  PIN/SPECIAL_DRILL*
G04 Layer:  VIA CLASS/GND4*
G04 Layer:  PIN/GND4*
G04 Layer:  MANUFACTURING/PHOTOPLOT_OUTLINE*
G04 Layer:  ETCH/GND4*
G04 Layer:  DRAWING FORMAT/TITLE_BLOCK*
G04 Layer:  DRAWING FORMAT/TITLE_DATA_GND4*
G04 *
G04 Offset:    (0.00 0.00)*
G04 Mirror:    No*
G04 Mode:      Negative*
G04 Rotation:  0*
G04 FullContactRelief:  No*
G04 UndefLineWidth:     6.00*
G04 ================== end FILE IDENTIFICATION RECORD ====================*
%FSLAX25Y25*MOIN*%
%IR0*IPPOS*OFA0.00000B0.00000*MIA0B0*SFA1.00000B1.00000*%
%ADD14C,.03*%
%ADD41C,.06*%
%ADD30C,.024*%
%ADD68C,.052*%
%ADD25C,.061*%
%AMMACRO54*
4,1,36,0.0,.01,
-.001736,.009848,
-.00342,.009397,
-.005,.00866,
-.006428,.00766,
-.00766,.006428,
-.00866,.005,
-.009397,.00342,
-.009848,.001736,
-.01,0.0,
-.009848,-.001736,
-.009397,-.00342,
-.00866,-.005,
-.00766,-.006428,
-.006428,-.00766,
-.005,-.00866,
-.00342,-.009397,
-.001736,-.009848,
0.0,-.01,
.001736,-.009848,
.00342,-.009397,
.005,-.00866,
.006428,-.00766,
.00766,-.006428,
.00866,-.005,
.009397,-.00342,
.009848,-.001736,
.01,0.0,
.009848,.001736,
.009397,.00342,
.00866,.005,
.00766,.006428,
.006428,.00766,
.005,.00866,
.00342,.009397,
.001736,.009848,
0.0,.01,
0.0*
%
%ADD54MACRO54*%
%ADD43C,.071*%
%ADD23C,.026*%
%ADD64C,.064*%
%AMMACRO28*
4,1,36,.0025,0.0,
.002462,.000434,
.002349,.000855,
.002165,.00125,
.001915,.001607,
.001607,.001915,
.00125,.002165,
.000855,.002349,
.000434,.002462,
0.0,.0025,
-.000434,.002462,
-.000855,.002349,
-.00125,.002165,
-.001607,.001915,
-.001915,.001607,
-.002165,.00125,
-.002349,.000855,
-.002462,.000434,
-.0025,0.0,
-.002462,-.000434,
-.002349,-.000855,
-.002165,-.00125,
-.001915,-.001607,
-.001607,-.001915,
-.00125,-.002165,
-.000855,-.002349,
-.000434,-.002462,
0.0,-.0025,
.000434,-.002462,
.000855,-.002349,
.00125,-.002165,
.001607,-.001915,
.001915,-.001607,
.002165,-.00125,
.002349,-.000855,
.002462,-.000434,
.0025,0.0,
135.*
%
%ADD28MACRO28*%
%ADD24C,.028*%
%AMMACRO19*
4,1,36,.0025,0.0,
.002462,.000434,
.002349,.000855,
.002165,.00125,
.001915,.001607,
.001607,.001915,
.00125,.002165,
.000855,.002349,
.000434,.002462,
0.0,.0025,
-.000434,.002462,
-.000855,.002349,
-.00125,.002165,
-.001607,.001915,
-.001915,.001607,
-.002165,.00125,
-.002349,.000855,
-.002462,.000434,
-.0025,0.0,
-.002462,-.000434,
-.002349,-.000855,
-.002165,-.00125,
-.001915,-.001607,
-.001607,-.001915,
-.00125,-.002165,
-.000855,-.002349,
-.000434,-.002462,
0.0,-.0025,
.000434,-.002462,
.000855,-.002349,
.00125,-.002165,
.001607,-.001915,
.001915,-.001607,
.002165,-.00125,
.002349,-.000855,
.002462,-.000434,
.0025,0.0,
180.*
%
%ADD19MACRO19*%
%AMMACRO17*
4,1,36,.0025,0.0,
.002462,.000434,
.002349,.000855,
.002165,.00125,
.001915,.001607,
.001607,.001915,
.00125,.002165,
.000855,.002349,
.000434,.002462,
0.0,.0025,
-.000434,.002462,
-.000855,.002349,
-.00125,.002165,
-.001607,.001915,
-.001915,.001607,
-.002165,.00125,
-.002349,.000855,
-.002462,.000434,
-.0025,0.0,
-.002462,-.000434,
-.002349,-.000855,
-.002165,-.00125,
-.001915,-.001607,
-.001607,-.001915,
-.00125,-.002165,
-.000855,-.002349,
-.000434,-.002462,
0.0,-.0025,
.000434,-.002462,
.000855,-.002349,
.00125,-.002165,
.001607,-.001915,
.001915,-.001607,
.002165,-.00125,
.002349,-.000855,
.002462,-.000434,
.0025,0.0,
225.*
%
%ADD17MACRO17*%
%AMMACRO10*
4,1,36,.0025,0.0,
.002462,.000434,
.002349,.000855,
.002165,.00125,
.001915,.001607,
.001607,.001915,
.00125,.002165,
.000855,.002349,
.000434,.002462,
0.0,.0025,
-.000434,.002462,
-.000855,.002349,
-.00125,.002165,
-.001607,.001915,
-.001915,.001607,
-.002165,.00125,
-.002349,.000855,
-.002462,.000434,
-.0025,0.0,
-.002462,-.000434,
-.002349,-.000855,
-.002165,-.00125,
-.001915,-.001607,
-.001607,-.001915,
-.00125,-.002165,
-.000855,-.002349,
-.000434,-.002462,
0.0,-.0025,
.000434,-.002462,
.000855,-.002349,
.00125,-.002165,
.001607,-.001915,
.001915,-.001607,
.002165,-.00125,
.002349,-.000855,
.002462,-.000434,
.0025,0.0,
270.*
%
%ADD10MACRO10*%
%AMMACRO82*
4,1,36,.003,0.0,
.002954,.000521,
.002819,.001026,
.002598,.0015,
.002298,.001928,
.001928,.002298,
.0015,.002598,
.001026,.002819,
.000521,.002954,
0.0,.003,
-.000521,.002954,
-.001026,.002819,
-.0015,.002598,
-.001928,.002298,
-.002298,.001928,
-.002598,.0015,
-.002819,.001026,
-.002954,.000521,
-.003,0.0,
-.002954,-.000521,
-.002819,-.001026,
-.002598,-.0015,
-.002298,-.001928,
-.001928,-.002298,
-.0015,-.002598,
-.001026,-.002819,
-.000521,-.002954,
0.0,-.003,
.000521,-.002954,
.001026,-.002819,
.0015,-.002598,
.001928,-.002298,
.002298,-.001928,
.002598,-.0015,
.002819,-.001026,
.002954,-.000521,
.003,0.0,
270.*
%
%ADD82MACRO82*%
%AMMACRO44*
4,1,36,-.0025,0.0,
-.002462,.000434,
-.002349,.000855,
-.002165,.00125,
-.001915,.001607,
-.001607,.001915,
-.00125,.002165,
-.000855,.002349,
-.000434,.002462,
0.0,.0025,
.000434,.002462,
.000855,.002349,
.00125,.002165,
.001607,.001915,
.001915,.001607,
.002165,.00125,
.002349,.000855,
.002462,.000434,
.0025,0.0,
.002462,-.000434,
.002349,-.000855,
.002165,-.00125,
.001915,-.001607,
.001607,-.001915,
.00125,-.002165,
.000855,-.002349,
.000434,-.002462,
0.0,-.0025,
-.000434,-.002462,
-.000855,-.002349,
-.00125,-.002165,
-.001607,-.001915,
-.001915,-.001607,
-.002165,-.00125,
-.002349,-.000855,
-.002462,-.000434,
-.0025,0.0,
180.*
%
%ADD44MACRO44*%
%AMMACRO32*
4,1,36,.003,0.0,
.002954,.000521,
.002819,.001026,
.002598,.0015,
.002298,.001928,
.001928,.002298,
.0015,.002598,
.001026,.002819,
.000521,.002954,
0.0,.003,
-.000521,.002954,
-.001026,.002819,
-.0015,.002598,
-.001928,.002298,
-.002298,.001928,
-.002598,.0015,
-.002819,.001026,
-.002954,.000521,
-.003,0.0,
-.002954,-.000521,
-.002819,-.001026,
-.002598,-.0015,
-.002298,-.001928,
-.001928,-.002298,
-.0015,-.002598,
-.001026,-.002819,
-.000521,-.002954,
0.0,-.003,
.000521,-.002954,
.001026,-.002819,
.0015,-.002598,
.001928,-.002298,
.002298,-.001928,
.002598,-.0015,
.002819,-.001026,
.002954,-.000521,
.003,0.0,
180.*
%
%ADD32MACRO32*%
%ADD22C,.074*%
%ADD20C,.0263*%
%AMMACRO81*
4,1,36,-.003,0.0,
-.002954,.000521,
-.002819,.001026,
-.002598,.0015,
-.002298,.001928,
-.001928,.002298,
-.0015,.002598,
-.001026,.002819,
-.000521,.002954,
0.0,.003,
.000521,.002954,
.001026,.002819,
.0015,.002598,
.001928,.002298,
.002298,.001928,
.002598,.0015,
.002819,.001026,
.002954,.000521,
.003,0.0,
.002954,-.000521,
.002819,-.001026,
.002598,-.0015,
.002298,-.001928,
.001928,-.002298,
.0015,-.002598,
.001026,-.002819,
.000521,-.002954,
0.0,-.003,
-.000521,-.002954,
-.001026,-.002819,
-.0015,-.002598,
-.001928,-.002298,
-.002298,-.001928,
-.002598,-.0015,
-.002819,-.001026,
-.002954,-.000521,
-.003,0.0,
270.*
%
%ADD81MACRO81*%
%ADD80C,.0435*%
%ADD67C,.075*%
%ADD62C,.06015*%
%ADD48C,.066*%
%ADD51C,.076*%
%ADD50C,.095*%
%ADD34C,.03047*%
%ADD31C,.0248*%
%ADD74C,.087*%
%ADD35C,.03417*%
%AMMACRO13*
4,1,18,.09673,.06845,
.107147,.050613,
.114308,.031238,
.117996,.010914,
.118098,-.009741,
.114613,-.030101,
.107644,-.049546,
.097406,-.067485,
.09673,-.06845,
.10175,-.07347,
.112962,-.054685,
.120742,-.034239,
.124853,-.012752,
.125171,.009122,
.121685,.030719,
.114502,.051383,
.10384,.070486,
.10175,.07347,
.09673,.06845,
0.0*
4,1,18,.06845,-.09673,
.050613,-.107147,
.031238,-.114308,
.010914,-.117996,
-.009741,-.118098,
-.030101,-.114613,
-.049546,-.107644,
-.067485,-.097406,
-.06845,-.09673,
-.07347,-.10175,
-.054685,-.112962,
-.034239,-.120742,
-.012752,-.124853,
.009122,-.125171,
.030719,-.121685,
.051383,-.114502,
.070486,-.10384,
.07347,-.10175,
.06845,-.09673,
0.0*
4,1,18,-.09673,-.06845,
-.107147,-.050613,
-.114308,-.031238,
-.117996,-.010914,
-.118098,.009741,
-.114613,.030101,
-.107644,.049546,
-.097406,.067485,
-.09673,.06845,
-.10175,.07347,
-.112962,.054685,
-.120742,.034239,
-.124853,.012752,
-.125171,-.009122,
-.121685,-.030719,
-.114502,-.051383,
-.10384,-.070486,
-.10175,-.07347,
-.09673,-.06845,
0.0*
4,1,18,-.06845,.09673,
-.050613,.107147,
-.031238,.114308,
-.010914,.117996,
.009741,.118098,
.030101,.114613,
.049546,.107644,
.067485,.097406,
.06845,.09673,
.07347,.10175,
.054685,.112962,
.034239,.120742,
.012752,.124853,
-.009122,.125171,
-.030719,.121685,
-.051383,.114502,
-.070486,.10384,
-.07347,.10175,
-.06845,.09673,
0.0*
%
%ADD13MACRO13*%
%AMMACRO37*
4,1,16,.0711,.04282,
.077455,.029823,
.081457,.01592,
.082984,.001533,
.08199,-.0129,
.078504,-.026942,
.072633,-.040164,
.0711,-.04282,
.07619,-.04791,
.083352,-.033952,
.087981,-.018962,
.089937,-.003396,
.089161,.012273,
.085675,.027569,
.079586,.042027,
.07619,.04791,
.0711,.04282,
0.0*
4,1,16,.04282,-.0711,
.029823,-.077455,
.01592,-.081457,
.001533,-.082984,
-.0129,-.08199,
-.026942,-.078504,
-.040164,-.072633,
-.04282,-.0711,
-.04791,-.07619,
-.033952,-.083352,
-.018962,-.087981,
-.003396,-.089937,
.012273,-.089161,
.027569,-.085675,
.042027,-.079586,
.04791,-.07619,
.04282,-.0711,
0.0*
4,1,16,-.0711,-.04282,
-.077455,-.029823,
-.081457,-.01592,
-.082984,-.001533,
-.08199,.0129,
-.078504,.026942,
-.072633,.040164,
-.0711,.04282,
-.07619,.04791,
-.083352,.033952,
-.087981,.018962,
-.089937,.003396,
-.089161,-.012273,
-.085675,-.027569,
-.079586,-.042027,
-.07619,-.04791,
-.0711,-.04282,
0.0*
4,1,16,-.04282,.0711,
-.029823,.077455,
-.01592,.081457,
-.001533,.082984,
.0129,.08199,
.026942,.078504,
.040164,.072633,
.04282,.0711,
.04791,.07619,
.033952,.083352,
.018962,.087981,
.003396,.089937,
-.012273,.089161,
-.027569,.085675,
-.042027,.079586,
-.04791,.07619,
-.04282,.0711,
0.0*
%
%ADD37MACRO37*%
%AMMACRO65*
4,1,16,.02584,.01524,
.028094,.010521,
.029494,.005483,
.029998,.000278,
.029591,-.004935,
.028284,-.009999,
.026118,-.014758,
.02584,-.01524,
.03092,-.02032,
.033979,-.014642,
.036005,-.008519,
.036938,-.002138,
.036748,.004309,
.035441,.010625,
.033058,.016618,
.03092,.02032,
.02584,.01524,
90.*
4,1,16,.01524,-.02584,
.010521,-.028094,
.005483,-.029494,
.000278,-.029998,
-.004935,-.029591,
-.009999,-.028284,
-.014758,-.026118,
-.01524,-.02584,
-.02032,-.03092,
-.014642,-.033979,
-.008519,-.036005,
-.002138,-.036938,
.004309,-.036748,
.010625,-.035441,
.016618,-.033058,
.02032,-.03092,
.01524,-.02584,
90.*
4,1,16,-.02584,-.01524,
-.028094,-.010521,
-.029494,-.005483,
-.029998,-.000278,
-.029591,.004935,
-.028284,.009999,
-.026118,.014758,
-.02584,.01524,
-.03092,.02032,
-.033979,.014642,
-.036005,.008519,
-.036938,.002138,
-.036748,-.004309,
-.035441,-.010625,
-.033058,-.016618,
-.03092,-.02032,
-.02584,-.01524,
90.*
4,1,16,-.01524,.02584,
-.010521,.028094,
-.005483,.029494,
-.000278,.029998,
.004935,.029591,
.009999,.028284,
.014758,.026118,
.01524,.02584,
.02032,.03092,
.014642,.033979,
.008519,.036005,
.002138,.036938,
-.004309,.036748,
-.010625,.035441,
-.016618,.033058,
-.02032,.03092,
-.01524,.02584,
90.*
%
%ADD65MACRO65*%
%AMMACRO47*
4,1,15,.02438,.01377,
.026401,.009327,
.027619,.004601,
.027999,-.000265,
.027527,-.005123,
.02622,-.009825,
.02438,-.01377,
.02948,-.01887,
.032309,-.013464,
.034156,-.007649,
.034965,-.001602,
.034712,.004494,
.033405,.010454,
.031082,.016095,
.02948,.01887,
.02438,.01377,
90.*
4,1,15,.01377,-.02438,
.009327,-.026401,
.004601,-.027619,
-.000265,-.027999,
-.005123,-.027527,
-.009825,-.02622,
-.01377,-.02438,
-.01887,-.02948,
-.013464,-.032309,
-.007649,-.034156,
-.001602,-.034965,
.004494,-.034712,
.010454,-.033405,
.016095,-.031082,
.01887,-.02948,
.01377,-.02438,
90.*
4,1,15,-.02438,-.01377,
-.026401,-.009327,
-.027619,-.004601,
-.027999,.000265,
-.027527,.005123,
-.02622,.009825,
-.02438,.01377,
-.02948,.01887,
-.032309,.013464,
-.034156,.007649,
-.034965,.001602,
-.034712,-.004494,
-.033405,-.010454,
-.031082,-.016095,
-.02948,-.01887,
-.02438,-.01377,
90.*
4,1,15,-.01377,.02438,
-.009327,.026401,
-.004601,.027619,
.000265,.027999,
.005123,.027527,
.009825,.02622,
.01377,.02438,
.01887,.02948,
.013464,.032309,
.007649,.034156,
.001602,.034965,
-.004494,.034712,
-.010454,.033405,
-.016095,.031082,
-.01887,.02948,
-.01377,.02438,
90.*
%
%ADD47MACRO47*%
%AMMACRO16*
4,1,16,.07001,.04172,
.076191,.028929,
.080057,.015259,
.08149,.001126,
.080448,-.013042,
.076961,-.026814,
.071136,-.03977,
.07001,-.04172,
.0751,-.04682,
.082089,-.033068,
.086584,-.018311,
.088449,-.002997,
.087625,.012407,
.08414,.027435,
.078097,.041629,
.0751,.04682,
.07001,.04172,
0.0*
4,1,16,.04172,-.07001,
.028929,-.076191,
.015259,-.080057,
.001126,-.08149,
-.013042,-.080448,
-.026814,-.076961,
-.03977,-.071136,
-.04172,-.07001,
-.04682,-.0751,
-.033068,-.082089,
-.018311,-.086584,
-.002997,-.088449,
.012407,-.087625,
.027435,-.08414,
.041629,-.078097,
.04682,-.0751,
.04172,-.07001,
0.0*
4,1,16,-.07001,-.04172,
-.076191,-.028929,
-.080057,-.015259,
-.08149,-.001126,
-.080448,.013042,
-.076961,.026814,
-.071136,.03977,
-.07001,.04172,
-.0751,.04682,
-.082089,.033068,
-.086584,.018311,
-.088449,.002997,
-.087625,-.012407,
-.08414,-.027435,
-.078097,-.041629,
-.0751,-.04682,
-.07001,-.04172,
0.0*
4,1,16,-.04172,.07001,
-.028929,.076191,
-.015259,.080057,
-.001126,.08149,
.013042,.080448,
.026814,.076961,
.03977,.071136,
.04172,.07001,
.04682,.0751,
.033068,.082089,
.018311,.086584,
.002997,.088449,
-.012407,.087625,
-.027435,.08414,
-.041629,.078097,
-.04682,.0751,
-.04172,.07001,
0.0*
%
%ADD16MACRO16*%
%AMMACRO66*
4,1,15,.02142,.01082,
.022973,.006936,
.023829,.002841,
.02396,-.00134,
.023364,-.00548,
.022057,-.009454,
.02142,-.01082,
.02657,-.01597,
.02894,-.011114,
.03043,-.005919,
.030995,-.000545,
.030619,.004845,
.029313,.010088,
.027115,.015025,
.02657,.01597,
.02142,.01082,
0.0*
4,1,15,.01082,-.02142,
.006936,-.022973,
.002841,-.023829,
-.00134,-.02396,
-.00548,-.023364,
-.009454,-.022057,
-.01082,-.02142,
-.01597,-.02657,
-.011114,-.02894,
-.005919,-.03043,
-.000545,-.030995,
.004845,-.030619,
.010088,-.029313,
.015025,-.027115,
.01597,-.02657,
.01082,-.02142,
0.0*
4,1,15,-.02142,-.01082,
-.022973,-.006936,
-.023829,-.002841,
-.02396,.00134,
-.023364,.00548,
-.022057,.009454,
-.02142,.01082,
-.02657,.01597,
-.02894,.011114,
-.03043,.005919,
-.030995,.000545,
-.030619,-.004845,
-.029313,-.010088,
-.027115,-.015025,
-.02657,-.01597,
-.02142,-.01082,
0.0*
4,1,15,-.01082,.02142,
-.006936,.022973,
-.002841,.023829,
.00134,.02396,
.00548,.023364,
.009454,.022057,
.01082,.02142,
.01597,.02657,
.011114,.02894,
.005919,.03043,
.000545,.030995,
-.004845,.030619,
-.010088,.029313,
-.015025,.027115,
-.01597,.02657,
-.01082,.02142,
0.0*
%
%ADD66MACRO66*%
%AMMACRO52*
4,1,15,.02475,.01414,
.026829,.009627,
.028094,.004822,
.028504,-.000129,
.028049,-.005077,
.026741,-.009871,
.02475,-.01414,
.02984,-.01923,
.032726,-.013756,
.034617,-.007864,
.035457,-.001734,
.03522,.00445,
.033912,.010498,
.031574,.016227,
.02984,.01923,
.02475,.01414,
0.0*
4,1,15,.01414,-.02475,
.009627,-.026829,
.004822,-.028094,
-.000129,-.028504,
-.005077,-.028049,
-.009871,-.026741,
-.01414,-.02475,
-.01923,-.02984,
-.013756,-.032726,
-.007864,-.034617,
-.001734,-.035457,
.00445,-.03522,
.010498,-.033912,
.016227,-.031574,
.01923,-.02984,
.01414,-.02475,
0.0*
4,1,15,-.02475,-.01414,
-.026829,-.009627,
-.028094,-.004822,
-.028504,.000129,
-.028049,.005077,
-.026741,.009871,
-.02475,.01414,
-.02984,.01923,
-.032726,.013756,
-.034617,.007864,
-.035457,.001734,
-.03522,-.00445,
-.033912,-.010498,
-.031574,-.016227,
-.02984,-.01923,
-.02475,-.01414,
0.0*
4,1,15,-.01414,.02475,
-.009627,.026829,
-.004822,.028094,
.000129,.028504,
.005077,.028049,
.009871,.026741,
.01414,.02475,
.01923,.02984,
.013756,.032726,
.007864,.034617,
.001734,.035457,
-.00445,.03522,
-.010498,.033912,
-.016227,.031574,
-.01923,.02984,
-.01414,.02475,
0.0*
%
%ADD52MACRO52*%
%AMMACRO77*
4,1,15,.03682,.01914,
.039584,.012455,
.041146,.005393,
.041457,-.001834,
.040509,-.009005,
.03833,-.015903,
.03682,-.01914,
.04197,-.0243,
.045552,-.016643,
.04775,-.00848,
.048497,-.000059,
.047771,.008363,
.045593,.016531,
.042029,.024197,
.04197,.0243,
.03682,.01914,
0.0*
4,1,15,.01914,-.03682,
.012455,-.039584,
.005393,-.041146,
-.001834,-.041457,
-.009005,-.040509,
-.015903,-.03833,
-.01914,-.03682,
-.0243,-.04197,
-.016643,-.045552,
-.00848,-.04775,
-.000059,-.048497,
.008363,-.047771,
.016531,-.045593,
.024197,-.042029,
.0243,-.04197,
.01914,-.03682,
0.0*
4,1,15,-.03682,-.01914,
-.039584,-.012455,
-.041146,-.005393,
-.041457,.001834,
-.040509,.009005,
-.03833,.015903,
-.03682,.01914,
-.04197,.0243,
-.045552,.016643,
-.04775,.00848,
-.048497,.000059,
-.047771,-.008363,
-.045593,-.016531,
-.042029,-.024197,
-.04197,-.0243,
-.03682,-.01914,
0.0*
4,1,15,-.01914,.03682,
-.012455,.039584,
-.005393,.041146,
.001834,.041457,
.009005,.040509,
.015903,.03833,
.01914,.03682,
.0243,.04197,
.016643,.045552,
.00848,.04775,
.000059,.048497,
-.008363,.047771,
-.016531,.045593,
-.024197,.042029,
-.0243,.04197,
-.01914,.03682,
0.0*
%
%ADD77MACRO77*%
%AMMACRO73*
4,1,36,.0025,0.0,
.002462,.000434,
.002349,.000855,
.002165,.00125,
.001915,.001607,
.001607,.001915,
.00125,.002165,
.000855,.002349,
.000434,.002462,
0.0,.0025,
-.000434,.002462,
-.000855,.002349,
-.00125,.002165,
-.001607,.001915,
-.001915,.001607,
-.002165,.00125,
-.002349,.000855,
-.002462,.000434,
-.0025,0.0,
-.002462,-.000434,
-.002349,-.000855,
-.002165,-.00125,
-.001915,-.001607,
-.001607,-.001915,
-.00125,-.002165,
-.000855,-.002349,
-.000434,-.002462,
0.0,-.0025,
.000434,-.002462,
.000855,-.002349,
.00125,-.002165,
.001607,-.001915,
.001915,-.001607,
.002165,-.00125,
.002349,-.000855,
.002462,-.000434,
.0025,0.0,
134.996*
%
%ADD73MACRO73*%
%AMMACRO75*
4,1,15,-.03682,.01914,
-.039584,.012455,
-.041146,.005393,
-.041457,-.001834,
-.040509,-.009005,
-.03833,-.015903,
-.03682,-.01914,
-.04197,-.0243,
-.045552,-.016643,
-.04775,-.00848,
-.048497,-.000059,
-.047771,.008363,
-.045593,.016531,
-.042029,.024197,
-.04197,.0243,
-.03682,.01914,
0.0*
4,1,15,-.01914,-.03682,
-.012455,-.039584,
-.005393,-.041146,
.001834,-.041457,
.009005,-.040509,
.015903,-.03833,
.01914,-.03682,
.0243,-.04197,
.016643,-.045552,
.00848,-.04775,
.000059,-.048497,
-.008363,-.047771,
-.016531,-.045593,
-.024197,-.042029,
-.0243,-.04197,
-.01914,-.03682,
0.0*
4,1,15,.03682,-.01914,
.039584,-.012455,
.041146,-.005393,
.041457,.001834,
.040509,.009005,
.03833,.015903,
.03682,.01914,
.04197,.0243,
.045552,.016643,
.04775,.00848,
.048497,.000059,
.047771,-.008363,
.045593,-.016531,
.042029,-.024197,
.04197,-.0243,
.03682,-.01914,
0.0*
4,1,15,.01914,.03682,
.012455,.039584,
.005393,.041146,
-.001834,.041457,
-.009005,.040509,
-.015903,.03833,
-.01914,.03682,
-.0243,.04197,
-.016643,.045552,
-.00848,.04775,
-.000059,.048497,
.008363,.047771,
.016531,.045593,
.024197,.042029,
.0243,.04197,
.01914,.03682,
0.0*
%
%ADD75MACRO75*%
%AMMACRO39*
4,1,36,.003,0.0,
.002954,.000521,
.002819,.001026,
.002598,.0015,
.002298,.001928,
.001928,.002298,
.0015,.002598,
.001026,.002819,
.000521,.002954,
0.0,.003,
-.000521,.002954,
-.001026,.002819,
-.0015,.002598,
-.001928,.002298,
-.002298,.001928,
-.002598,.0015,
-.002819,.001026,
-.002954,.000521,
-.003,0.0,
-.002954,-.000521,
-.002819,-.001026,
-.002598,-.0015,
-.002298,-.001928,
-.001928,-.002298,
-.0015,-.002598,
-.001026,-.002819,
-.000521,-.002954,
0.0,-.003,
.000521,-.002954,
.001026,-.002819,
.0015,-.002598,
.001928,-.002298,
.002298,-.001928,
.002598,-.0015,
.002819,-.001026,
.002954,-.000521,
.003,0.0,
179.996*
%
%ADD39MACRO39*%
%ADD60O,.285X.23*%
%ADD72C,.142*%
%AMMACRO61*
4,1,36,0.0,.01,
-.001736,.009848,
-.00342,.009397,
-.005,.00866,
-.006428,.00766,
-.00766,.006428,
-.00866,.005,
-.009397,.00342,
-.009848,.001736,
-.01,0.0,
-.009848,-.001736,
-.009397,-.00342,
-.00866,-.005,
-.00766,-.006428,
-.006428,-.00766,
-.005,-.00866,
-.00342,-.009397,
-.001736,-.009848,
0.0,-.01,
.001736,-.009848,
.00342,-.009397,
.005,-.00866,
.006428,-.00766,
.00766,-.006428,
.00866,-.005,
.009397,-.00342,
.009848,-.001736,
.01,0.0,
.009848,.001736,
.009397,.00342,
.00866,.005,
.00766,.006428,
.006428,.00766,
.005,.00866,
.00342,.009397,
.001736,.009848,
0.0,.01,
180.*
%
%ADD61MACRO61*%
%ADD36O,.219X.156*%
%ADD11C,.125*%
%ADD27C,.424*%
%ADD18C,.155*%
%ADD53C,.291*%
%ADD55C,.247*%
%ADD46C,.256*%
%AMMACRO33*
4,1,36,0.0,.0085,
.001476,.008371,
.002907,.007987,
.00425,.007361,
.005464,.006511,
.006511,.005464,
.007361,.00425,
.007987,.002907,
.008371,.001476,
.0085,0.0,
.008371,-.001476,
.007987,-.002907,
.007361,-.00425,
.006511,-.005464,
.005464,-.006511,
.00425,-.007361,
.002907,-.007987,
.001476,-.008371,
0.0,-.0085,
-.001476,-.008371,
-.002907,-.007987,
-.00425,-.007361,
-.005464,-.006511,
-.006511,-.005464,
-.007361,-.00425,
-.007987,-.002907,
-.008371,-.001476,
-.0085,0.0,
-.008371,.001476,
-.007987,.002907,
-.007361,.00425,
-.006511,.005464,
-.005464,.006511,
-.00425,.007361,
-.002907,.007987,
-.001476,.008371,
0.0,.0085,
180.*
%
%ADD33MACRO33*%
%AMMACRO59*
4,1,20,-.0075,-.05555,
-.0075,-.06273,
-.013677,-.060878,
-.019439,-.057981,
-.024611,-.054127,
-.029034,-.049434,
-.032576,-.044045,
-.035127,-.038122,
-.036612,-.031846,
-.037,-.0265,
-.037,-.0075,
-.03,-.0075,
-.03,-.0265,
-.029544,-.03171,
-.028191,-.036762,
-.02598,-.041502,
-.022981,-.045786,
-.019282,-.049484,
-.014998,-.052484,
-.010258,-.054694,
-.0075,-.05555,
90.*
4,1,20,.0075,-.06273,
.0075,-.05555,
.01243,-.053806,
.016983,-.051232,
.02102,-.047906,
.024418,-.043931,
.027073,-.039425,
.028906,-.034527,
.029861,-.029385,
.03,-.0265,
.03,-.0075,
.037,-.0075,
.037,-.0265,
.036438,-.032925,
.034769,-.039154,
.032043,-.044999,
.028344,-.050282,
.023784,-.054842,
.018501,-.058541,
.012656,-.061266,
.0075,-.06273,
90.*
4,1,20,-.0075,.06273,
-.0075,.05555,
-.01243,.053806,
-.016983,.051232,
-.02102,.047906,
-.024418,.043931,
-.027073,.039425,
-.028906,.034527,
-.029861,.029385,
-.03,.0265,
-.03,.0075,
-.037,.0075,
-.037,.0265,
-.036438,.032925,
-.034769,.039154,
-.032043,.044999,
-.028344,.050282,
-.023784,.054842,
-.018501,.058541,
-.012656,.061266,
-.0075,.06273,
90.*
4,1,20,.0075,.05555,
.0075,.06273,
.013677,.060878,
.019439,.057981,
.024611,.054127,
.029034,.049434,
.032576,.044045,
.035127,.038122,
.036612,.031846,
.037,.0265,
.037,.0075,
.03,.0075,
.03,.0265,
.029544,.03171,
.028191,.036762,
.02598,.041502,
.022981,.045786,
.019282,.049484,
.014998,.052484,
.010258,.054694,
.0075,.05555,
90.*
%
%ADD59MACRO59*%
%AMMACRO15*
4,1,36,.0025,0.0,
.002462,.000434,
.002349,.000855,
.002165,.00125,
.001915,.001607,
.001607,.001915,
.00125,.002165,
.000855,.002349,
.000434,.002462,
0.0,.0025,
-.000434,.002462,
-.000855,.002349,
-.00125,.002165,
-.001607,.001915,
-.001915,.001607,
-.002165,.00125,
-.002349,.000855,
-.002462,.000434,
-.0025,0.0,
-.002462,-.000434,
-.002349,-.000855,
-.002165,-.00125,
-.001915,-.001607,
-.001607,-.001915,
-.00125,-.002165,
-.000855,-.002349,
-.000434,-.002462,
0.0,-.0025,
.000434,-.002462,
.000855,-.002349,
.00125,-.002165,
.001607,-.001915,
.001915,-.001607,
.002165,-.00125,
.002349,-.000855,
.002462,-.000434,
.0025,0.0,
90.*
%
%ADD15MACRO15*%
%AMMACRO56*
4,1,36,0.0,.019,
-.003299,.018711,
-.006498,.017854,
-.0095,.016454,
-.012213,.014555,
-.014555,.012213,
-.016454,.0095,
-.017854,.006498,
-.018711,.003299,
-.019,0.0,
-.018711,-.003299,
-.017854,-.006498,
-.016454,-.0095,
-.014555,-.012213,
-.012213,-.014555,
-.0095,-.016454,
-.006498,-.017854,
-.003299,-.018711,
0.0,-.019,
.003299,-.018711,
.006498,-.017854,
.0095,-.016454,
.012213,-.014555,
.014555,-.012213,
.016454,-.0095,
.017854,-.006498,
.018711,-.003299,
.019,0.0,
.018711,.003299,
.017854,.006498,
.016454,.0095,
.014555,.012213,
.012213,.014555,
.0095,.016454,
.006498,.017854,
.003299,.018711,
0.0,.019,
270.*
%
%ADD56MACRO56*%
%AMMACRO40*
4,1,36,.003,0.0,
.002954,.000521,
.002819,.001026,
.002598,.0015,
.002298,.001928,
.001928,.002298,
.0015,.002598,
.001026,.002819,
.000521,.002954,
0.0,.003,
-.000521,.002954,
-.001026,.002819,
-.0015,.002598,
-.001928,.002298,
-.002298,.001928,
-.002598,.0015,
-.002819,.001026,
-.002954,.000521,
-.003,0.0,
-.002954,-.000521,
-.002819,-.001026,
-.002598,-.0015,
-.002298,-.001928,
-.001928,-.002298,
-.0015,-.002598,
-.001026,-.002819,
-.000521,-.002954,
0.0,-.003,
.000521,-.002954,
.001026,-.002819,
.0015,-.002598,
.001928,-.002298,
.002298,-.001928,
.002598,-.0015,
.002819,-.001026,
.002954,-.000521,
.003,0.0,
90.*
%
%ADD40MACRO40*%
%AMMACRO12*
4,1,36,.0025,0.0,
.002462,.000434,
.002349,.000855,
.002165,.00125,
.001915,.001607,
.001607,.001915,
.00125,.002165,
.000855,.002349,
.000434,.002462,
0.0,.0025,
-.000434,.002462,
-.000855,.002349,
-.00125,.002165,
-.001607,.001915,
-.001915,.001607,
-.002165,.00125,
-.002349,.000855,
-.002462,.000434,
-.0025,0.0,
-.002462,-.000434,
-.002349,-.000855,
-.002165,-.00125,
-.001915,-.001607,
-.001607,-.001915,
-.00125,-.002165,
-.000855,-.002349,
-.000434,-.002462,
0.0,-.0025,
.000434,-.002462,
.000855,-.002349,
.00125,-.002165,
.001607,-.001915,
.001915,-.001607,
.002165,-.00125,
.002349,-.000855,
.002462,-.000434,
.0025,0.0,
0.0*
%
%ADD12MACRO12*%
%AMMACRO79*
4,1,36,-.003,0.0,
-.002954,.000521,
-.002819,.001026,
-.002598,.0015,
-.002298,.001928,
-.001928,.002298,
-.0015,.002598,
-.001026,.002819,
-.000521,.002954,
0.0,.003,
.000521,.002954,
.001026,.002819,
.0015,.002598,
.001928,.002298,
.002298,.001928,
.002598,.0015,
.002819,.001026,
.002954,.000521,
.003,0.0,
.002954,-.000521,
.002819,-.001026,
.002598,-.0015,
.002298,-.001928,
.001928,-.002298,
.0015,-.002598,
.001026,-.002819,
.000521,-.002954,
0.0,-.003,
-.000521,-.002954,
-.001026,-.002819,
-.0015,-.002598,
-.001928,-.002298,
-.002298,-.001928,
-.002598,-.0015,
-.002819,-.001026,
-.002954,-.000521,
-.003,0.0,
90.*
%
%ADD79MACRO79*%
%AMMACRO45*
4,1,36,-.0025,0.0,
-.002462,.000434,
-.002349,.000855,
-.002165,.00125,
-.001915,.001607,
-.001607,.001915,
-.00125,.002165,
-.000855,.002349,
-.000434,.002462,
0.0,.0025,
.000434,.002462,
.000855,.002349,
.00125,.002165,
.001607,.001915,
.001915,.001607,
.002165,.00125,
.002349,.000855,
.002462,.000434,
.0025,0.0,
.002462,-.000434,
.002349,-.000855,
.002165,-.00125,
.001915,-.001607,
.001607,-.001915,
.00125,-.002165,
.000855,-.002349,
.000434,-.002462,
0.0,-.0025,
-.000434,-.002462,
-.000855,-.002349,
-.00125,-.002165,
-.001607,-.001915,
-.001915,-.001607,
-.002165,-.00125,
-.002349,-.000855,
-.002462,-.000434,
-.0025,0.0,
0.0*
%
%ADD45MACRO45*%
%ADD38C,.188*%
%AMMACRO29*
4,1,36,.003,0.0,
.002954,.000521,
.002819,.001026,
.002598,.0015,
.002298,.001928,
.001928,.002298,
.0015,.002598,
.001026,.002819,
.000521,.002954,
0.0,.003,
-.000521,.002954,
-.001026,.002819,
-.0015,.002598,
-.001928,.002298,
-.002298,.001928,
-.002598,.0015,
-.002819,.001026,
-.002954,.000521,
-.003,0.0,
-.002954,-.000521,
-.002819,-.001026,
-.002598,-.0015,
-.002298,-.001928,
-.001928,-.002298,
-.0015,-.002598,
-.001026,-.002819,
-.000521,-.002954,
0.0,-.003,
.000521,-.002954,
.001026,-.002819,
.0015,-.002598,
.001928,-.002298,
.002298,-.001928,
.002598,-.0015,
.002819,-.001026,
.002954,-.000521,
.003,0.0,
0.0*
%
%ADD29MACRO29*%
%AMMACRO21*
4,1,16,.02584,.01524,
.028094,.010521,
.029494,.005483,
.029998,.000278,
.029591,-.004935,
.028284,-.009999,
.026118,-.014758,
.02584,-.01524,
.03092,-.02032,
.033979,-.014642,
.036005,-.008519,
.036938,-.002138,
.036748,.004309,
.035441,.010625,
.033058,.016618,
.03092,.02032,
.02584,.01524,
180.*
4,1,16,.01524,-.02584,
.010521,-.028094,
.005483,-.029494,
.000278,-.029998,
-.004935,-.029591,
-.009999,-.028284,
-.014758,-.026118,
-.01524,-.02584,
-.02032,-.03092,
-.014642,-.033979,
-.008519,-.036005,
-.002138,-.036938,
.004309,-.036748,
.010625,-.035441,
.016618,-.033058,
.02032,-.03092,
.01524,-.02584,
180.*
4,1,16,-.02584,-.01524,
-.028094,-.010521,
-.029494,-.005483,
-.029998,-.000278,
-.029591,.004935,
-.028284,.009999,
-.026118,.014758,
-.02584,.01524,
-.03092,.02032,
-.033979,.014642,
-.036005,.008519,
-.036938,.002138,
-.036748,-.004309,
-.035441,-.010625,
-.033058,-.016618,
-.03092,-.02032,
-.02584,-.01524,
180.*
4,1,16,-.01524,.02584,
-.010521,.028094,
-.005483,.029494,
-.000278,.029998,
.004935,.029591,
.009999,.028284,
.014758,.026118,
.01524,.02584,
.02032,.03092,
.014642,.033979,
.008519,.036005,
.002138,.036938,
-.004309,.036748,
-.010625,.035441,
-.016618,.033058,
-.02032,.03092,
-.01524,.02584,
180.*
%
%ADD21MACRO21*%
%AMMACRO63*
4,1,15,.02438,.01377,
.026401,.009327,
.027619,.004601,
.027999,-.000265,
.027527,-.005123,
.02622,-.009825,
.02438,-.01377,
.02948,-.01887,
.032309,-.013464,
.034156,-.007649,
.034965,-.001602,
.034712,.004494,
.033405,.010454,
.031082,.016095,
.02948,.01887,
.02438,.01377,
270.*
4,1,15,.01377,-.02438,
.009327,-.026401,
.004601,-.027619,
-.000265,-.027999,
-.005123,-.027527,
-.009825,-.02622,
-.01377,-.02438,
-.01887,-.02948,
-.013464,-.032309,
-.007649,-.034156,
-.001602,-.034965,
.004494,-.034712,
.010454,-.033405,
.016095,-.031082,
.01887,-.02948,
.01377,-.02438,
270.*
4,1,15,-.02438,-.01377,
-.026401,-.009327,
-.027619,-.004601,
-.027999,.000265,
-.027527,.005123,
-.02622,.009825,
-.02438,.01377,
-.02948,.01887,
-.032309,.013464,
-.034156,.007649,
-.034965,.001602,
-.034712,-.004494,
-.033405,-.010454,
-.031082,-.016095,
-.02948,-.01887,
-.02438,-.01377,
270.*
4,1,15,-.01377,.02438,
-.009327,.026401,
-.004601,.027619,
.000265,.027999,
.005123,.027527,
.009825,.02622,
.01377,.02438,
.01887,.02948,
.013464,.032309,
.007649,.034156,
.001602,.034965,
-.004494,.034712,
-.010454,.033405,
-.016095,.031082,
-.01887,.02948,
-.01377,.02438,
270.*
%
%ADD63MACRO63*%
%AMMACRO42*
4,1,15,.02438,.01377,
.026401,.009327,
.027619,.004601,
.027999,-.000265,
.027527,-.005123,
.02622,-.009825,
.02438,-.01377,
.02948,-.01887,
.032309,-.013464,
.034156,-.007649,
.034965,-.001602,
.034712,.004494,
.033405,.010454,
.031082,.016095,
.02948,.01887,
.02438,.01377,
180.*
4,1,15,.01377,-.02438,
.009327,-.026401,
.004601,-.027619,
-.000265,-.027999,
-.005123,-.027527,
-.009825,-.02622,
-.01377,-.02438,
-.01887,-.02948,
-.013464,-.032309,
-.007649,-.034156,
-.001602,-.034965,
.004494,-.034712,
.010454,-.033405,
.016095,-.031082,
.01887,-.02948,
.01377,-.02438,
180.*
4,1,15,-.02438,-.01377,
-.026401,-.009327,
-.027619,-.004601,
-.027999,.000265,
-.027527,.005123,
-.02622,.009825,
-.02438,.01377,
-.02948,.01887,
-.032309,.013464,
-.034156,.007649,
-.034965,.001602,
-.034712,-.004494,
-.033405,-.010454,
-.031082,-.016095,
-.02948,-.01887,
-.02438,-.01377,
180.*
4,1,15,-.01377,.02438,
-.009327,.026401,
-.004601,.027619,
.000265,.027999,
.005123,.027527,
.009825,.02622,
.01377,.02438,
.01887,.02948,
.013464,.032309,
.007649,.034156,
.001602,.034965,
-.004494,.034712,
-.010454,.033405,
-.016095,.031082,
-.01887,.02948,
-.01377,.02438,
180.*
%
%ADD42MACRO42*%
%AMMACRO26*
4,1,20,-.039,.0245,
-.038408,.031272,
-.036648,.037838,
-.033775,.043999,
-.029876,.049567,
-.02507,.054374,
-.019501,.058273,
-.01334,.061146,
-.0075,.06277,
-.0075,.05561,
-.012788,.053835,
-.017688,.051168,
-.02205,.047691,
-.025742,.04351,
-.028652,.038751,
-.030691,.033558,
-.031798,.028091,
-.032,.0245,
-.032,.0075,
-.039,.0075,
-.039,.0245,
90.*
4,1,20,-.039,-.0075,
-.032,-.0075,
-.032,-.0245,
-.031514,-.030057,
-.03007,-.035445,
-.027713,-.040501,
-.024513,-.04507,
-.020569,-.049015,
-.015999,-.052214,
-.010944,-.054572,
-.0075,-.05561,
-.0075,-.06277,
-.014032,-.060887,
-.020137,-.057898,
-.025631,-.053894,
-.030345,-.048997,
-.034138,-.043356,
-.036894,-.037142,
-.038529,-.030544,
-.039,-.0245,
-.039,-.0075,
90.*
4,1,20,.0075,.06277,
.014032,.060887,
.020137,.057898,
.025631,.053894,
.030345,.048997,
.034138,.043356,
.036894,.037142,
.038529,.030544,
.039,.0245,
.039,.0075,
.032,.0075,
.032,.0245,
.031514,.030057,
.03007,.035445,
.027713,.040501,
.024513,.04507,
.020569,.049015,
.015999,.052214,
.010944,.054572,
.0075,.05561,
.0075,.06277,
90.*
4,1,20,.0075,-.05561,
.012788,-.053835,
.017688,-.051168,
.02205,-.047691,
.025742,-.04351,
.028652,-.038751,
.030691,-.033558,
.031798,-.028091,
.032,-.0245,
.032,-.0075,
.039,-.0075,
.039,-.0245,
.038408,-.031272,
.036648,-.037838,
.033775,-.043999,
.029876,-.049567,
.02507,-.054374,
.019501,-.058273,
.01334,-.061146,
.0075,-.06277,
.0075,-.05561,
90.*
%
%ADD26MACRO26*%
%AMMACRO71*
4,1,15,.02475,.01414,
.026829,.009627,
.028094,.004822,
.028504,-.000129,
.028049,-.005077,
.026741,-.009871,
.02475,-.01414,
.02984,-.01923,
.032726,-.013756,
.034617,-.007864,
.035457,-.001734,
.03522,.00445,
.033912,.010498,
.031574,.016227,
.02984,.01923,
.02475,.01414,
270.*
4,1,15,.01414,-.02475,
.009627,-.026829,
.004822,-.028094,
-.000129,-.028504,
-.005077,-.028049,
-.009871,-.026741,
-.01414,-.02475,
-.01923,-.02984,
-.013756,-.032726,
-.007864,-.034617,
-.001734,-.035457,
.00445,-.03522,
.010498,-.033912,
.016227,-.031574,
.01923,-.02984,
.01414,-.02475,
270.*
4,1,15,-.02475,-.01414,
-.026829,-.009627,
-.028094,-.004822,
-.028504,.000129,
-.028049,.005077,
-.026741,.009871,
-.02475,.01414,
-.02984,.01923,
-.032726,.013756,
-.034617,.007864,
-.035457,.001734,
-.03522,-.00445,
-.033912,-.010498,
-.031574,-.016227,
-.02984,-.01923,
-.02475,-.01414,
270.*
4,1,15,-.01414,.02475,
-.009627,.026829,
-.004822,.028094,
.000129,.028504,
.005077,.028049,
.009871,.026741,
.01414,.02475,
.01923,.02984,
.013756,.032726,
.007864,.034617,
.001734,.035457,
-.00445,.03522,
-.010498,.033912,
-.016227,.031574,
-.01923,.02984,
-.01414,.02475,
270.*
%
%ADD71MACRO71*%
%AMMACRO70*
4,1,15,.02142,.01082,
.022973,.006936,
.023829,.002841,
.02396,-.00134,
.023364,-.00548,
.022057,-.009454,
.02142,-.01082,
.02657,-.01597,
.02894,-.011114,
.03043,-.005919,
.030995,-.000545,
.030619,.004845,
.029313,.010088,
.027115,.015025,
.02657,.01597,
.02142,.01082,
180.*
4,1,15,.01082,-.02142,
.006936,-.022973,
.002841,-.023829,
-.00134,-.02396,
-.00548,-.023364,
-.009454,-.022057,
-.01082,-.02142,
-.01597,-.02657,
-.011114,-.02894,
-.005919,-.03043,
-.000545,-.030995,
.004845,-.030619,
.010088,-.029313,
.015025,-.027115,
.01597,-.02657,
.01082,-.02142,
180.*
4,1,15,-.02142,-.01082,
-.022973,-.006936,
-.023829,-.002841,
-.02396,.00134,
-.023364,.00548,
-.022057,.009454,
-.02142,.01082,
-.02657,.01597,
-.02894,.011114,
-.03043,.005919,
-.030995,.000545,
-.030619,-.004845,
-.029313,-.010088,
-.027115,-.015025,
-.02657,-.01597,
-.02142,-.01082,
180.*
4,1,15,-.01082,.02142,
-.006936,.022973,
-.002841,.023829,
.00134,.02396,
.00548,.023364,
.009454,.022057,
.01082,.02142,
.01597,.02657,
.011114,.02894,
.005919,.03043,
.000545,.030995,
-.004845,.030619,
-.010088,.029313,
-.015025,.027115,
-.01597,.02657,
-.01082,.02142,
180.*
%
%ADD70MACRO70*%
%AMMACRO69*
4,1,15,.02475,.01414,
.026829,.009627,
.028094,.004822,
.028504,-.000129,
.028049,-.005077,
.026741,-.009871,
.02475,-.01414,
.02984,-.01923,
.032726,-.013756,
.034617,-.007864,
.035457,-.001734,
.03522,.00445,
.033912,.010498,
.031574,.016227,
.02984,.01923,
.02475,.01414,
180.*
4,1,15,.01414,-.02475,
.009627,-.026829,
.004822,-.028094,
-.000129,-.028504,
-.005077,-.028049,
-.009871,-.026741,
-.01414,-.02475,
-.01923,-.02984,
-.013756,-.032726,
-.007864,-.034617,
-.001734,-.035457,
.00445,-.03522,
.010498,-.033912,
.016227,-.031574,
.01923,-.02984,
.01414,-.02475,
180.*
4,1,15,-.02475,-.01414,
-.026829,-.009627,
-.028094,-.004822,
-.028504,.000129,
-.028049,.005077,
-.026741,.009871,
-.02475,.01414,
-.02984,.01923,
-.032726,.013756,
-.034617,.007864,
-.035457,.001734,
-.03522,-.00445,
-.033912,-.010498,
-.031574,-.016227,
-.02984,-.01923,
-.02475,-.01414,
180.*
4,1,15,-.01414,.02475,
-.009627,.026829,
-.004822,.028094,
.000129,.028504,
.005077,.028049,
.009871,.026741,
.01414,.02475,
.01923,.02984,
.013756,.032726,
.007864,.034617,
.001734,.035457,
-.00445,.03522,
-.010498,.033912,
-.016227,.031574,
-.01923,.02984,
-.01414,.02475,
180.*
%
%ADD69MACRO69*%
%AMMACRO57*
4,1,18,.07103,.05689,
.07983,.043691,
.086204,.029165,
.089959,.013753,
.09098,-.002077,
.089237,-.017844,
.084783,-.033069,
.077753,-.047289,
.07103,-.05689,
.07601,-.06186,
.085597,-.047721,
.092583,-.032132,
.096757,-.015567,
.09799,.001471,
.096246,.018464,
.091577,.034897,
.084126,.050269,
.07601,.06186,
.07103,.05689,
270.*
4,1,18,.05689,-.07103,
.043691,-.07983,
.029165,-.086204,
.013753,-.089959,
-.002077,-.09098,
-.017844,-.089237,
-.033069,-.084783,
-.047289,-.077753,
-.05689,-.07103,
-.06186,-.07601,
-.047721,-.085597,
-.032132,-.092583,
-.015567,-.096757,
.001471,-.09799,
.018464,-.096246,
.034897,-.091577,
.050269,-.084126,
.06186,-.07601,
.05689,-.07103,
270.*
4,1,18,-.07103,-.05689,
-.07983,-.043691,
-.086204,-.029165,
-.089959,-.013753,
-.09098,.002077,
-.089237,.017844,
-.084783,.033069,
-.077753,.047289,
-.07103,.05689,
-.07601,.06186,
-.085597,.047721,
-.092583,.032132,
-.096757,.015567,
-.09799,-.001471,
-.096246,-.018464,
-.091577,-.034897,
-.084126,-.050269,
-.07601,-.06186,
-.07103,-.05689,
270.*
4,1,18,-.05689,.07103,
-.043691,.07983,
-.029165,.086204,
-.013753,.089959,
.002077,.09098,
.017844,.089237,
.033069,.084783,
.047289,.077753,
.05689,.07103,
.06186,.07601,
.047721,.085597,
.032132,.092583,
.015567,.096757,
-.001471,.09799,
-.018464,.096246,
-.034897,.091577,
-.050269,.084126,
-.06186,.07601,
-.05689,.07103,
270.*
%
%ADD57MACRO57*%
%AMMACRO49*
4,1,16,.02657,.01597,
.02894,.011114,
.03043,.005919,
.030995,.000545,
.030619,-.004845,
.029313,-.010088,
.027115,-.015025,
.02657,-.01597,
.03164,-.02104,
.034813,-.015226,
.036928,-.00895,
.037921,-.002401,
.037762,.00422,
.036455,.010713,
.034041,.016881,
.03164,.02104,
.02657,.01597,
180.*
4,1,16,.01597,-.02657,
.011114,-.02894,
.005919,-.03043,
.000545,-.030995,
-.004845,-.030619,
-.010088,-.029313,
-.015025,-.027115,
-.01597,-.02657,
-.02104,-.03164,
-.015226,-.034813,
-.00895,-.036928,
-.002401,-.037921,
.00422,-.037762,
.010713,-.036455,
.016881,-.034041,
.02104,-.03164,
.01597,-.02657,
180.*
4,1,16,-.02657,-.01597,
-.02894,-.011114,
-.03043,-.005919,
-.030995,-.000545,
-.030619,.004845,
-.029313,.010088,
-.027115,.015025,
-.02657,.01597,
-.03164,.02104,
-.034813,.015226,
-.036928,.00895,
-.037921,.002401,
-.037762,-.00422,
-.036455,-.010713,
-.034041,-.016881,
-.03164,-.02104,
-.02657,-.01597,
180.*
4,1,16,-.01597,.02657,
-.011114,.02894,
-.005919,.03043,
-.000545,.030995,
.004845,.030619,
.010088,.029313,
.015025,.027115,
.01597,.02657,
.02104,.03164,
.015226,.034813,
.00895,.036928,
.002401,.037921,
-.00422,.037762,
-.010713,.036455,
-.016881,.034041,
-.02104,.03164,
-.01597,.02657,
180.*
%
%ADD49MACRO49*%
%AMMACRO58*
4,1,15,.04124,.02356,
.044705,.016041,
.046811,.008034,
.047495,-.000216,
.046736,-.008461,
.044557,-.016448,
.04124,-.02356,
.04635,-.02867,
.050624,-.020186,
.05336,-.011088,
.054475,-.001654,
.053935,.007831,
.051756,.017077,
.048004,.025805,
.04635,.02867,
.04124,.02356,
0.0*
4,1,15,.02356,-.04124,
.016041,-.044705,
.008034,-.046811,
-.000216,-.047495,
-.008461,-.046736,
-.016448,-.044557,
-.02356,-.04124,
-.02867,-.04635,
-.020186,-.050624,
-.011088,-.05336,
-.001654,-.054475,
.007831,-.053935,
.017077,-.051756,
.025805,-.048004,
.02867,-.04635,
.02356,-.04124,
0.0*
4,1,15,-.04124,-.02356,
-.044705,-.016041,
-.046811,-.008034,
-.047495,.000216,
-.046736,.008461,
-.044557,.016448,
-.04124,.02356,
-.04635,.02867,
-.050624,.020186,
-.05336,.011088,
-.054475,.001654,
-.053935,-.007831,
-.051756,-.017077,
-.048004,-.025805,
-.04635,-.02867,
-.04124,-.02356,
0.0*
4,1,15,-.02356,.04124,
-.016041,.044705,
-.008034,.046811,
.000216,.047495,
.008461,.046736,
.016448,.044557,
.02356,.04124,
.02867,.04635,
.020186,.050624,
.011088,.05336,
.001654,.054475,
-.007831,.053935,
-.017077,.051756,
-.025805,.048004,
-.02867,.04635,
-.02356,.04124,
0.0*
%
%ADD58MACRO58*%
%AMMACRO78*
4,1,15,.03682,.01914,
.039584,.012455,
.041146,.005393,
.041457,-.001834,
.040509,-.009005,
.03833,-.015903,
.03682,-.01914,
.04197,-.0243,
.045552,-.016643,
.04775,-.00848,
.048497,-.000059,
.047771,.008363,
.045593,.016531,
.042029,.024197,
.04197,.0243,
.03682,.01914,
180.*
4,1,15,.01914,-.03682,
.012455,-.039584,
.005393,-.041146,
-.001834,-.041457,
-.009005,-.040509,
-.015903,-.03833,
-.01914,-.03682,
-.0243,-.04197,
-.016643,-.045552,
-.00848,-.04775,
-.000059,-.048497,
.008363,-.047771,
.016531,-.045593,
.024197,-.042029,
.0243,-.04197,
.01914,-.03682,
180.*
4,1,15,-.03682,-.01914,
-.039584,-.012455,
-.041146,-.005393,
-.041457,.001834,
-.040509,.009005,
-.03833,.015903,
-.03682,.01914,
-.04197,.0243,
-.045552,.016643,
-.04775,.00848,
-.048497,.000059,
-.047771,-.008363,
-.045593,-.016531,
-.042029,-.024197,
-.04197,-.0243,
-.03682,-.01914,
180.*
4,1,15,-.01914,.03682,
-.012455,.039584,
-.005393,.041146,
.001834,.041457,
.009005,.040509,
.015903,.03833,
.01914,.03682,
.0243,.04197,
.016643,.045552,
.00848,.04775,
.000059,.048497,
-.008363,.047771,
-.016531,.045593,
-.024197,.042029,
-.0243,.04197,
-.01914,.03682,
180.*
%
%ADD78MACRO78*%
%AMMACRO76*
4,1,15,-.03682,.01914,
-.039584,.012455,
-.041146,.005393,
-.041457,-.001834,
-.040509,-.009005,
-.03833,-.015903,
-.03682,-.01914,
-.04197,-.0243,
-.045552,-.016643,
-.04775,-.00848,
-.048497,-.000059,
-.047771,.008363,
-.045593,.016531,
-.042029,.024197,
-.04197,.0243,
-.03682,.01914,
180.*
4,1,15,-.01914,-.03682,
-.012455,-.039584,
-.005393,-.041146,
.001834,-.041457,
.009005,-.040509,
.015903,-.03833,
.01914,-.03682,
.0243,-.04197,
.016643,-.045552,
.00848,-.04775,
.000059,-.048497,
-.008363,-.047771,
-.016531,-.045593,
-.024197,-.042029,
-.0243,-.04197,
-.01914,-.03682,
180.*
4,1,15,.03682,-.01914,
.039584,-.012455,
.041146,-.005393,
.041457,.001834,
.040509,.009005,
.03833,.015903,
.03682,.01914,
.04197,.0243,
.045552,.016643,
.04775,.00848,
.048497,.000059,
.047771,-.008363,
.045593,-.016531,
.042029,-.024197,
.04197,-.0243,
.03682,-.01914,
180.*
4,1,15,.01914,.03682,
.012455,.039584,
.005393,.041146,
-.001834,.041457,
-.009005,.040509,
-.015903,.03833,
-.01914,.03682,
-.0243,.04197,
-.016643,.045552,
-.00848,.04775,
-.000059,.048497,
.008363,.047771,
.016531,.045593,
.024197,.042029,
.0243,.04197,
.01914,.03682,
180.*
%
%ADD76MACRO76*%
%ADD83C,.006*%
%ADD88C,.024*%
%ADD89C,.02404*%
%ADD108C,.07005*%
%ADD91C,.07006*%
%ADD87C,.07306*%
%ADD90C,.07608*%
%ADD98C,.07808*%
%ADD96C,.09708*%
%ADD110C,.311*%
%ADD106O,.03004X.07004*%
%ADD101C,.11006*%
%ADD92O,.03004X.06404*%
%ADD109C,.31502*%
%ADD93O,.03006X.06406*%
%ADD111C,.16206*%
%ADD94O,.03004X.06904*%
%ADD102C,.43406*%
%ADD85O,.03404X.06804*%
%ADD84C,.16506*%
%ADD100O,.03006X.06906*%
%ADD97C,.25806*%
%ADD95O,.2363X.2993*%
%ADD86O,.03406X.06806*%
%ADD105C,.19806*%
%ADD103C,.19807*%
%ADD104C,.19809*%
%ADD107C,.19786*%
%ADD99O,.43374X.77626*%
G75*
%LPD*%
G75*
G36*
G01X-476840Y-884638D02*
X5911000D01*
Y2768362D01*
X-476840D01*
Y-884638D01*
G37*
%LPC*%
G75*
G36*
G01X1007087Y132327D02*
G02X1009020Y130394I0J-1933D01*
G01Y46378D01*
G03X1018898Y36500I9878J0D01*
G01X1510244D01*
G02X1516114Y30630I0J-5870D01*
G01Y-1575D01*
G03X1525992Y-11453I9878J0D01*
G01X1796071D01*
G03X1805949Y-1575I0J9878D01*
G01Y30630D01*
G02X1811819Y36500I5870J0D01*
G01X1849606D01*
G02X1855476Y30630I0J-5870D01*
G01Y-40945D01*
G02X1849606Y-46815I-5870J0D01*
G01X7874D01*
G02X2004Y-40945I0J5870D01*
G01Y30630D01*
G02X7874Y36500I5870J0D01*
G01X35835D01*
G02X41705Y30630I0J-5870D01*
G01Y-1575D01*
G03X51583Y-11453I9878J0D01*
G01X321661D01*
G03X331539Y-1575I0J9878D01*
G01Y30630D01*
G02X337409Y36500I5870J0D01*
G01X480717D01*
G02X486587Y30630I0J-5870D01*
G01Y19212D01*
G03X496465Y9334I9878J0D01*
G01X766543D01*
G03X776421Y19212I0J9878D01*
G01Y30630D01*
G02X782291Y36500I5870J0D01*
G01X879134D01*
G03X889012Y46378I0J9878D01*
G01Y130394D01*
G02X890945Y132327I1933J0D01*
G01X1007087D01*
G37*
G36*
G01X1092027Y1738114D02*
X1824016D01*
G02X1829886Y1732244I0J-5870D01*
G01Y1612316D01*
G03X1832779Y1605332I9878J1D01*
G01X1839978Y1598133D01*
G02X1841697Y1593984I-4150J-4150D01*
G01Y326095D01*
G03X1844590Y319111I9878J1D01*
G01X1853757Y309944D01*
G02X1855476Y305795I-4150J-4150D01*
G01Y54252D01*
G02X1849606Y48382I-5870J0D01*
G01X1803945D01*
G03X1794067Y38504I0J-9878D01*
G01Y2204D01*
G02X1793867Y2004I-200J0D01*
G01X1528196D01*
G02X1527996Y2204I0J200D01*
G01Y38504D01*
G03X1518118Y48382I-9878J0D01*
G01X1026772D01*
G02X1020902Y54252I0J5870D01*
G01Y134331D01*
G03X1011024Y144209I-9878J0D01*
G01X887008D01*
G03X877130Y134331I0J-9878D01*
G01Y54252D01*
G02X871260Y48382I-5870J0D01*
G01X774417D01*
G03X764539Y38504I0J-9878D01*
G01Y22991D01*
G02X764339Y22791I-200J0D01*
G01X498669D01*
G02X498469Y22991I0J200D01*
G01Y38504D01*
G03X488591Y48382I-9878J0D01*
G01X329535D01*
G03X319657Y38504I0J-9878D01*
G01Y2204D01*
G02X319457Y2004I-200J0D01*
G01X53787D01*
G02X53587Y2204I0J200D01*
G01Y38504D01*
G03X43709Y48382I-9878J0D01*
G01X7874D01*
G02X2004Y54252I0J5870D01*
G01Y305795D01*
G02X3723Y309944I5869J-1D01*
G01X6985Y313206D01*
G03X9878Y320190I-6985J6985D01*
G01Y1588078D01*
G02X11597Y1592228I5870J-1D01*
G01X24701Y1605332D01*
G03X27595Y1612317I-6985J6986D01*
G01Y1732244D01*
G02X33465Y1738114I5870J0D01*
G01X765532D01*
G02X765732Y1737914I0J-200D01*
G01Y1736890D01*
G03X769705Y1732917I3973J0D01*
G01X1087854D01*
G03X1091827Y1736890I0J3973D01*
G01Y1737914D01*
G02X1092027Y1738114I200J0D01*
G37*
G36*
G01X1873228Y1820942D02*
X2093700D01*
G02X2099570Y1815072I0J-5870D01*
G01Y1791450D01*
G02X2093700Y1785580I-5870J0D01*
G01X2031574D01*
G03X2021696Y1775702I0J-9878D01*
G01Y1229954D01*
G03X2031574Y1220076I9878J0D01*
G01X2093700D01*
G02X2099570Y1214206I0J-5870D01*
G01Y-40945D01*
G02X2093700Y-46815I-5870J0D01*
G01X1873228D01*
G02X1867358Y-40945I0J5870D01*
G01Y305795D01*
G03X1862159Y318346I-17750J0D01*
G01X1855299Y325206D01*
G02X1853579Y329357I4150J4151D01*
G01Y1593984D01*
G03X1848380Y1606535I-17750J0D01*
G01X1843487Y1611428D01*
G02X1841768Y1615578I4151J4150D01*
G01Y1732244D01*
G02X1847638Y1738114I5870J0D01*
G01X1857480D01*
G03X1867358Y1747992I0J9878D01*
G01Y1815072D01*
G02X1873228Y1820942I5870J0D01*
G37*
%LPD*%
G75*
G36*
G01X81970Y18038D02*
G02Y21044I0J1503D01*
G01X85370D01*
G02Y18038I0J-1503D01*
G01X81970D01*
G37*
G36*
G01X96143D02*
G02Y21044I0J1503D01*
G01X99543D01*
G02Y18038I0J-1503D01*
G01X96143D01*
G37*
G36*
G01X110316D02*
G02Y21044I0J1503D01*
G01X113716D01*
G02Y18038I0J-1503D01*
G01X110316D01*
G37*
G36*
G01X124490D02*
G02Y21044I0J1503D01*
G01X127890D01*
G02Y18038I0J-1503D01*
G01X124490D01*
G37*
G36*
G01X160356D02*
G02Y21044I0J1503D01*
G01X163756D01*
G02Y18038I0J-1503D01*
G01X160356D01*
G37*
G36*
G01X174529D02*
G02Y21044I0J1503D01*
G01X177929D01*
G02Y18038I0J-1503D01*
G01X174529D01*
G37*
G36*
G01X204490D02*
G02Y21044I0J1503D01*
G01X207890D01*
G02Y18038I0J-1503D01*
G01X204490D01*
G37*
G36*
G01X218663D02*
G02Y21044I0J1503D01*
G01X222063D01*
G02Y18038I0J-1503D01*
G01X218663D01*
G37*
G36*
G01X1556379D02*
G02Y21044I0J1503D01*
G01X1559779D01*
G02Y18038I0J-1503D01*
G01X1556379D01*
G37*
G36*
G01X1570552D02*
G02Y21044I0J1503D01*
G01X1573952D01*
G02Y18038I0J-1503D01*
G01X1570552D01*
G37*
G36*
G01X1584725D02*
G02Y21044I0J1503D01*
G01X1588125D01*
G02Y18038I0J-1503D01*
G01X1584725D01*
G37*
G36*
G01X1598899D02*
G02Y21044I0J1503D01*
G01X1602299D01*
G02Y18038I0J-1503D01*
G01X1598899D01*
G37*
G36*
G01X1634765D02*
G02Y21044I0J1503D01*
G01X1638165D01*
G02Y18038I0J-1503D01*
G01X1634765D01*
G37*
G36*
G01X1648938D02*
G02Y21044I0J1503D01*
G01X1652338D01*
G02Y18038I0J-1503D01*
G01X1648938D01*
G37*
G36*
G01X1678899D02*
G02Y21044I0J1503D01*
G01X1682299D01*
G02Y18038I0J-1503D01*
G01X1678899D01*
G37*
G36*
G01X1693072D02*
G02Y21044I0J1503D01*
G01X1696472D01*
G02Y18038I0J-1503D01*
G01X1693072D01*
G37*
G36*
G01X280828Y24432D02*
G02Y27438I0J1503D01*
G01X284228D01*
G02Y24432I0J-1503D01*
G01X280828D01*
G37*
G36*
G01X74865Y24974D02*
G02Y27980I0J1503D01*
G01X78265D01*
G02Y24974I0J-1503D01*
G01X74865D01*
G37*
G36*
G01X89038D02*
G02Y27980I0J1503D01*
G01X92438D01*
G02Y24974I0J-1503D01*
G01X89038D01*
G37*
G36*
G01X103211D02*
G02Y27980I0J1503D01*
G01X106611D01*
G02Y24974I0J-1503D01*
G01X103211D01*
G37*
G36*
G01X117385D02*
G02Y27980I0J1503D01*
G01X120785D01*
G02Y24974I0J-1503D01*
G01X117385D01*
G37*
G36*
G01X153251D02*
G02Y27980I0J1503D01*
G01X156651D01*
G02Y24974I0J-1503D01*
G01X153251D01*
G37*
G36*
G01X167424D02*
G02Y27980I0J1503D01*
G01X170824D01*
G02Y24974I0J-1503D01*
G01X167424D01*
G37*
G36*
G01X197385D02*
G02Y27980I0J1503D01*
G01X200785D01*
G02Y24974I0J-1503D01*
G01X197385D01*
G37*
G36*
G01X211558D02*
G02Y27980I0J1503D01*
G01X214958D01*
G02Y24974I0J-1503D01*
G01X211558D01*
G37*
G36*
G01X225731D02*
G02Y27980I0J1503D01*
G01X229131D01*
G02Y24974I0J-1503D01*
G01X225731D01*
G37*
G36*
G01X1549274D02*
G02Y27980I0J1503D01*
G01X1552674D01*
G02Y24974I0J-1503D01*
G01X1549274D01*
G37*
G36*
G01X1563447D02*
G02Y27980I0J1503D01*
G01X1566847D01*
G02Y24974I0J-1503D01*
G01X1563447D01*
G37*
G36*
G01X1577620D02*
G02Y27980I0J1503D01*
G01X1581020D01*
G02Y24974I0J-1503D01*
G01X1577620D01*
G37*
G36*
G01X1591794D02*
G02Y27980I0J1503D01*
G01X1595194D01*
G02Y24974I0J-1503D01*
G01X1591794D01*
G37*
G36*
G01X1627660D02*
G02Y27980I0J1503D01*
G01X1631060D01*
G02Y24974I0J-1503D01*
G01X1627660D01*
G37*
G36*
G01X1641833D02*
G02Y27980I0J1503D01*
G01X1645233D01*
G02Y24974I0J-1503D01*
G01X1641833D01*
G37*
G36*
G01X1671794D02*
G02Y27980I0J1503D01*
G01X1675194D01*
G02Y24974I0J-1503D01*
G01X1671794D01*
G37*
G36*
G01X1685967D02*
G02Y27980I0J1503D01*
G01X1689367D01*
G02Y24974I0J-1503D01*
G01X1685967D01*
G37*
G36*
G01X1755238D02*
G02Y27980I0J1503D01*
G01X1758638D01*
G02Y24974I0J-1503D01*
G01X1755238D01*
G37*
G36*
G01X1700183Y25002D02*
G02Y28008I0J1503D01*
G01X1703583D01*
G02Y25002I0J-1503D01*
G01X1700183D01*
G37*
G36*
G01X519765Y38826D02*
G02Y41830I0J1502D01*
G01X523165D01*
G02Y38826I0J-1502D01*
G01X519765D01*
G37*
G36*
G01X670613Y40962D02*
G02Y43966I0J1502D01*
G01X674013D01*
G02Y40962I0J-1502D01*
G01X670613D01*
G37*
G36*
G01X512658Y45110D02*
G02Y48116I0J1503D01*
G01X516058D01*
G02Y45110I0J-1503D01*
G01X512658D01*
G37*
G36*
G01X533918Y45564D02*
G02Y48570I0J1503D01*
G01X537318D01*
G02Y45564I0J-1503D01*
G01X533918D01*
G37*
G36*
G01X225727Y49146D02*
G02Y52152I0J1503D01*
G01X229127D01*
G02Y49146I0J-1503D01*
G01X225727D01*
G37*
G36*
G01X280826D02*
G02Y52152I0J1503D01*
G01X284226D01*
G02Y49146I0J-1503D01*
G01X280826D01*
G37*
G36*
G01X1700136D02*
G02Y52152I0J1503D01*
G01X1703536D01*
G02Y49146I0J-1503D01*
G01X1700136D01*
G37*
G36*
G01X1755235D02*
G02Y52152I0J1503D01*
G01X1758635D01*
G02Y49146I0J-1503D01*
G01X1755235D01*
G37*
G36*
G01X262198Y54862D02*
G03X262334I68J188D01*
G02X263516Y55068I1184J-3297D01*
G02X266921Y52387I0J-3503D01*
G03X267021Y52257I195J46D01*
G02X268868Y49171I-1655J-3086D01*
G02X265365Y45668I-3503J0D01*
G02X263864Y46006I0J3503D01*
G03X263672Y45995I-86J-181D01*
G02X261816Y45462I-1857J2970D01*
G02X260634Y45668I2J3503D01*
G03X260498I-68J-188D01*
G02X259316Y45462I-1184J3297D01*
G02X257661Y45878I1J3503D01*
G03X257471I-95J-176D01*
G02X255816Y45462I-1656J3087D01*
G02X254161Y45878I1J3503D01*
G03X253971I-95J-176D01*
G02X252316Y45462I-1656J3087D01*
G02X250661Y45878I1J3503D01*
G03X250471I-95J-176D01*
G02X248816Y45462I-1656J3087D01*
G02X245314Y48965I1J3503D01*
G02X246959Y51935I3504J0D01*
G03X247051Y52075I-106J170D01*
G02X250516Y55068I3465J-509D01*
G02X252171Y54652I-1J-3503D01*
G03X252361I95J176D01*
G02X254016Y55068I1656J-3087D01*
G02X255671Y54652I-1J-3503D01*
G03X255861I95J176D01*
G02X257516Y55068I1656J-3087D01*
G02X259171Y54652I-1J-3503D01*
G03X259361I95J176D01*
G02X261016Y55068I1656J-3087D01*
G02X262198Y54862I-2J-3503D01*
G37*
G36*
G01X757202Y54804D02*
G02X758621Y55104I1418J-3202D01*
G02X762124Y51602I1J-3502D01*
G02X760383Y48575I-3502J0D01*
G01X760382Y48574D01*
G03X760284Y48421I101J-173D01*
G01X760252Y48099D01*
G03X760319Y47929I199J-20D01*
G02X754928Y47567I-2516J-2851D01*
G01X754962Y47606D01*
X754984Y47707D01*
X754852Y48131D01*
X754778Y48202D01*
X754728Y48215D01*
G02X752118Y51602I893J3387D01*
G02X755621Y55104I3503J-1D01*
G01X755623D01*
G02X757040Y54804I-1J-3502D01*
G03X757202I81J183D01*
G37*
G36*
G01X1728848Y55655D02*
X1728849Y55656D01*
G02X1729836Y56026I987J-1131D01*
G02X1731332Y54658I0J-1502D01*
G03X1731443Y54496I199J18D01*
G02X1733398Y51354I-1547J-3142D01*
G02X1733316Y50602I-3503J1D01*
G03X1733334Y50465I195J-44D01*
G02X1733744Y48822I-3093J-1644D01*
G02X1733586Y47785I-3503J3D01*
G01X1733567Y47725D01*
X1733604Y47607D01*
X1733950Y47338D01*
G03X1734177Y47325I123J158D01*
G02X1736004Y47840I1828J-2987D01*
G01X1736006D01*
G02X1739508Y44338I0J-3502D01*
G01Y44335D01*
G02X1739303Y43155I-3502J1D01*
G03Y43021I188J-67D01*
G02X1739508Y41841I-3297J-1181D01*
G01Y41838D01*
G02X1732504I-3502J0D01*
G01Y41841D01*
G02X1732709Y43021I3502J-1D01*
G03Y43155I-188J67D01*
G02X1732504Y44335I3297J1181D01*
G01Y44338D01*
G02X1732661Y45375I3503J0D01*
G01X1732680Y45435D01*
X1732643Y45553D01*
X1732297Y45822D01*
G03X1732070Y45835I-123J-158D01*
G02X1730241Y45320I-1828J2987D01*
G02X1728585Y45735I-2J3502D01*
G03X1728397I-94J-176D01*
G02X1726741Y45320I-1654J3087D01*
G02X1725085Y45735I-2J3502D01*
G03X1724897I-94J-176D01*
G02X1723241Y45320I-1654J3087D01*
G02X1719738Y48822I-1J3502D01*
G02X1721117Y51607I3503J0D01*
G03X1721195Y51749I-121J159D01*
G02X1724685Y54956I3490J-295D01*
G02X1725575Y54842I4J-3502D01*
G03X1725722Y54860I51J193D01*
G01X1725828Y54918D01*
G03X1725920Y55026I-96J175D01*
G02X1727336Y56026I1416J-503D01*
G02X1728323Y55656I0J-1501D01*
G01X1728324D01*
Y55655D01*
G03X1728454Y55607I130J152D01*
G01X1728718D01*
G03X1728848Y55655I0J200D01*
G37*
G36*
G01X1734796Y54421D02*
G02X1734590Y55603I3297J1184D01*
G02X1741596I3503J0D01*
G02X1741390Y54421I-3503J2D01*
G03Y54285I188J-68D01*
G02X1741596Y53103I-3297J-1184D01*
G02X1734590I-3503J0D01*
G02X1734796Y54285I3503J-2D01*
G03Y54421I-188J68D01*
G37*
G36*
G01X1770792Y63032D02*
Y63033D01*
G02X1777796I3502J0D01*
G01Y63032D01*
G02X1777516Y61661I-3502J1D01*
G03Y61505I184J-78D01*
G02X1777796Y60133I-3222J-1372D01*
G01Y60129D01*
G02X1777507Y58738I-3502J2D01*
G03Y58579I183J-79D01*
G02X1777794Y57191I-3216J-1389D01*
G02X1770788I-3503J0D01*
G02X1771078Y58586I3503J-1D01*
G03X1771079Y58745I-183J81D01*
G02X1770792Y60133I3215J1388D01*
G02X1771072Y61505I3502J0D01*
G03Y61661I-184J78D01*
G02X1770792Y63032I3222J1372D01*
G37*
G36*
G01X763221Y68634D02*
G02X766724Y65132I1J-3502D01*
G02X766134Y63188I-3503J2D01*
G03X766107Y63026I167J-111D01*
G02X766224Y62132I-3386J-898D01*
G02X762721Y58630I-3503J1D01*
G01X762718D01*
G02X761538Y58835I1J3502D01*
G03X761404I-67J-188D01*
G02X760221Y58630I-1181J3297D01*
G02X759038Y58835I-2J3502D01*
G03X758904I-67J-188D01*
G02X757721Y58630I-1181J3297D01*
G02X754218Y62132I-1J3502D01*
G02X754424Y63314I3503J-2D01*
G03Y63450I-188J68D01*
G02X754218Y64632I3297J1184D01*
G02X757721Y68134I3503J-1D01*
G01X757724D01*
G02X758904Y67929I-1J-3502D01*
G03X759038I67J188D01*
G02X760221Y68134I1181J-3297D01*
G02X761115Y68018I0J-3502D01*
G03X761277Y68045I51J194D01*
G02X763221Y68634I1944J-2913D01*
G37*
G36*
G01X304943Y68370D02*
G03X305084Y68377I61J190D01*
G02X306468Y68662I1384J-3217D01*
G01X306470D01*
G02Y61658I0J-3502D01*
G01X306466D01*
G02X305379Y61832I3J3502D01*
G03X305238Y61825I-61J-190D01*
G02X303854Y61540I-1384J3217D01*
G01X303852D01*
G02Y68544I0J3502D01*
G01X303856D01*
G02X304943Y68370I-3J-3502D01*
G37*
G36*
G01X61157Y67838D02*
G02Y70842I0J1502D01*
G01X64557D01*
G02Y67838I0J-1502D01*
G01X61157D01*
G37*
G36*
G01X83157D02*
G02Y70842I0J1502D01*
G01X86557D01*
G02Y67838I0J-1502D01*
G01X83157D01*
G37*
G36*
G01X105157D02*
G02Y70842I0J1502D01*
G01X108557D01*
G02Y67838I0J-1502D01*
G01X105157D01*
G37*
G36*
G01X172361D02*
G02Y70842I0J1502D01*
G01X175761D01*
G02Y67838I0J-1502D01*
G01X172361D01*
G37*
G36*
G01X194361D02*
G02Y70842I0J1502D01*
G01X197761D01*
G02Y67838I0J-1502D01*
G01X194361D01*
G37*
G36*
G01X1535566D02*
G02Y70842I0J1502D01*
G01X1538966D01*
G02Y67838I0J-1502D01*
G01X1535566D01*
G37*
G36*
G01X1557566D02*
G02Y70842I0J1502D01*
G01X1560966D01*
G02Y67838I0J-1502D01*
G01X1557566D01*
G37*
G36*
G01X1579566D02*
G02Y70842I0J1502D01*
G01X1582966D01*
G02Y67838I0J-1502D01*
G01X1579566D01*
G37*
G36*
G01X1646770D02*
G02Y70842I0J1502D01*
G01X1650170D01*
G02Y67838I0J-1502D01*
G01X1646770D01*
G37*
G36*
G01X1668770D02*
G02Y70842I0J1502D01*
G01X1672170D01*
G02Y67838I0J-1502D01*
G01X1668770D01*
G37*
G36*
G01X127153Y67840D02*
G02Y70846I0J1503D01*
G01X130553D01*
G02Y67840I0J-1503D01*
G01X127153D01*
G37*
G36*
G01X149153D02*
G02Y70846I0J1503D01*
G01X152553D01*
G02Y67840I0J-1503D01*
G01X149153D01*
G37*
G36*
G01X216491D02*
G02Y70846I0J1503D01*
G01X219891D01*
G02Y67840I0J-1503D01*
G01X216491D01*
G37*
G36*
G01X1601562D02*
G02Y70846I0J1503D01*
G01X1604962D01*
G02Y67840I0J-1503D01*
G01X1601562D01*
G37*
G36*
G01X1623562D02*
G02Y70846I0J1503D01*
G01X1626962D01*
G02Y67840I0J-1503D01*
G01X1623562D01*
G37*
G36*
G01X1690900D02*
G02Y70846I0J1503D01*
G01X1694300D01*
G02Y67840I0J-1503D01*
G01X1690900D01*
G37*
G36*
G01X1221518Y67427D02*
G02X1225540Y71450I4023J0D01*
G01X1225541D01*
G02Y63504I0J-3973D01*
G01X1225441D01*
G02X1221518Y67427I0J3923D01*
G37*
G36*
G01X519743Y69934D02*
G02Y72938I0J1502D01*
G01X523143D01*
G02Y69934I0J-1502D01*
G01X519743D01*
G37*
G36*
G01X541003D02*
G02Y72938I0J1502D01*
G01X544403D01*
G02Y69934I0J-1502D01*
G01X541003D01*
G37*
G36*
G01X555176D02*
G02Y72938I0J1502D01*
G01X558576D01*
G02Y69934I0J-1502D01*
G01X555176D01*
G37*
G36*
G01X311430Y70434D02*
G02X311150Y71806I3223J1372D01*
G02X318156I3503J0D01*
G02X317876Y70434I-3503J0D01*
G03Y70278I184J-78D01*
G02X318156Y68906I-3223J-1372D01*
G02X311150I-3503J0D01*
G02X311430Y70278I3503J0D01*
G03Y70434I-184J78D01*
G37*
G36*
G01X1776242Y72972D02*
Y72973D01*
G02X1783246I3502J0D01*
G01Y72972D01*
G02X1782966Y71601I-3502J1D01*
G03Y71445I184J-78D01*
G02X1783246Y70074I-3222J-1372D01*
G01Y70073D01*
G02X1776242I-3502J0D01*
G01Y70074D01*
G02X1776522Y71445I3502J-1D01*
G03Y71601I-184J78D01*
G02X1776242Y72972I3222J1372D01*
G37*
G36*
G01X94157Y73838D02*
G02Y76842I0J1502D01*
G01X97557D01*
G02Y73838I0J-1502D01*
G01X94157D01*
G37*
G36*
G01X116157D02*
G02Y76842I0J1502D01*
G01X119557D01*
G02Y73838I0J-1502D01*
G01X116157D01*
G37*
G36*
G01X138157D02*
G02Y76842I0J1502D01*
G01X141557D01*
G02Y73838I0J-1502D01*
G01X138157D01*
G37*
G36*
G01X161361D02*
G02Y76842I0J1502D01*
G01X164761D01*
G02Y73838I0J-1502D01*
G01X161361D01*
G37*
G36*
G01X205495D02*
G02Y76842I0J1502D01*
G01X208895D01*
G02Y73838I0J-1502D01*
G01X205495D01*
G37*
G36*
G01X227495D02*
G02Y76842I0J1502D01*
G01X230895D01*
G02Y73838I0J-1502D01*
G01X227495D01*
G37*
G36*
G01X1568566D02*
G02Y76842I0J1502D01*
G01X1571966D01*
G02Y73838I0J-1502D01*
G01X1568566D01*
G37*
G36*
G01X1590566D02*
G02Y76842I0J1502D01*
G01X1593966D01*
G02Y73838I0J-1502D01*
G01X1590566D01*
G37*
G36*
G01X1612566D02*
G02Y76842I0J1502D01*
G01X1615966D01*
G02Y73838I0J-1502D01*
G01X1612566D01*
G37*
G36*
G01X1635770D02*
G02Y76842I0J1502D01*
G01X1639170D01*
G02Y73838I0J-1502D01*
G01X1635770D01*
G37*
G36*
G01X1679904D02*
G02Y76842I0J1502D01*
G01X1683304D01*
G02Y73838I0J-1502D01*
G01X1679904D01*
G37*
G36*
G01X1701904D02*
G02Y76842I0J1502D01*
G01X1705304D01*
G02Y73838I0J-1502D01*
G01X1701904D01*
G37*
G36*
G01X72153Y73840D02*
G02Y76846I0J1503D01*
G01X75553D01*
G02Y73840I0J-1503D01*
G01X72153D01*
G37*
G36*
G01X183357D02*
G02Y76846I0J1503D01*
G01X186757D01*
G02Y73840I0J-1503D01*
G01X183357D01*
G37*
G36*
G01X1546562D02*
G02Y76846I0J1503D01*
G01X1549962D01*
G02Y73840I0J-1503D01*
G01X1546562D01*
G37*
G36*
G01X1657766D02*
G02Y76846I0J1503D01*
G01X1661166D01*
G02Y73840I0J-1503D01*
G01X1657766D01*
G37*
G36*
G01X547821Y77870D02*
G02Y80874I0J1502D01*
G01X551721D01*
G02Y77870I0J-1502D01*
G01X547821D01*
G37*
G36*
G01X259596Y78847D02*
G02X259390Y80029I3297J1184D01*
G02X266396I3503J0D01*
G02X266190Y78847I-3503J2D01*
G03Y78711I188J-68D01*
G02X266396Y77529I-3297J-1184D01*
G02X265926Y75777I-3503J1D01*
G03X265941Y75554I173J-100D01*
G02X266353Y74883I-2760J-2157D01*
G01Y74881D01*
G03X266515Y74768I181J86D01*
G01X266858Y74735D01*
G03X267037Y74814I19J199D01*
G01X267038Y74815D01*
G02X269860Y76244I2823J-2074D01*
G02Y69238I0J-3503D01*
G02X266689Y71254I0J3503D01*
G01Y71256D01*
G03X266527Y71369I-181J-86D01*
G01X266184Y71402D01*
G03X266005Y71323I-19J-199D01*
G01X266004Y71322D01*
G02X263182Y69894I-2822J2074D01*
G02X259680Y73396I0J3502D01*
G01Y73397D01*
G02X260149Y75148I3502J0D01*
G03X260134Y75371I-173J100D01*
G02X259390Y77529I2758J2158D01*
G02X259596Y78711I3503J-2D01*
G03Y78847I-188J68D01*
G37*
G36*
G01X1454786Y76366D02*
G02Y84312I0J3973D01*
G01X1454886D01*
G02X1458808Y80389I-1J-3923D01*
G02X1454786Y76366I-4022J-1D01*
G37*
G36*
G01X1738824Y84928D02*
G03X1739040Y84981I68J188D01*
G02X1741621Y86116I2581J-2367D01*
G02X1745124Y82613I0J-3503D01*
G02X1744918Y81431I-3503J2D01*
G03Y81295I188J-68D01*
G02X1745124Y80113I-3297J-1184D01*
G02X1744708Y78458I-3503J1D01*
G03Y78268I176J-95D01*
G02X1745124Y76613I-3087J-1656D01*
G02X1744918Y75431I-3503J2D01*
G03Y75295I188J-68D01*
G02X1745124Y74113I-3297J-1184D01*
G02X1741621Y70610I-3503J0D01*
G02X1740414Y70825I1J3503D01*
G03X1740198Y70772I-68J-188D01*
G02X1737617Y69638I-2580J2368D01*
G02X1734114Y73140I-1J3502D01*
G02X1734320Y74322I3503J-2D01*
G03Y74458I-188J68D01*
G02X1734114Y75640I3297J1184D01*
G02X1734530Y77295I3503J-1D01*
G03Y77485I-176J95D01*
G02X1734114Y79140I3087J1656D01*
G02X1734320Y80322I3503J-2D01*
G03Y80458I-188J68D01*
G02X1734114Y81640I3297J1184D01*
G02X1737617Y85142I3503J-1D01*
G01X1737620D01*
G02X1738824Y84928I-1J-3502D01*
G37*
G36*
G01X695374Y87282D02*
G03X695481Y87389I-77J184D01*
G02X698711Y89538I3230J-1353D01*
G02X702214Y86035I0J-3503D01*
G02X700174Y82852I-3503J0D01*
G03X700067Y82610I84J-182D01*
G02X700230Y81556I-3339J-1056D01*
G01Y81552D01*
G02X699726Y79743I-3501J1D01*
G03X699707Y79578I171J-103D01*
G02X699874Y78512I-3336J-1069D01*
G02X692868I-3503J0D01*
G02X693373Y80321I3502J-3D01*
G03X693392Y80486I-171J103D01*
G02X693226Y81552I3336J1065D01*
G02X693431Y82735I3502J2D01*
G03Y82869I-188J67D01*
G02X693226Y84049I3297J1181D01*
G01Y84052D01*
G02X695374Y87282I3503J0D01*
G37*
G36*
G01X452102Y87208D02*
G02Y90214I0J1503D01*
G01X455502D01*
G02Y87208I0J-1503D01*
G01X452102D01*
G37*
G36*
G01X537148Y89555D02*
G02X539273Y91680I1062J1062D01*
G01X541678Y89276D01*
G02X542118Y88214I-1063J-1063D01*
G01Y88213D01*
G02X540615Y86710I-1503J0D01*
G01X540614D01*
G02X539552Y87150I1J1503D01*
G01X537148Y89555D01*
G37*
G36*
G01X445014Y93182D02*
G02Y96186I0J1502D01*
G01X448414D01*
G02Y93182I0J-1502D01*
G01X445014D01*
G37*
G36*
G01X746532Y92887D02*
Y92888D01*
G02X753536I3502J0D01*
G01Y92887D01*
G02X753256Y91516I-3502J1D01*
G03Y91360I184J-78D01*
G02X753536Y89989I-3222J-1372D01*
G01Y89988D01*
G02X746532I-3502J0D01*
G01Y89989D01*
G02X746812Y91360I3502J-1D01*
G03Y91516I-184J78D01*
G02X746532Y92887I3222J1372D01*
G37*
G36*
G01X459056Y93598D02*
G02Y96604I0J1503D01*
G01X462456D01*
G02Y93598I0J-1503D01*
G01X459056D01*
G37*
G36*
G01X514240Y95644D02*
G02Y98648I0J1502D01*
G01X517640D01*
G02Y95644I0J-1502D01*
G01X514240D01*
G37*
G36*
G01X266571Y103752D02*
G03X266761I95J176D01*
G02X268416Y104168I1656J-3087D01*
G02X271908Y100934I0J-3502D01*
G03X271989Y100788I200J15D01*
G02X272651Y100153I-2073J-2823D01*
G03X272851Y100083I156J125D01*
G02X273616Y100168I767J-3418D01*
G02Y93162I0J-3503D01*
G02X270881Y94477I0J3502D01*
G03X270681Y94547I-156J-125D01*
G02X269916Y94462I-767J3418D01*
G02X268261Y94878I1J3503D01*
G03X268071I-95J-176D01*
G02X266416Y94462I-1656J3087D01*
G02X264761Y94878I1J3503D01*
G03X264571I-95J-176D01*
G02X262916Y94462I-1656J3087D01*
G02X259424Y97696I0J3502D01*
G03X259343Y97842I-200J-15D01*
G02X257914Y100665I2073J2823D01*
G02X261416Y104168I3502J1D01*
G02X263071Y103752I-1J-3503D01*
G03X263261I95J176D01*
G02X264916Y104168I1656J-3087D01*
G02X266571Y103752I-1J-3503D01*
G37*
G36*
G01X1741886Y105380D02*
G03X1742076I95J176D01*
G02X1743731Y105796I1656J-3087D01*
G02X1747049Y103414I0J-3502D01*
G03X1747141Y103303I190J64D01*
G02X1748844Y101047I-1706J-3059D01*
G03X1749019Y100894I195J46D01*
G02X1752188Y97408I-333J-3486D01*
G02X1748686Y93906I-3502J0D01*
G02X1745277Y96605I0J3502D01*
G03X1745102Y96758I-195J-46D01*
G02X1743779Y97157I330J3487D01*
G03X1743591I-94J-176D01*
G02X1741935Y96742I-1654J3087D01*
G02X1740279Y97157I-2J3502D01*
G03X1740091I-94J-176D01*
G02X1738437Y96742I-1654J3087D01*
G01X1738435D01*
G02X1735117Y99123I0J3502D01*
G03X1735025Y99234I-190J-64D01*
G02X1733228Y102293I1705J3059D01*
G02X1736731Y105796I3503J0D01*
G02X1738386Y105380I-1J-3503D01*
G03X1738576I95J176D01*
G02X1740231Y105796I1656J-3087D01*
G02X1741886Y105380I-1J-3503D01*
G37*
G36*
G01X696065Y107949D02*
G02X697721Y108364I1654J-3087D01*
G02X699377Y107949I2J-3502D01*
G03X699565I94J176D01*
G02X701219Y108364I1654J-3087D01*
G01X701221D01*
G02X704713Y105131I0J-3502D01*
G03X704794Y104985I200J15D01*
G02X705722Y103968I-2073J-2823D01*
G03X705938Y103876I171J103D01*
G02X706716Y103964I780J-3414D01*
G01X706721D01*
G02Y96960I0J-3502D01*
G02X703720Y98656I0J3503D01*
G03X703504Y98748I-171J-103D01*
G02X702721Y98660I-780J3414D01*
G02X701065Y99075I-2J3502D01*
G03X700877I-94J-176D01*
G02X699221Y98660I-1654J3087D01*
G02X697565Y99075I-2J3502D01*
G03X697377I-94J-176D01*
G02X695723Y98660I-1654J3087D01*
G01X695721D01*
G02X692229Y101893I0J3502D01*
G03X692148Y102039I-200J-15D01*
G02X690718Y104862I2071J2823D01*
G02X694221Y108364I3503J-1D01*
G01X694223D01*
G02X695877Y107949I0J-3502D01*
G03X696065I94J176D01*
G37*
G36*
G01X552105Y110700D02*
G02Y113706I0J1503D01*
G01X555505D01*
G02Y110700I0J-1503D01*
G01X552105D01*
G37*
G36*
G01X791363Y124244D02*
G03X791499I68J188D01*
G02X792681Y124450I1184J-3297D01*
G02Y117444I0J-3503D01*
G02X792393Y117456I2J3503D01*
G03X792191Y117331I-16J-199D01*
G02X788941Y115134I-3250J1305D01*
G02X787759Y115340I2J3503D01*
G03X787623I-68J-188D01*
G02X786441Y115134I-1184J3297D01*
G02X785259Y115340I2J3503D01*
G03X785123I-68J-188D01*
G02X783941Y115134I-1184J3297D01*
G02X782759Y115340I2J3503D01*
G03X782623I-68J-188D01*
G02X781441Y115134I-1184J3297D01*
G02Y122140I0J3503D01*
G02X781729Y122128I-2J-3503D01*
G03X781931Y122253I16J199D01*
G02X785181Y124450I3250J-1305D01*
G02X786363Y124244I-2J-3503D01*
G03X786499I68J188D01*
G02X787681Y124450I1184J-3297D01*
G02X788863Y124244I-2J-3503D01*
G03X788999I68J188D01*
G02X790181Y124450I1184J-3297D01*
G02X791363Y124244I-2J-3503D01*
G37*
G36*
G01X472895Y128518D02*
G02Y131522I0J1502D01*
G01X476295D01*
G02Y128518I0J-1502D01*
G01X472895D01*
G37*
G36*
G01X47255Y123148D02*
X51557Y127748D01*
G02X69964Y110535I9203J-8607D01*
G01X65662Y105934D01*
G02X47255Y123148I-9203J8607D01*
G37*
G36*
G01X490380Y129940D02*
G02Y132944I0J1502D01*
G01X493780D01*
G02Y129940I0J-1502D01*
G01X490380D01*
G37*
G36*
G01X482380Y140440D02*
G02Y143444I0J1502D01*
G01X485780D01*
G02Y140440I0J-1502D01*
G01X482380D01*
G37*
G36*
G01X779327Y150364D02*
G03X779471Y150499I-47J194D01*
G02X782819Y152974I3348J-1027D01*
G02X786322Y149471I0J-3503D01*
G02X783651Y146068I-3503J0D01*
G03X783507Y145933I47J-194D01*
G02X780159Y143458I-3348J1027D01*
G02X776656Y146961I0J3503D01*
G02X779327Y150364I3503J0D01*
G37*
G36*
G01X975691Y157718D02*
G02Y164722I0J3502D01*
G01X975693D01*
G02X978131Y163733I-1J-3502D01*
G01X978159Y163705D01*
X978231Y163676D01*
X978548Y163675D01*
G03X978686Y163730I0J200D01*
G01X978687Y163731D01*
G02X981112Y164706I2425J-2528D01*
G02Y157702I0J-3502D01*
G01X981110D01*
G02X978672Y158691I1J3502D01*
G01X978644Y158719D01*
X978572Y158748D01*
X978255Y158749D01*
G03X978117Y158694I0J-200D01*
G01X978116Y158693D01*
G02X975691Y157718I-2425J2528D01*
G37*
G36*
G01X959376Y169081D02*
G02X959170Y170263I3297J1184D01*
G02X966176I3503J0D01*
G02X965970Y169081I-3503J2D01*
G03Y168945I188J-68D01*
G02X966176Y167763I-3297J-1184D01*
G02X959170I-3503J0D01*
G02X959376Y168945I3503J-2D01*
G03Y169081I-188J68D01*
G37*
G36*
G01X946854Y179703D02*
G03X946999Y179709I65J189D01*
G02X948401Y180002I1402J-3210D01*
G02X951904Y176499I0J-3503D01*
G02X949342Y173125I-3503J0D01*
G03X949197Y172957I54J-193D01*
G02X945721Y169886I-3476J432D01*
G02X944539Y170092I2J3503D01*
G03X944403I-68J-188D01*
G02X943221Y169886I-1184J3297D01*
G02X942039Y170092I2J3503D01*
G03X941903I-68J-188D01*
G02X940721Y169886I-1184J3297D01*
G02X939510Y170103I3J3503D01*
G03X939372I-69J-188D01*
G02X938161Y169886I-1214J3286D01*
G02X937002Y170084I2J3503D01*
G03X936861Y170081I-67J-189D01*
G02X935551Y169826I-1312J3248D01*
G02X932048Y173329I0J3503D01*
G02X932313Y174663I3503J-2D01*
G03X932315Y174810I-185J76D01*
G02X932088Y176049I3276J1240D01*
G02X935591Y179552I3503J0D01*
G01X935592D01*
G02X936376Y179463I-1J-3503D01*
G03X936515Y179481I45J195D01*
G02X938161Y179892I1646J-3091D01*
G02X939372Y179675I-3J-3503D01*
G03X939510I69J188D01*
G02X940721Y179892I1214J-3286D01*
G02X941903Y179686I-2J-3503D01*
G03X942039I68J188D01*
G02X943221Y179892I1184J-3297D01*
G02X944403Y179686I-2J-3503D01*
G03X944539I68J188D01*
G02X945721Y179892I1184J-3297D01*
G02X946854Y179703I-2J-3503D01*
G37*
G36*
G01X365287Y173422D02*
G02Y197050I0J11814D01*
G01X371587D01*
G02Y173422I0J-11814D01*
G01X365287D01*
G37*
G36*
G01X247177Y172636D02*
G02Y197836I0J12600D01*
G01X253476D01*
G02Y172636I0J-12600D01*
G01X247177D01*
G37*
G36*
G01X987564Y209093D02*
G03X987721Y209152I15J199D01*
G02X990221Y210202I2501J-2453D01*
G02X993724Y206699I0J-3503D01*
G02X993308Y205044I-3503J1D01*
G03Y204854I176J-95D01*
G02X993724Y203199I-3087J-1656D01*
G02X993308Y201544I-3503J1D01*
G03Y201354I176J-95D01*
G02X993724Y199699I-3087J-1656D01*
G02X990221Y196196I-3503J0D01*
G02X989978Y196205I8J3503D01*
G03X989821Y196146I-15J-199D01*
G02X989542Y195890I-2504J2449D01*
G03X989471Y195701I126J-155D01*
G02X989524Y195099I-3450J-607D01*
G02X982518I-3503J0D01*
G02X983800Y197808I3503J0D01*
G03X983871Y197997I-126J155D01*
G02X983818Y198598I3450J607D01*
G01Y198600D01*
G02X983819Y198660I3503J-28D01*
G02X982055Y199171I59J3502D01*
G03X981837Y199165I-104J-170D01*
G02X979849Y198546I-1988J2884D01*
G02X977910Y199132I1J3503D01*
G03X977688I-111J-166D01*
G02X975749Y198546I-1940J2917D01*
G02X972359Y201167I0J3503D01*
G03X972153Y201317I-194J-50D01*
G02X971943Y201310I-222J3496D01*
G02X970051Y201866I2J3503D01*
G03X969835I-108J-169D01*
G02X967943Y201310I-1894J2947D01*
G02X964686Y203525I0J3502D01*
G03X964536Y203648I-186J-74D01*
G02X963305Y205125I271J1477D01*
G02X964807Y206627I1502J0D01*
G01X964833D01*
G03X965004Y206718I3J200D01*
G02X967943Y208316I2939J-1904D01*
G02X969835Y207760I-2J-3503D01*
G03X970051I108J169D01*
G02X971943Y208316I1894J-2947D01*
G02X974028Y207627I-1J-3503D01*
G01X974059Y207604D01*
X974131Y207584D01*
X974478Y207624D01*
X974544Y207658D01*
X974569Y207687D01*
G02X977221Y208902I2652J-2287D01*
G02X980718Y205584I0J-3502D01*
G03X980860Y205403I200J11D01*
G02X981673Y205040I-1010J-3354D01*
G03X981891Y205046I104J170D01*
G02X983641Y205656I1987J-2884D01*
G03X983827Y205842I-14J200D01*
G02X987321Y209102I3494J-242D01*
G02X987564Y209093I-8J-3503D01*
G37*
G36*
G01X860942Y329356D02*
G02Y332360I0J1502D01*
G01X864342D01*
G02Y329356I0J-1502D01*
G01X860942D01*
G37*
G36*
G01X920139Y309612D02*
G02X937341I8601J12042D01*
G01X920139D01*
G37*
G36*
G01X857187Y340708D02*
G02Y343712I0J1502D01*
G01X860587D01*
G02Y340708I0J-1502D01*
G01X857187D01*
G37*
G36*
G01X45960Y427304D02*
G02Y430308I0J1502D01*
G01X49360D01*
G02Y427304I0J-1502D01*
G01X45960D01*
G37*
G36*
G01X60921Y429304D02*
G02Y432308I0J1502D01*
G01X64821D01*
G02Y429304I0J-1502D01*
G01X60921D01*
G37*
G36*
G01X45812Y450100D02*
G02Y453104I0J1502D01*
G01X49212D01*
G02Y450100I0J-1502D01*
G01X45812D01*
G37*
G36*
G01X644414Y569666D02*
G02Y572672I0J1503D01*
G01X648314D01*
G02Y569666I0J-1503D01*
G01X644414D01*
G37*
G36*
G01X646358Y588814D02*
G02Y591818I0J1502D01*
G01X650258D01*
G02Y588814I0J-1502D01*
G01X646358D01*
G37*
G36*
G01X634794Y589002D02*
G02Y592006I0J1502D01*
G01X638694D01*
G02Y589002I0J-1502D01*
G01X634794D01*
G37*
G36*
G01X469014Y604311D02*
G03X469148I67J188D01*
G02X470331Y604516I1181J-3297D01*
G02X473834Y601014I1J-3502D01*
G02X473628Y599832I-3503J2D01*
G03Y599696I188J-68D01*
G02X473834Y598514I-3297J-1184D01*
G02X470331Y595012I-3503J1D01*
G01X470328D01*
G02X469148Y595217I1J3502D01*
G03X469014I-67J-188D01*
G02X467831Y595012I-1181J3297D01*
G02X466648Y595217I-2J3502D01*
G03X466514I-67J-188D01*
G02X465331Y595012I-1181J3297D01*
G02X464148Y595217I-2J3502D01*
G03X464014I-67J-188D01*
G02X462831Y595012I-1181J3297D01*
G02X461592Y595238I-1J3502D01*
G03X461450I-71J-187D01*
G02X460211Y595012I-1238J3276D01*
G02X459028Y595217I-2J3502D01*
G03X458894I-67J-188D01*
G02X457711Y595012I-1181J3297D01*
G02X454208Y598514I-1J3502D01*
G02X454414Y599696I3503J-2D01*
G03Y599832I-188J68D01*
G02X454208Y601014I3297J1184D01*
G02X457711Y604516I3503J-1D01*
G01X457714D01*
G02X458894Y604311I-1J-3502D01*
G03X459028I67J188D01*
G02X460211Y604516I1181J-3297D01*
G02X461450Y604290I1J-3502D01*
G03X461592I71J187D01*
G02X462831Y604516I1238J-3276D01*
G02X464014Y604311I2J-3502D01*
G03X464148I67J188D01*
G02X465331Y604516I1181J-3297D01*
G02X466514Y604311I2J-3502D01*
G03X466648I67J188D01*
G02X467831Y604516I1181J-3297D01*
G02X469014Y604311I2J-3502D01*
G37*
G36*
G01X509510Y613939D02*
Y613940D01*
G02X516514I3502J0D01*
G01Y613939D01*
G02X516234Y612568I-3502J1D01*
G03X516235Y612412I185J-77D01*
G02X516372Y612030I-3223J-1372D01*
G03X516544Y611887I192J56D01*
G02X517354Y611708I-338J-3451D01*
G03X517486I66J189D01*
G02X518635Y611904I1149J-3272D01*
G02Y604968I0J-3468D01*
G02X517486Y605164I0J3468D01*
G03X517354I-66J-189D01*
G02X516205Y604968I-1149J3272D01*
G02X515056Y605164I0J3468D01*
G03X514924I-66J-189D01*
G02X514513Y605048I-1146J3273D01*
G02X514514Y605003I-3501J-100D01*
G01Y604999D01*
G02X514234Y603629I-3503J2D01*
G03Y603473I184J-78D01*
G02X514514Y602101I-3223J-1372D01*
G02X511011Y598598I-3503J0D01*
G02X508840Y599353I1J3503D01*
G03X508609Y599365I-124J-157D01*
G02X506745Y598828I-1864J2967D01*
G02X503242Y602331I0J3503D01*
G02X503522Y603703I3503J0D01*
G03Y603859I-184J78D01*
G02X503242Y605231I3223J1372D01*
G02X503522Y606603I3503J0D01*
G03Y606759I-184J78D01*
G02X503242Y608131I3223J1372D01*
G02X506745Y611634I3503J0D01*
G02X508871Y610914I-1J-3503D01*
G01X508916Y610880D01*
X509025Y610868D01*
X509449Y611065D01*
X509511Y611157D01*
X509514Y611212D01*
G02X509790Y612412I3498J-173D01*
G03Y612568I-184J78D01*
G02X509510Y613939I3222J1372D01*
G37*
G36*
G01X1525960Y621415D02*
G03X1526094I67J188D01*
G02X1527277Y621620I1181J-3297D01*
G02X1530780Y618118I1J-3502D01*
G02X1530574Y616936I-3503J2D01*
G03Y616800I188J-68D01*
G02X1530780Y615618I-3297J-1184D01*
G02X1530569Y614421I-3503J0D01*
G03Y614285I188J-68D01*
G02X1530780Y613088I-3292J-1197D01*
G02X1530574Y611906I-3503J2D01*
G03Y611770I188J-68D01*
G02X1530780Y610588I-3297J-1184D01*
G02X1530556Y609358I-3503J2D01*
G03Y609218I188J-70D01*
G02X1530780Y607988I-3279J-1232D01*
G02X1530574Y606806I-3503J2D01*
G03Y606670I188J-68D01*
G02X1530780Y605488I-3297J-1184D01*
G02X1527277Y601986I-3503J1D01*
G01X1527274D01*
G02X1526094Y602191I1J3502D01*
G03X1525960I-67J-188D01*
G02X1524777Y601986I-1181J3297D01*
G02X1521274Y605488I-1J3502D01*
G02X1521480Y606670I3503J-2D01*
G03Y606806I-188J68D01*
G02X1521274Y607988I3297J1184D01*
G02X1521498Y609218I3503J-2D01*
G03Y609358I-188J70D01*
G02X1521274Y610588I3279J1232D01*
G02X1521480Y611770I3503J-2D01*
G03Y611906I-188J68D01*
G02X1521274Y613088I3297J1184D01*
G02X1521485Y614285I3503J0D01*
G03Y614421I-188J68D01*
G02X1521274Y615618I3292J1197D01*
G02X1521480Y616800I3503J-2D01*
G03Y616936I-188J68D01*
G02X1521274Y618118I3297J1184D01*
G02X1524777Y621620I3503J-1D01*
G01X1524780D01*
G02X1525960Y621415I-1J-3502D01*
G37*
G36*
G01X1357462Y632413D02*
Y632414D01*
G02X1364466I3502J0D01*
G01Y632413D01*
G02X1364186Y631042I-3502J1D01*
G03X1364187Y630886I185J-77D01*
G02X1364411Y630133I-3224J-1369D01*
G03X1364567Y629973I197J36D01*
G02X1365006Y629851I-707J-3395D01*
G03X1365138I66J189D01*
G02X1366283Y630046I1146J-3272D01*
G01X1366287D01*
G02Y623112I0J-3467D01*
G01X1366283D01*
G02X1365138Y623307I1J3467D01*
G03X1365006I-66J-189D01*
G02X1363857Y623112I-1146J3272D01*
G02X1362708Y623307I-3J3467D01*
G03X1362576I-66J-189D01*
G02X1362165Y623191I-1146J3273D01*
G02X1362166Y623146I-3501J-100D01*
G01Y623142D01*
G02X1361886Y621772I-3503J2D01*
G03Y621616I184J-78D01*
G02X1362166Y620244I-3223J-1372D01*
G02X1358663Y616742I-3503J1D01*
G01X1358662D01*
G02X1356492Y617496I1J3502D01*
G03X1356261Y617508I-124J-157D01*
G02X1354397Y616972I-1862J2967D01*
G02X1350894Y620474I-1J3502D01*
G02X1351174Y621846I3503J0D01*
G03Y622002I-184J78D01*
G02X1350894Y623374I3223J1372D01*
G02X1351174Y624746I3503J0D01*
G03Y624902I-184J78D01*
G02X1350894Y626274I3223J1372D01*
G02X1354397Y629776I3503J-1D01*
G02X1357197Y628378I0J-3503D01*
G03X1357316Y628302I160J120D01*
G02X1357363Y628292I-705J-3431D01*
G01X1357522Y628461D01*
G03X1357570Y628647I-146J137D01*
G02X1357462Y629514I3394J863D01*
G02X1357742Y630886I3502J0D01*
G03Y631042I-184J78D01*
G02X1357462Y632413I3222J1372D01*
G37*
G36*
G01X1701661Y643052D02*
G02Y646056I0J1502D01*
G01X1705561D01*
G02Y643052I0J-1502D01*
G01X1701661D01*
G37*
G36*
G01X1620462Y642739D02*
Y642741D01*
G02X1627466I3502J0D01*
G01Y642739D01*
G02X1627166Y641322I-3502J1D01*
G03Y641160I183J-81D01*
G02X1627387Y640480I-3203J-1417D01*
G03X1627543Y640326I196J42D01*
G02X1628006Y640199I-684J-3400D01*
G03X1628138I66J189D01*
G02X1629283Y640394I1146J-3272D01*
G01X1629287D01*
G02Y633460I0J-3467D01*
G01X1629283D01*
G02X1628138Y633655I1J3467D01*
G03X1628006I-66J-189D01*
G02X1626857Y633460I-1146J3272D01*
G02X1625708Y633655I-3J3467D01*
G03X1625576I-66J-189D01*
G02X1625165Y633539I-1146J3273D01*
G02X1625166Y633494I-3501J-100D01*
G01Y633490D01*
G02X1624886Y632120I-3503J2D01*
G03Y631964I184J-78D01*
G02X1625166Y630592I-3223J-1372D01*
G02X1621663Y627090I-3503J1D01*
G01X1621662D01*
G02X1619492Y627844I1J3502D01*
G03X1619261Y627856I-124J-157D01*
G02X1617397Y627320I-1862J2967D01*
G02X1613894Y630822I-1J3502D01*
G02X1614174Y632194I3503J0D01*
G03Y632350I-184J78D01*
G02X1613894Y633722I3223J1372D01*
G02X1614174Y635094I3503J0D01*
G03Y635250I-184J78D01*
G02X1613894Y636622I3223J1372D01*
G02X1617397Y640124I3503J-1D01*
G01X1617398D01*
G02X1620198Y638726I0J-3504D01*
G03X1620316Y638650I160J119D01*
G02X1620330Y638647I-727J-3426D01*
G01X1620490Y638813D01*
G03X1620542Y638994I-143J139D01*
G02X1620462Y639741I3422J744D01*
G02X1620762Y641160I3502J1D01*
G03Y641322I-183J81D01*
G02X1620462Y642739I3202J1418D01*
G37*
G36*
G01X353915Y649354D02*
G02X355195Y649596I1279J-3260D01*
G02X358698Y646094I1J-3502D01*
G02X358517Y644986I-3502J3D01*
G03X358522Y644848I190J-62D01*
G02X358778Y643534I-3247J-1315D01*
G02X358572Y642352I-3503J2D01*
G03Y642216I188J-68D01*
G02X358778Y641034I-3297J-1184D01*
G02X355275Y637532I-3503J1D01*
G01X355272D01*
G02X354096Y637736I2J3502D01*
G03X353955Y637734I-68J-188D01*
G02X352675Y637492I-1279J3260D01*
G02X351492Y637697I-2J3502D01*
G03X351358I-67J-188D01*
G02X350175Y637492I-1181J3297D01*
G02X348992Y637697I-2J3502D01*
G03X348858I-67J-188D01*
G02X347675Y637492I-1181J3297D01*
G02X346492Y637697I-2J3502D01*
G03X346358I-67J-188D01*
G02X345175Y637492I-1181J3297D01*
G02X343992Y637697I-2J3502D01*
G03X343858I-67J-188D01*
G02X342675Y637492I-1181J3297D01*
G02X339172Y640994I-1J3502D01*
G02X339378Y642176I3503J-2D01*
G03Y642312I-188J68D01*
G02X339172Y643494I3297J1184D01*
G02X339353Y644602I3502J-3D01*
G03X339348Y644740I-190J62D01*
G02X339092Y646054I3247J1315D01*
G02X342595Y649556I3503J-1D01*
G01X342598D01*
G02X343778Y649351I-1J-3502D01*
G03X343912I67J188D01*
G02X345095Y649556I1181J-3297D01*
G02X346278Y649351I2J-3502D01*
G03X346412I67J188D01*
G02X347595Y649556I1181J-3297D01*
G02X348778Y649351I2J-3502D01*
G03X348912I67J188D01*
G02X350095Y649556I1181J-3297D01*
G02X351278Y649351I2J-3502D01*
G03X351412I67J188D01*
G02X352595Y649556I1181J-3297D01*
G02X353774Y649352I1J-3502D01*
G03X353915Y649354I68J188D01*
G37*
G36*
G01X476310Y648139D02*
Y648140D01*
G02X483314I3502J0D01*
G01Y648139D01*
G02X483034Y646768I-3502J1D01*
G03X483035Y646612I185J-77D01*
G02X483202Y646120I-3224J-1369D01*
G03X483369Y645972I194J50D01*
G02X484054Y645808I-461J-3437D01*
G03X484186I66J189D01*
G02X485335Y646004I1149J-3272D01*
G02Y639068I0J-3468D01*
G02X484186Y639264I0J3468D01*
G03X484054I-66J-189D01*
G02X482905Y639068I-1149J3272D01*
G02X481756Y639264I0J3468D01*
G03X481624I-66J-189D01*
G02X481213Y639148I-1146J3273D01*
G02X481214Y639103I-3501J-100D01*
G01Y639099D01*
G02X480934Y637729I-3503J2D01*
G03Y637573I184J-78D01*
G02X481214Y636201I-3223J-1372D01*
G02X477711Y632698I-3503J0D01*
G02X475540Y633453I1J3503D01*
G03X475309Y633465I-124J-157D01*
G02X473445Y632928I-1864J2967D01*
G02X469942Y636431I0J3503D01*
G02X470222Y637803I3503J0D01*
G03Y637959I-184J78D01*
G02X469942Y639331I3223J1372D01*
G02X470222Y640703I3503J0D01*
G03Y640859I-184J78D01*
G02X469942Y642231I3223J1372D01*
G02X473445Y645734I3503J0D01*
G02X475657Y644947I0J-3502D01*
G03X475869Y644921I127J155D01*
G01X476196Y645075D01*
G03X476310Y645255I-86J181D01*
G02X476590Y646612I3502J-15D01*
G03Y646768I-184J78D01*
G02X476310Y648139I3222J1372D01*
G37*
G36*
G01X1452863Y653667D02*
G02X1454046Y653872I1181J-3297D01*
G02X1455229Y653667I2J-3502D01*
G03X1455363I67J188D01*
G02X1456541Y653872I1181J-3297D01*
G01X1456546D01*
G02X1457918Y653592I0J-3502D01*
G03X1458074I78J184D01*
G02X1459445Y653872I1372J-3222D01*
G01X1459446D01*
G02X1462948Y650370I0J-3502D01*
G01Y650365D01*
G02X1462701Y649077I-3502J4D01*
G03X1462699Y648936I186J-73D01*
G02X1462898Y647770I-3303J-1164D01*
G02X1462693Y646587I-3502J-2D01*
G03Y646453I188J-67D01*
G02X1462898Y645273I-3297J-1181D01*
G01Y645270D01*
G02X1459396Y641768I-3502J0D01*
G01X1459395D01*
G02X1458024Y642048I1J3502D01*
G03X1457868I-78J-184D01*
G02X1456496Y641768I-1372J3222D01*
G01X1456491D01*
G02X1455313Y641973I3J3502D01*
G03X1455179I-67J-188D01*
G02X1453996Y641768I-1181J3297D01*
G02X1452813Y641973I-2J3502D01*
G03X1452679I-67J-188D01*
G02X1451496Y641768I-1181J3297D01*
G02X1450313Y641973I-2J3502D01*
G03X1450179I-67J-188D01*
G02X1448996Y641768I-1181J3297D01*
G02X1447757Y641994I-1J3502D01*
G03X1447615I-71J-187D01*
G02X1446376Y641768I-1238J3276D01*
G02X1445193Y641973I-2J3502D01*
G03X1445059I-67J-188D01*
G02X1443879Y641768I-1181J3297D01*
G01X1443876D01*
G02X1440374Y645270I0J3502D01*
G01Y645273D01*
G02X1440579Y646453I3502J-1D01*
G03Y646587I-188J67D01*
G02X1440374Y647770I3297J1181D01*
G02X1440621Y649063I3502J1D01*
G03X1440623Y649204I-186J73D01*
G02X1440424Y650366I3303J1164D01*
G01Y650370D01*
G02X1443926Y653872I3502J0D01*
G01X1443929D01*
G02X1445109Y653667I-1J-3502D01*
G03X1445243I67J188D01*
G02X1446426Y653872I1181J-3297D01*
G02X1447665Y653646I1J-3502D01*
G03X1447807I71J187D01*
G02X1449046Y653872I1238J-3276D01*
G02X1450229Y653667I2J-3502D01*
G03X1450363I67J188D01*
G02X1451546Y653872I1181J-3297D01*
G02X1452729Y653667I2J-3502D01*
G03X1452863I67J188D01*
G37*
G36*
G01X1587462Y661739D02*
Y661741D01*
G02X1594466I3502J0D01*
G01Y661739D01*
G02X1594166Y660322I-3502J1D01*
G03Y660160I183J-81D01*
G02X1594387Y659480I-3203J-1417D01*
G03X1594543Y659326I196J42D01*
G02X1595006Y659199I-684J-3400D01*
G03X1595138I66J189D01*
G02X1596283Y659394I1146J-3272D01*
G01X1596287D01*
G02Y652460I0J-3467D01*
G01X1596283D01*
G02X1595138Y652655I1J3467D01*
G03X1595006I-66J-189D01*
G02X1593857Y652460I-1146J3272D01*
G02X1592708Y652655I-3J3467D01*
G03X1592576I-66J-189D01*
G02X1592165Y652539I-1146J3273D01*
G02X1592166Y652494I-3501J-100D01*
G01Y652490D01*
G02X1591886Y651120I-3503J2D01*
G03Y650964I184J-78D01*
G02X1592166Y649592I-3223J-1372D01*
G02X1588663Y646090I-3503J1D01*
G01X1588662D01*
G02X1586492Y646844I1J3502D01*
G03X1586261Y646856I-124J-157D01*
G02X1584397Y646320I-1862J2967D01*
G02X1580894Y649822I-1J3502D01*
G02X1581174Y651194I3503J0D01*
G03Y651350I-184J78D01*
G02X1580894Y652722I3223J1372D01*
G02X1581174Y654094I3503J0D01*
G03Y654250I-184J78D01*
G02X1580894Y655622I3223J1372D01*
G02X1584397Y659124I3503J-1D01*
G01X1584398D01*
G02X1587198Y657726I0J-3504D01*
G03X1587316Y657650I160J119D01*
G02X1587330Y657647I-727J-3426D01*
G01X1587490Y657813D01*
G03X1587542Y657994I-143J139D01*
G02X1587462Y658741I3422J744D01*
G02X1587762Y660160I3502J1D01*
G03Y660322I-183J81D01*
G02X1587462Y661739I3202J1418D01*
G37*
G36*
G01X246810Y663079D02*
Y663080D01*
G02X253814I3502J0D01*
G01Y663079D01*
G02X253534Y661708I-3502J1D01*
G03X253535Y661552I185J-77D01*
G02X253756Y660818I-3223J-1371D01*
G03X253917Y660658I197J37D01*
G02X254454Y660517I-609J-3414D01*
G03X254586I66J189D01*
G02X255731Y660712I1146J-3272D01*
G01X255735D01*
G02Y653778I0J-3467D01*
G01X255731D01*
G02X254586Y653973I1J3467D01*
G03X254454I-66J-189D01*
G02X253305Y653778I-1146J3272D01*
G02X252156Y653973I-3J3467D01*
G03X252024I-66J-189D01*
G02X251613Y653857I-1146J3273D01*
G02X251614Y653812I-3501J-100D01*
G01Y653808D01*
G02X251334Y652438I-3503J2D01*
G03Y652282I184J-78D01*
G02X251614Y650910I-3223J-1372D01*
G02X248111Y647408I-3503J1D01*
G01X248110D01*
G02X245940Y648162I1J3502D01*
G03X245709Y648174I-124J-157D01*
G02X243845Y647638I-1862J2967D01*
G02X240342Y651140I-1J3502D01*
G02X240622Y652512I3503J0D01*
G03Y652668I-184J78D01*
G02X240342Y654040I3223J1372D01*
G02X240622Y655412I3503J0D01*
G03Y655568I-184J78D01*
G02X240342Y656940I3223J1372D01*
G02X243845Y660442I3503J-1D01*
G01X243846D01*
G02X246158Y659570I0J-3502D01*
G01X246204Y659529D01*
X246324Y659514D01*
X246711Y659708D01*
G03X246821Y659902I-89J179D01*
G02X246810Y660179I3491J277D01*
G01Y660180D01*
G02X247090Y661552I3502J0D01*
G03Y661708I-184J78D01*
G02X246810Y663079I3222J1372D01*
G37*
G36*
G01X1390162Y665283D02*
Y665284D01*
G02X1397166I3502J0D01*
G01Y665283D01*
G02X1396886Y663912I-3502J1D01*
G03Y663756I184J-78D01*
G02X1397105Y663033I-3223J-1371D01*
G03X1397261Y662874I197J37D01*
G02X1397706Y662751I-699J-3396D01*
G03X1397838I66J189D01*
G02X1398983Y662946I1146J-3272D01*
G01X1398987D01*
G02Y656012I0J-3467D01*
G01X1398983D01*
G02X1397838Y656207I1J3467D01*
G03X1397706I-66J-189D01*
G02X1396557Y656012I-1146J3272D01*
G02X1395408Y656207I-3J3467D01*
G03X1395276I-66J-189D01*
G02X1394865Y656091I-1146J3273D01*
G02X1394866Y656046I-3501J-100D01*
G01Y656042D01*
G02X1394586Y654672I-3503J2D01*
G03Y654516I184J-78D01*
G02X1394866Y653144I-3223J-1372D01*
G02X1391363Y649642I-3503J1D01*
G01X1391362D01*
G02X1389192Y650396I1J3502D01*
G03X1388961Y650408I-124J-157D01*
G02X1387097Y649872I-1862J2967D01*
G02X1383594Y653374I-1J3502D01*
G02X1383874Y654746I3503J0D01*
G03Y654902I-184J78D01*
G02X1383594Y656274I3223J1372D01*
G02X1383874Y657646I3503J0D01*
G03Y657802I-184J78D01*
G02X1383594Y659174I3223J1372D01*
G02X1387097Y662676I3503J-1D01*
G02X1389897Y661278I0J-3503D01*
G03X1390016Y661202I160J120D01*
G02X1390055Y661194I-684J-3435D01*
G01X1390214Y661362D01*
G03X1390263Y661547I-145J138D01*
G02X1390162Y662380I3401J835D01*
G01Y662384D01*
G02X1390442Y663756I3502J0D01*
G03Y663912I-184J78D01*
G02X1390162Y665283I3222J1372D01*
G37*
G36*
G01X635567Y670272D02*
G02Y673276I0J1502D01*
G01X638967D01*
G02Y670272I0J-1502D01*
G01X635567D01*
G37*
G36*
G01X443710Y674539D02*
Y674540D01*
G02X450714I3502J0D01*
G01Y674539D01*
G02X450434Y673168I-3502J1D01*
G03X450435Y673012I185J-77D01*
G02X450575Y672618I-3225J-1368D01*
G03X450742Y672476I192J56D01*
G02X451454Y672308I-436J-3440D01*
G03X451586I66J189D01*
G02X452735Y672504I1149J-3272D01*
G02Y665568I0J-3468D01*
G02X451586Y665764I0J3468D01*
G03X451454I-66J-189D01*
G02X450305Y665568I-1149J3272D01*
G02X449156Y665764I0J3468D01*
G03X449024I-66J-189D01*
G02X448613Y665648I-1146J3273D01*
G02X448614Y665603I-3501J-100D01*
G01Y665599D01*
G02X448334Y664229I-3503J2D01*
G03Y664073I184J-78D01*
G02X448614Y662701I-3223J-1372D01*
G02X445111Y659198I-3503J0D01*
G02X442940Y659953I1J3503D01*
G03X442709Y659965I-124J-157D01*
G02X440845Y659428I-1864J2967D01*
G02X437342Y662931I0J3503D01*
G02X437622Y664303I3503J0D01*
G03Y664459I-184J78D01*
G02X437342Y665831I3223J1372D01*
G02X437622Y667203I3503J0D01*
G03Y667359I-184J78D01*
G02X437342Y668731I3223J1372D01*
G02X440845Y672234I3503J0D01*
G02X443057Y671445I-2J-3502D01*
G01X443059D01*
Y671444D01*
G03X443267Y671418I125J156D01*
G01X443594Y671567D01*
G03X443711Y671743I-83J182D01*
G01Y671744D01*
G02X443990Y673012I3501J-106D01*
G03Y673168I-184J78D01*
G02X443710Y674539I3222J1372D01*
G37*
G36*
G01X1554692Y695499D02*
Y695501D01*
G02X1561696I3502J0D01*
G01Y695499D01*
G02X1561396Y694082I-3502J1D01*
G03Y693920I183J-81D01*
G02X1561616Y693249I-3201J-1421D01*
G03X1561772Y693095I196J42D01*
G02X1562236Y692968I-681J-3400D01*
G03X1562368I66J189D01*
G02X1563517Y693164I1149J-3272D01*
G02Y686228I0J-3468D01*
G02X1562368Y686424I0J3468D01*
G03X1562236I-66J-189D01*
G02X1561087Y686228I-1149J3272D01*
G02X1559938Y686424I0J3468D01*
G03X1559806I-66J-189D01*
G02X1559395Y686308I-1146J3273D01*
G02X1559396Y686263I-3501J-100D01*
G01Y686259D01*
G02X1559116Y684889I-3503J2D01*
G03Y684733I184J-78D01*
G02X1559396Y683361I-3223J-1372D01*
G02X1559161Y682101I-3503J1D01*
G03X1559168Y681940I186J-73D01*
G02X1559530Y680391I-3141J-1551D01*
G02X1556581Y676933I-3502J0D01*
G03X1556453Y676856I32J-198D01*
G02X1553657Y675462I-2797J2109D01*
G02X1550154Y678965I0J3503D01*
G02X1550455Y680384I3503J-2D01*
G03Y680546I-183J81D01*
G02X1550154Y681965I3202J1421D01*
G02X1550494Y683470I3503J0D01*
G03X1550498Y683634I-180J86D01*
G02X1550224Y684991I3229J1358D01*
G02X1550574Y686516I3503J-1D01*
G03X1550579Y686678I-180J87D01*
G02X1550324Y687989I3248J1312D01*
G01Y687991D01*
G02X1553827Y691494I3503J0D01*
G02X1554292Y691463I0J-3503D01*
G01X1554340Y691456D01*
X1554429Y691487D01*
X1554686Y691752D01*
G03X1554739Y691925I-144J139D01*
G02X1554692Y692501I3455J572D01*
G02X1554992Y693920I3502J1D01*
G03Y694082I-183J81D01*
G02X1554692Y695499I3202J1418D01*
G37*
G36*
G01X279540Y697279D02*
Y697280D01*
G02X286544I3502J0D01*
G01Y697279D01*
G02X286264Y695908I-3502J1D01*
G03Y695752I184J-78D01*
G02X286477Y695066I-3221J-1376D01*
G03X286638Y694908I196J39D01*
G02X287184Y694765I-603J-3415D01*
G03X287316I66J189D01*
G02X288461Y694960I1146J-3272D01*
G01X288465D01*
G02Y688026I0J-3467D01*
G01X288461D01*
G02X287316Y688221I1J3467D01*
G03X287184I-66J-189D01*
G02X286035Y688026I-1146J3272D01*
G02X284886Y688221I-3J3467D01*
G03X284754I-66J-189D01*
G02X284343Y688105I-1146J3273D01*
G02X284344Y688052I-3501J-93D01*
G01Y688050D01*
G02X284064Y686679I-3503J1D01*
G03Y686523I184J-78D01*
G02X284344Y685151I-3223J-1372D01*
G02X280841Y681648I-3503J0D01*
G02X278670Y682403I1J3503D01*
G03X278439Y682415I-124J-157D01*
G02X276575Y681878I-1864J2967D01*
G02X273072Y685381I0J3503D01*
G02X273352Y686753I3503J0D01*
G03Y686909I-184J78D01*
G02X273072Y688281I3223J1372D01*
G02X273352Y689653I3503J0D01*
G03Y689809I-184J78D01*
G02X273072Y691181I3223J1372D01*
G02X276575Y694684I3503J0D01*
G02X278885Y693814I0J-3502D01*
G01X278930Y693774D01*
X279050Y693758D01*
X279437Y693949D01*
G03X279548Y694142I-88J179D01*
G02X279540Y694377I3494J237D01*
G01Y694380D01*
G02X279820Y695752I3502J0D01*
G03Y695908I-184J78D01*
G02X279540Y697279I3222J1372D01*
G37*
G36*
G01X1422762Y697853D02*
Y697854D01*
G02X1429766I3502J0D01*
G01Y697853D01*
G02X1429486Y696482I-3502J1D01*
G03Y696326I184J-78D01*
G02X1429631Y695916I-3223J-1370D01*
G03X1429789Y695773I193J54D01*
G02X1430336Y695631I-595J-3416D01*
G03X1430468I66J189D01*
G02X1431613Y695826I1146J-3272D01*
G01X1431617D01*
G02Y688892I0J-3467D01*
G01X1431613D01*
G02X1430468Y689087I1J3467D01*
G03X1430336I-66J-189D01*
G02X1429187Y688892I-1146J3272D01*
G02X1428038Y689087I-3J3467D01*
G03X1427906I-66J-189D01*
G02X1427612Y688998I-1151J3271D01*
G03X1427461Y688794I49J-194D01*
G02X1427466Y688624I-3497J-188D01*
G02X1427186Y687252I-3503J0D01*
G03Y687096I184J-78D01*
G02X1427466Y685724I-3223J-1372D01*
G02X1423963Y682222I-3503J1D01*
G01X1423962D01*
G02X1421792Y682976I1J3502D01*
G03X1421561Y682988I-124J-157D01*
G02X1419697Y682452I-1862J2967D01*
G02X1416194Y685954I-1J3502D01*
G02X1416474Y687326I3503J0D01*
G03Y687482I-184J78D01*
G02X1416194Y688854I3223J1372D01*
G02X1416474Y690226I3503J0D01*
G03Y690382I-184J78D01*
G02X1416194Y691754I3223J1372D01*
G02X1419697Y695256I3503J-1D01*
G02X1422498Y693857I0J-3504D01*
G03X1422615Y693782I160J120D01*
G02X1422652Y693774I-722J-3427D01*
G01X1422812Y693943D01*
G03X1422861Y694127I-145J137D01*
G02X1422762Y694954I3405J827D01*
G01Y694955D01*
G02X1423042Y696326I3502J-1D01*
G03Y696482I-184J78D01*
G02X1422762Y697853I3222J1372D01*
G37*
G36*
G01X411210Y699439D02*
Y699440D01*
G02X418214I3502J0D01*
G01Y699439D01*
G02X417934Y698068I-3502J1D01*
G03X417935Y697912I185J-77D01*
G02X418145Y697237I-3223J-1373D01*
G03X418317Y697079I196J40D01*
G02X419054Y696908I-411J-3443D01*
G03X419186I66J189D01*
G02X420335Y697104I1149J-3272D01*
G02Y690168I0J-3468D01*
G02X419186Y690364I0J3468D01*
G03X419054I-66J-189D01*
G02X417905Y690168I-1149J3272D01*
G02X416756Y690364I0J3468D01*
G03X416624I-66J-189D01*
G02X416213Y690248I-1146J3273D01*
G02X416214Y690203I-3501J-100D01*
G01Y690199D01*
G02X415934Y688829I-3503J2D01*
G03Y688673I184J-78D01*
G02X416214Y687301I-3223J-1372D01*
G02X412711Y683798I-3503J0D01*
G02X410540Y684553I1J3503D01*
G03X410309Y684565I-124J-157D01*
G02X408445Y684028I-1864J2967D01*
G02X404942Y687531I0J3503D01*
G02X405222Y688903I3503J0D01*
G03Y689059I-184J78D01*
G02X404942Y690431I3223J1372D01*
G02X405222Y691803I3503J0D01*
G03Y691959I-184J78D01*
G02X404942Y693331I3223J1372D01*
G02X408445Y696834I3503J0D01*
G02X410567Y696116I-3J-3502D01*
G01X410569D01*
Y696115D01*
G03X410780Y696097I120J160D01*
G01X411102Y696262D01*
G03X411211Y696445I-91J178D01*
G02X411210Y696540I3501J84D01*
G02X411490Y697912I3502J0D01*
G03Y698068I-184J78D01*
G02X411210Y699439I3222J1372D01*
G37*
G36*
G01X378310Y717059D02*
Y717060D01*
G02X385314I3502J0D01*
G01Y717059D01*
G02X385034Y715688I-3502J1D01*
G03Y715532I184J-78D01*
G02X385207Y715020I-3221J-1374D01*
G03X385374Y714871I194J49D01*
G02X386054Y714708I-464J-3436D01*
G03X386186I66J189D01*
G02X387335Y714904I1149J-3272D01*
G02Y707968I0J-3468D01*
G02X386186Y708164I0J3468D01*
G03X386054I-66J-189D01*
G02X384905Y707968I-1149J3272D01*
G02X383756Y708164I0J3468D01*
G03X383624I-66J-189D01*
G02X383213Y708048I-1146J3273D01*
G02X383214Y708003I-3501J-100D01*
G01Y707999D01*
G02X382934Y706629I-3503J2D01*
G03Y706473I184J-78D01*
G02X383214Y705101I-3223J-1372D01*
G02X379711Y701598I-3503J0D01*
G02X377540Y702353I1J3503D01*
G03X377309Y702365I-124J-157D01*
G02X375445Y701828I-1864J2967D01*
G02X371942Y705331I0J3503D01*
G02X372222Y706703I3503J0D01*
G03Y706859I-184J78D01*
G02X371942Y708231I3223J1372D01*
G02X372222Y709603I3503J0D01*
G03Y709759I-184J78D01*
G02X371942Y711131I3223J1372D01*
G02X375445Y714634I3503J0D01*
G02X377657Y713847I0J-3502D01*
G01X377702Y713810D01*
X377816Y713796D01*
X378196Y713977D01*
G03X378310Y714157I-86J181D01*
G01Y714161D01*
G02X378590Y715532I3502J-1D01*
G03Y715688I-184J78D01*
G02X378310Y717059I3222J1372D01*
G37*
G36*
G01X345172Y715688D02*
G02X344892Y717060I3223J1372D01*
G02X351898I3503J0D01*
G02X351618Y715688I-3503J0D01*
G03Y715532I184J-78D01*
G02X351832Y714835I-3223J-1371D01*
G02X351862Y714836I130J-3464D01*
G01X351868D01*
G02X353014Y714640I-3J-3468D01*
G03X353146I66J189D01*
G02X354295Y714836I1149J-3272D01*
G02Y707900I0J-3468D01*
G02X353146Y708096I0J3468D01*
G03X353014I-66J-189D01*
G02X351865Y707900I-1149J3272D01*
G02X350716Y708096I0J3468D01*
G03X350584I-66J-189D01*
G02X350173Y707980I-1146J3273D01*
G02X350174Y707935I-3501J-100D01*
G01Y707931D01*
G02X349894Y706561I-3503J2D01*
G03Y706405I184J-78D01*
G02X350174Y705033I-3223J-1372D01*
G02X346671Y701530I-3503J0D01*
G02X344500Y702285I1J3503D01*
G03X344269Y702297I-124J-157D01*
G02X342405Y701760I-1864J2967D01*
G02X338902Y705263I0J3503D01*
G02X339182Y706635I3503J0D01*
G03Y706791I-184J78D01*
G02X338902Y708163I3223J1372D01*
G02X339182Y709535I3503J0D01*
G03Y709691I-184J78D01*
G02X338902Y711063I3223J1372D01*
G02X342405Y714566I3503J0D01*
G02X344283Y714019I-2J-3503D01*
G01X344328Y713990D01*
X344434Y713986D01*
X344789Y714169D01*
G03X344897Y714337I-92J178D01*
G02X345172Y715532I3498J-176D01*
G03Y715688I-184J78D01*
G37*
G36*
G01X1455554Y715722D02*
G02X1455274Y717094I3223J1372D01*
G02X1462280I3503J0D01*
G02X1462000Y715723I-3503J1D01*
G03Y715566I184J-78D01*
G02X1462059Y715418I-3223J-1371D01*
G03X1462235Y715288I188J70D01*
G02X1463194Y715098I-188J-3462D01*
G03X1463326I66J189D01*
G02X1464475Y715294I1149J-3272D01*
G02Y708358I0J-3468D01*
G02X1463326Y708554I0J3468D01*
G03X1463194I-66J-189D01*
G02X1462045Y708358I-1149J3272D01*
G02X1460896Y708554I0J3468D01*
G03X1460764I-66J-189D01*
G02X1460530Y708481I-1149J3272D01*
G03X1460383Y708283I53J-193D01*
G02X1460384Y708201I-3502J-84D01*
G02X1460104Y706829I-3503J0D01*
G03Y706673I184J-78D01*
G02X1460384Y705301I-3223J-1372D01*
G02X1458218Y702064I-3502J0D01*
G03X1458101Y701828I76J-185D01*
G02X1458218Y700932I-3386J-898D01*
G01Y700931D01*
G02X1451212I-3503J0D01*
G02X1451371Y701972I3503J-2D01*
G03X1451362Y702115I-191J60D01*
G01X1451313Y702222D01*
G03X1451211Y702323I-182J-82D01*
G02X1449112Y705531I1403J3209D01*
G02X1451314Y708783I3502J0D01*
G03X1451433Y709021I-74J186D01*
G02X1451312Y709931I3382J913D01*
G02X1454814Y713434I3503J0D01*
G01X1454816D01*
G02X1454883Y713433I-19J-3503D01*
G01X1454926Y713432D01*
X1455005Y713465D01*
X1455237Y713716D01*
G03X1455290Y713870I-146J136D01*
G02X1455274Y714194I3486J335D01*
G02X1455554Y715566I3503J0D01*
G03Y715722I-184J78D01*
G37*
G36*
G01X312410Y717399D02*
Y717400D01*
G02X319414I3502J0D01*
G01Y717399D01*
G02X319134Y716028I-3502J1D01*
G03X319135Y715872I185J-77D01*
G02X319346Y715189I-3224J-1370D01*
G03X319502Y715033I196J40D01*
G02X319954Y714908I-696J-3397D01*
G03X320086I66J189D01*
G02X321235Y715104I1149J-3272D01*
G02Y708168I0J-3468D01*
G02X320086Y708364I0J3468D01*
G03X319954I-66J-189D01*
G02X318805Y708168I-1149J3272D01*
G02X317656Y708364I0J3468D01*
G03X317524I-66J-189D01*
G02X317113Y708248I-1146J3273D01*
G02X317114Y708203I-3501J-100D01*
G01Y708199D01*
G02X316834Y706829I-3503J2D01*
G03Y706673I184J-78D01*
G02X317114Y705301I-3223J-1372D01*
G02X316143Y702881I-3503J1D01*
G03X316089Y702719I144J-138D01*
G02X316114Y702301I-3478J-418D01*
G02X313343Y698876I-3502J0D01*
G03X313226Y698802I42J-196D01*
G02X310445Y697428I-2782J2129D01*
G02X306942Y700931I0J3503D01*
G02X307243Y702350I3503J-2D01*
G03Y702512I-183J81D01*
G02X306942Y703931I3202J1421D01*
G02X307913Y706351I3503J-1D01*
G03X307967Y706513I-144J138D01*
G02X307942Y706931I3478J418D01*
G02X308292Y708456I3503J-1D01*
G03X308297Y708618I-180J87D01*
G02X308042Y709929I3248J1312D01*
G01Y709931D01*
G02X311545Y713434I3503J0D01*
G02X312019Y713401I-6J-3503D01*
G01X312067Y713394D01*
X312157Y713426D01*
X312415Y713696D01*
G03X312467Y713869I-145J138D01*
G01Y713870D01*
G02X312410Y714499I3445J629D01*
G01Y714500D01*
G02X312690Y715872I3502J0D01*
G03Y716028I-184J78D01*
G02X312410Y717399I3222J1372D01*
G37*
G36*
G01X1488762Y717443D02*
Y717444D01*
G02X1495766I3502J0D01*
G01Y717443D01*
G02X1495486Y716072I-3502J1D01*
G03X1495487Y715916I185J-77D01*
G02X1495706Y715190I-3224J-1369D01*
G03X1495862Y715031I197J37D01*
G02X1496306Y714908I-702J-3396D01*
G03X1496438I66J189D01*
G02X1497587Y715104I1149J-3272D01*
G02Y708168I0J-3468D01*
G02X1496438Y708364I0J3468D01*
G03X1496306I-66J-189D01*
G02X1495157Y708168I-1149J3272D01*
G02X1494008Y708364I0J3468D01*
G03X1493876I-66J-189D01*
G02X1493465Y708248I-1146J3273D01*
G02X1493466Y708203I-3501J-100D01*
G01Y708199D01*
G02X1493186Y706829I-3503J2D01*
G03Y706673I184J-78D01*
G02X1493466Y705301I-3223J-1372D01*
G02X1489963Y701798I-3503J0D01*
G02X1487792Y702553I1J3503D01*
G03X1487561Y702565I-124J-157D01*
G02X1485697Y702028I-1864J2967D01*
G02X1482194Y705531I0J3503D01*
G02X1482474Y706903I3503J0D01*
G03Y707059I-184J78D01*
G02X1482194Y708431I3223J1372D01*
G02X1482474Y709803I3503J0D01*
G03Y709959I-184J78D01*
G02X1482194Y711331I3223J1372D01*
G02X1485697Y714834I3503J0D01*
G02X1488498Y713434I0J-3502D01*
G03X1488615Y713359I160J120D01*
G02X1488655Y713350I-749J-3421D01*
G01X1488815Y713519D01*
G03X1488864Y713704I-146J138D01*
G02X1488762Y714542I3400J839D01*
G01Y714544D01*
G02X1489042Y715916I3502J0D01*
G03Y716072I-184J78D01*
G02X1488762Y717443I3222J1372D01*
G37*
G36*
G01X1521562D02*
Y717444D01*
G02X1528566I3502J0D01*
G01Y717443D01*
G02X1528286Y716072I-3502J1D01*
G03X1528287Y715916I185J-77D01*
G02X1528506Y715190I-3224J-1369D01*
G03X1528662Y715031I197J37D01*
G02X1529106Y714908I-702J-3396D01*
G03X1529238I66J189D01*
G02X1530387Y715104I1149J-3272D01*
G02Y708168I0J-3468D01*
G02X1529238Y708364I0J3468D01*
G03X1529106I-66J-189D01*
G02X1527957Y708168I-1149J3272D01*
G02X1526808Y708364I0J3468D01*
G03X1526676I-66J-189D01*
G02X1526265Y708248I-1146J3273D01*
G02X1526266Y708203I-3501J-100D01*
G01Y708199D01*
G02X1525986Y706829I-3503J2D01*
G03Y706673I184J-78D01*
G02X1526266Y705301I-3223J-1372D01*
G02X1522763Y701798I-3503J0D01*
G02X1520592Y702553I1J3503D01*
G03X1520361Y702565I-124J-157D01*
G02X1518497Y702028I-1864J2967D01*
G02X1514994Y705531I0J3503D01*
G02X1515274Y706903I3503J0D01*
G03Y707059I-184J78D01*
G02X1514994Y708431I3223J1372D01*
G02X1515274Y709803I3503J0D01*
G03Y709959I-184J78D01*
G02X1514994Y711331I3223J1372D01*
G02X1518497Y714834I3503J0D01*
G02X1521298Y713434I0J-3502D01*
G03X1521415Y713359I160J120D01*
G02X1521455Y713350I-749J-3421D01*
G01X1521615Y713519D01*
G03X1521664Y713704I-146J138D01*
G02X1521562Y714542I3400J839D01*
G01Y714544D01*
G02X1521842Y715916I3502J0D01*
G03Y716072I-184J78D01*
G02X1521562Y717443I3222J1372D01*
G37*
G36*
G01X869275Y748970D02*
G02Y751974I0J1502D01*
G01X873175D01*
G02Y748970I0J-1502D01*
G01X869275D01*
G37*
G36*
G01X1332812Y854880D02*
G02Y857886I0J1503D01*
G01X1336812D01*
G02Y854880I0J-1503D01*
G01X1332812D01*
G37*
G36*
G01X509572Y863824D02*
G02Y866830I0J1503D01*
G01X513572D01*
G02Y863824I0J-1503D01*
G01X509572D01*
G37*
G36*
G01X427130Y958146D02*
G02Y960550I0J1202D01*
G01X430831D01*
G02Y958146I0J-1202D01*
G01X427130D01*
G37*
G36*
G01X1425452Y958144D02*
G02Y960550I0J1203D01*
G01X1429153D01*
G02Y958144I0J-1203D01*
G01X1425452D01*
G37*
G36*
G01X1434704Y961334D02*
G02Y963738I0J1202D01*
G01X1438405D01*
G02Y961334I0J-1202D01*
G01X1434704D01*
G37*
G36*
G01X1445806D02*
G02Y963738I0J1202D01*
G01X1449507D01*
G02Y961334I0J-1202D01*
G01X1445806D01*
G37*
G36*
G01X1456909D02*
G02Y963738I0J1202D01*
G01X1460610D01*
G02Y961334I0J-1202D01*
G01X1456909D01*
G37*
G36*
G01X1468011D02*
G02Y963738I0J1202D01*
G01X1471712D01*
G02Y961334I0J-1202D01*
G01X1468011D01*
G37*
G36*
G01X384571D02*
G02Y963740I0J1203D01*
G01X388272D01*
G02Y961334I0J-1203D01*
G01X384571D01*
G37*
G36*
G01X395673D02*
G02Y963740I0J1203D01*
G01X399374D01*
G02Y961334I0J-1203D01*
G01X395673D01*
G37*
G36*
G01X406776D02*
G02Y963740I0J1203D01*
G01X410477D01*
G02Y961334I0J-1203D01*
G01X406776D01*
G37*
G36*
G01X417878D02*
G02Y963740I0J1203D01*
G01X421579D01*
G02Y961334I0J-1203D01*
G01X417878D01*
G37*
G36*
G01X427130Y964524D02*
G02Y966928I0J1202D01*
G01X430831D01*
G02Y964524I0J-1202D01*
G01X427130D01*
G37*
G36*
G01X1425452Y964522D02*
G02Y966928I0J1203D01*
G01X1429153D01*
G02Y964522I0J-1203D01*
G01X1425452D01*
G37*
G36*
G01X1434704Y967712D02*
G02Y970116I0J1202D01*
G01X1438405D01*
G02Y967712I0J-1202D01*
G01X1434704D01*
G37*
G36*
G01X1445806D02*
G02Y970116I0J1202D01*
G01X1449507D01*
G02Y967712I0J-1202D01*
G01X1445806D01*
G37*
G36*
G01X1456909D02*
G02Y970116I0J1202D01*
G01X1460610D01*
G02Y967712I0J-1202D01*
G01X1456909D01*
G37*
G36*
G01X1468011D02*
G02Y970116I0J1202D01*
G01X1471712D01*
G02Y967712I0J-1202D01*
G01X1468011D01*
G37*
G36*
G01X384571D02*
G02Y970118I0J1203D01*
G01X388272D01*
G02Y967712I0J-1203D01*
G01X384571D01*
G37*
G36*
G01X395673D02*
G02Y970118I0J1203D01*
G01X399374D01*
G02Y967712I0J-1203D01*
G01X395673D01*
G37*
G36*
G01X406776D02*
G02Y970118I0J1203D01*
G01X410477D01*
G02Y967712I0J-1203D01*
G01X406776D01*
G37*
G36*
G01X417878D02*
G02Y970118I0J1203D01*
G01X421579D01*
G02Y967712I0J-1203D01*
G01X417878D01*
G37*
G36*
G01X427130Y970902D02*
G02Y973306I0J1202D01*
G01X430831D01*
G02Y970902I0J-1202D01*
G01X427130D01*
G37*
G36*
G01X1425452Y970900D02*
G02Y973306I0J1203D01*
G01X1429153D01*
G02Y970900I0J-1203D01*
G01X1425452D01*
G37*
G36*
G01X1434704Y974090D02*
G02Y976494I0J1202D01*
G01X1438405D01*
G02Y974090I0J-1202D01*
G01X1434704D01*
G37*
G36*
G01X1445806D02*
G02Y976494I0J1202D01*
G01X1449507D01*
G02Y974090I0J-1202D01*
G01X1445806D01*
G37*
G36*
G01X1456909D02*
G02Y976494I0J1202D01*
G01X1460610D01*
G02Y974090I0J-1202D01*
G01X1456909D01*
G37*
G36*
G01X1468011D02*
G02Y976494I0J1202D01*
G01X1471712D01*
G02Y974090I0J-1202D01*
G01X1468011D01*
G37*
G36*
G01X384571D02*
G02Y976496I0J1203D01*
G01X388272D01*
G02Y974090I0J-1203D01*
G01X384571D01*
G37*
G36*
G01X395673D02*
G02Y976496I0J1203D01*
G01X399374D01*
G02Y974090I0J-1203D01*
G01X395673D01*
G37*
G36*
G01X406776D02*
G02Y976496I0J1203D01*
G01X410477D01*
G02Y974090I0J-1203D01*
G01X406776D01*
G37*
G36*
G01X417878D02*
G02Y976496I0J1203D01*
G01X421579D01*
G02Y974090I0J-1203D01*
G01X417878D01*
G37*
G36*
G01X427130Y977280D02*
G02Y979684I0J1202D01*
G01X430831D01*
G02Y977280I0J-1202D01*
G01X427130D01*
G37*
G36*
G01X1425452Y977278D02*
G02Y979684I0J1203D01*
G01X1429153D01*
G02Y977278I0J-1203D01*
G01X1425452D01*
G37*
G36*
G01X368726Y1212952D02*
G02Y1215958I0J1503D01*
G01X372126D01*
G02Y1212952I0J-1503D01*
G01X368726D01*
G37*
G36*
G01X1325972Y1332957D02*
Y1332959D01*
G02X1329474Y1336460I3502J-1D01*
G02X1331645Y1335705I-1J-3503D01*
G03X1331876Y1335693I124J157D01*
G02X1333740Y1336230I1864J-2967D01*
G02X1337242Y1332727I-1J-3503D01*
G01Y1332726D01*
G02X1336962Y1331355I-3502J1D01*
G03Y1331199I184J-78D01*
G02X1337242Y1329827I-3222J-1372D01*
G02X1336962Y1328455I-3502J0D01*
G03Y1328299I184J-78D01*
G02X1337242Y1326927I-3222J-1372D01*
G01Y1326925D01*
G02X1333740Y1323424I-3502J1D01*
G02X1331971Y1323904I1J3503D01*
G01X1331926Y1323930D01*
X1331823Y1323932D01*
X1331476Y1323750D01*
G03X1331370Y1323587I94J-177D01*
G02X1331099Y1322462I-3494J247D01*
G03X1331098Y1322306I184J-79D01*
G02X1331378Y1320935I-3222J-1372D01*
G01Y1320934D01*
G02X1324374I-3502J0D01*
G01Y1320935D01*
G02X1324654Y1322306I3502J-1D01*
G03X1324653Y1322462I-185J77D01*
G02X1324439Y1323158I3223J1372D01*
G02X1324280Y1323154I-167J3464D01*
G02X1323131Y1323350I0J3468D01*
G03X1322999I-66J-189D01*
G02X1321850Y1323154I-1149J3272D01*
G02Y1330090I0J3468D01*
G02X1322999Y1329894I0J-3468D01*
G03X1323131I66J189D01*
G02X1324280Y1330090I1149J-3272D01*
G02X1325429Y1329894I0J-3468D01*
G03X1325561I66J189D01*
G02X1325972Y1330010I1146J-3273D01*
G01Y1330057D01*
G02X1326252Y1331429I3502J0D01*
G03Y1331585I-184J78D01*
G02X1325972Y1332957I3222J1372D01*
G37*
G36*
G01X349842Y1332976D02*
G02X353345Y1336478I3503J-1D01*
G01X353346D01*
G02X355516Y1335724I-1J-3502D01*
G03X355747Y1335712I124J157D01*
G02X357611Y1336248I1862J-2967D01*
G02X361114Y1332746I1J-3502D01*
G02X360834Y1331374I-3503J0D01*
G03Y1331218I184J-78D01*
G02X361114Y1329846I-3223J-1372D01*
G02X360834Y1328474I-3503J0D01*
G03Y1328318I184J-78D01*
G02X361114Y1326946I-3223J-1372D01*
G02X357611Y1323444I-3503J1D01*
G01X357609D01*
G02X355729Y1323992I1J3502D01*
G01X355683Y1324021D01*
X355578Y1324026D01*
X355222Y1323842D01*
G03X355114Y1323675I92J-178D01*
G01Y1323674D01*
G02X354836Y1322471I-3463J167D01*
G03Y1322313I184J-79D01*
G02X355118Y1320945I-3185J-1370D01*
G01Y1320942D01*
G02X348184I-3467J0D01*
G01Y1320945D01*
G02X348466Y1322313I3467J-2D01*
G03Y1322471I-184J79D01*
G02X348248Y1323175I3185J1372D01*
G02X348151Y1323174I-84J3466D01*
G02X347002Y1323369I-3J3467D01*
G03X346870I-66J-189D01*
G02X345725Y1323174I-1146J3272D01*
G01X345721D01*
G02Y1330108I0J3467D01*
G01X345725D01*
G02X346870Y1329913I-1J-3467D01*
G03X347002I66J189D01*
G02X348151Y1330108I1146J-3272D01*
G02X349300Y1329913I3J-3467D01*
G03X349432I66J189D01*
G02X349843Y1330029I1146J-3273D01*
G02X349842Y1330074I3501J100D01*
G01Y1330078D01*
G02X350122Y1331448I3503J-2D01*
G03Y1331604I-184J78D01*
G02X349842Y1332976I3223J1372D01*
G37*
G36*
G01X1293068Y1333014D02*
G02X1296570Y1336516I3502J0D01*
G01X1296571D01*
G02X1298741Y1335762I-1J-3502D01*
G03X1298972Y1335750I124J157D01*
G02X1300833Y1336286I1862J-2967D01*
G01X1300836D01*
G02X1304338Y1332784I0J-3502D01*
G01Y1332783D01*
G02X1304058Y1331412I-3502J1D01*
G03Y1331256I184J-78D01*
G02X1304338Y1329884I-3222J-1372D01*
G02X1304058Y1328512I-3502J0D01*
G03Y1328356I184J-78D01*
G02X1304338Y1326985I-3222J-1372D01*
G01Y1326984D01*
G02X1300836Y1323482I-3502J0D01*
G02X1299056Y1323968I0J3503D01*
G03X1298860Y1323972I-102J-172D01*
G01X1298512Y1323785D01*
X1298456Y1323697D01*
X1298453Y1323645D01*
G02X1298178Y1322462I-3497J189D01*
G03Y1322306I184J-78D01*
G02X1298458Y1320935I-3222J-1372D01*
G01Y1320934D01*
G02X1291454I-3502J0D01*
G01Y1320935D01*
G02X1291734Y1322306I3502J-1D01*
G03Y1322462I-184J78D01*
G02X1291509Y1323214I3222J1374D01*
G02X1291376Y1323212I-119J3465D01*
G02X1290227Y1323407I-3J3467D01*
G03X1290095I-66J-189D01*
G02X1288950Y1323212I-1146J3272D01*
G01X1288946D01*
G02Y1330146I0J3467D01*
G01X1288950D01*
G02X1290095Y1329951I-1J-3467D01*
G03X1290227I66J189D01*
G02X1291376Y1330146I1146J-3272D01*
G02X1292525Y1329951I3J-3467D01*
G03X1292657I66J189D01*
G02X1293068Y1330067I1146J-3273D01*
G01Y1330114D01*
G02X1293348Y1331486I3502J0D01*
G03Y1331642I-184J78D01*
G02X1293068Y1333013I3222J1372D01*
G01Y1333014D01*
G37*
G36*
G01X317218Y1331661D02*
G02X316938Y1333033I3223J1372D01*
G02X320441Y1336536I3503J0D01*
G02X322612Y1335781I-1J-3503D01*
G03X322843Y1335769I124J157D01*
G02X324707Y1336306I1864J-2967D01*
G02X328210Y1332803I0J-3503D01*
G02X327930Y1331431I-3503J0D01*
G03Y1331275I184J-78D01*
G02X328210Y1329903I-3223J-1372D01*
G02X327930Y1328531I-3503J0D01*
G03Y1328375I184J-78D01*
G02X328210Y1327003I-3223J-1372D01*
G02X324707Y1323500I-3503J0D01*
G02X322884Y1324012I0J3503D01*
G01X322838Y1324040D01*
X322732Y1324043D01*
X322381Y1323853D01*
G03X322276Y1323684I95J-176D01*
G02X321996Y1322431I-3465J117D01*
G03Y1322273I184J-79D01*
G02X322278Y1320905I-3185J-1370D01*
G01Y1320902D01*
G02X315344I-3467J0D01*
G01Y1320905D01*
G02X315626Y1322273I3467J-2D01*
G03Y1322431I-184J79D01*
G02X315390Y1323233I3184J1373D01*
G02X315247Y1323230I-144J3465D01*
G02X314098Y1323426I0J3468D01*
G03X313966I-66J-189D01*
G02X312817Y1323230I-1149J3272D01*
G02Y1330166I0J3468D01*
G02X313966Y1329970I0J-3468D01*
G03X314098I66J189D01*
G02X315247Y1330166I1149J-3272D01*
G02X316396Y1329970I0J-3468D01*
G03X316528I66J189D01*
G02X316939Y1330086I1146J-3273D01*
G02X316938Y1330131I3501J100D01*
G01Y1330135D01*
G02X317218Y1331505I3503J-2D01*
G03Y1331661I-184J78D01*
G37*
G36*
G01X1260172Y1333042D02*
G02X1263674Y1336544I3502J0D01*
G01X1263675D01*
G02X1265845Y1335790I-1J-3502D01*
G03X1266076Y1335778I124J157D01*
G02X1267937Y1336314I1862J-2967D01*
G01X1267940D01*
G02X1271442Y1332812I0J-3502D01*
G01Y1332811D01*
G02X1271162Y1331440I-3502J1D01*
G03Y1331284I184J-78D01*
G02X1271442Y1329912I-3222J-1372D01*
G02X1271162Y1328540I-3502J0D01*
G03Y1328384I184J-78D01*
G02X1271442Y1327013I-3222J-1372D01*
G01Y1327012D01*
G02X1267940Y1323510I-3502J0D01*
G01X1267938D01*
G02X1266154Y1323999I1J3502D01*
G01X1266108Y1324026D01*
X1266003Y1324028D01*
X1265607Y1323810D01*
X1265552Y1323720D01*
X1265551Y1323667D01*
G02X1265273Y1322406I-3501J111D01*
G03X1265272Y1322250I184J-79D01*
G02X1265552Y1320879I-3222J-1372D01*
G01Y1320878D01*
G02X1258548I-3502J0D01*
G01Y1320879D01*
G02X1258828Y1322250I3502J-1D01*
G03Y1322406I-184J78D01*
G02X1258589Y1323241I3222J1374D01*
G02X1258481Y1323240I-86J3466D01*
G01X1258479D01*
G02X1257331Y1323435I-2J3467D01*
G03X1257199I-66J-189D01*
G02X1256054Y1323240I-1146J3272D01*
G01X1256050D01*
G02Y1330174I0J3467D01*
G01X1256054D01*
G02X1257199Y1329979I-1J-3467D01*
G03X1257331I66J189D01*
G02X1258480Y1330174I1146J-3272D01*
G02X1259629Y1329979I3J-3467D01*
G03X1259761I66J189D01*
G02X1260172Y1330095I1146J-3273D01*
G01Y1330142D01*
G02X1260452Y1331514I3502J0D01*
G03Y1331670I-184J78D01*
G02X1260172Y1333041I3222J1372D01*
G01Y1333042D01*
G37*
G36*
G01X284322Y1331689D02*
G02X284042Y1333061I3223J1372D01*
G02X287545Y1336564I3503J0D01*
G02X289716Y1335809I-1J-3503D01*
G03X289947Y1335797I124J157D01*
G02X291811Y1336334I1864J-2967D01*
G02X295314Y1332831I0J-3503D01*
G02X295034Y1331459I-3503J0D01*
G03Y1331303I184J-78D01*
G02X295314Y1329931I-3223J-1372D01*
G02X295034Y1328559I-3503J0D01*
G03Y1328403I184J-78D01*
G02X295314Y1327031I-3223J-1372D01*
G02X291811Y1323528I-3503J0D01*
G02X289967Y1324053I1J3503D01*
G01X289921Y1324082D01*
X289815Y1324085D01*
X289415Y1323871D01*
X289358Y1323780D01*
X289357Y1323727D01*
G02X289076Y1322471I-3466J116D01*
G03Y1322313I184J-79D01*
G02X289358Y1320945I-3185J-1370D01*
G01Y1320942D01*
G02X282424I-3467J0D01*
G01Y1320945D01*
G02X282706Y1322313I3467J-2D01*
G03Y1322471I-184J79D01*
G02X282473Y1323261I3186J1369D01*
G02X282352Y1323258I-146J3464D01*
G01X282350D01*
G02X281202Y1323454I1J3468D01*
G03X281070I-66J-189D01*
G02X279921Y1323258I-1149J3272D01*
G02Y1330194I0J3468D01*
G02X281070Y1329998I0J-3468D01*
G03X281202I66J189D01*
G02X282351Y1330194I1149J-3272D01*
G02X283500Y1329998I0J-3468D01*
G03X283632I66J189D01*
G02X284043Y1330114I1146J-3273D01*
G02X284042Y1330159I3501J100D01*
G01Y1330163D01*
G02X284322Y1331533I3503J-2D01*
G03Y1331689I-184J78D01*
G37*
G36*
G01X1361459Y1339463D02*
G03X1361576Y1339543I-47J194D01*
G02X1364440Y1341030I2865J-2016D01*
G02X1367942Y1337527I-1J-3503D01*
G01Y1337525D01*
G02X1367642Y1336108I-3502J1D01*
G03Y1335946I183J-81D01*
G02X1367942Y1334527I-3202J-1418D01*
G02X1367642Y1333108I-3502J-1D01*
G03Y1332946I183J-81D01*
G02X1367942Y1331527I-3202J-1418D01*
G02X1367593Y1330002I-3502J-1D01*
G03X1367587Y1329840I180J-88D01*
G02X1367842Y1328531I-3247J-1312D01*
G01Y1328527D01*
G02X1364563Y1325032I-3502J0D01*
G01X1364561D01*
G03X1364420Y1324959I14J-200D01*
G01X1364208Y1324699D01*
X1364186Y1324618D01*
X1364192Y1324576D01*
G02X1364226Y1324084I-3468J-487D01*
G02X1363946Y1322712I-3502J0D01*
G03Y1322556I184J-78D01*
G02X1364226Y1321185I-3222J-1372D01*
G01Y1321184D01*
G02X1357222I-3502J0D01*
G01Y1321185D01*
G02X1357502Y1322556I3502J-1D01*
G03Y1322712I-184J78D01*
G02X1357334Y1323205I3222J1373D01*
G03X1357137Y1323355I-194J-50D01*
G02X1357080Y1323354I-89J3466D01*
G02X1355931Y1323550I0J3468D01*
G03X1355799I-66J-189D01*
G02X1354650Y1323354I-1149J3272D01*
G02Y1330290I0J3468D01*
G02X1355799Y1330094I0J-3468D01*
G03X1355931I66J189D01*
G02X1357080Y1330290I1149J-3272D01*
G02X1358229Y1330094I0J-3468D01*
G03X1358361I66J189D01*
G02X1358772Y1330210I1146J-3273D01*
G01Y1330257D01*
G02X1359052Y1331629I3502J0D01*
G03Y1331785I-184J78D01*
G02X1358772Y1333157I3222J1372D01*
G02X1359052Y1334529I3502J0D01*
G03Y1334685I-184J78D01*
G02X1358772Y1336056I3222J1372D01*
G01Y1336057D01*
G02X1361459Y1339463I3502J0D01*
G37*
G36*
G01X385890Y1339537D02*
G02X388771Y1341048I2881J-1991D01*
G01X388773D01*
G02X392274Y1337546I-1J-3502D01*
G02X391973Y1336127I-3503J2D01*
G03Y1335965I183J-81D01*
G02X392274Y1334546I-3202J-1421D01*
G02X391711Y1332643I-3503J1D01*
G03X391686Y1332481I168J-109D01*
G02X391814Y1331546I-3375J-938D01*
G02X391464Y1330021I-3503J1D01*
G03X391459Y1329859I180J-87D01*
G02X391714Y1328548I-3248J-1312D01*
G01Y1328546D01*
G02X388300Y1325045I-3502J0D01*
G01X388298D01*
G03X388152Y1324974I7J-200D01*
G01X387930Y1324713D01*
X387907Y1324630D01*
X387913Y1324588D01*
G02X387948Y1324092I-3432J-491D01*
G02X387666Y1322721I-3467J-1D01*
G03Y1322563I184J-79D01*
G02X387948Y1321195I-3185J-1370D01*
G01Y1321192D01*
G02X381014I-3467J0D01*
G01Y1321195D01*
G02X381296Y1322563I3467J-2D01*
G03Y1322721I-184J79D01*
G02X381088Y1323376I3185J1372D01*
G02X380952Y1323374I-119J3465D01*
G01X380950D01*
G02X379802Y1323569I-2J3467D01*
G03X379670I-66J-189D01*
G02X378525Y1323374I-1146J3272D01*
G01X378521D01*
G02Y1330308I0J3467D01*
G01X378525D01*
G02X379670Y1330113I-1J-3467D01*
G03X379802I66J189D01*
G02X380951Y1330308I1146J-3272D01*
G02X382100Y1330113I3J-3467D01*
G03X382232I66J189D01*
G02X382643Y1330229I1146J-3273D01*
G02X382642Y1330274I3501J100D01*
G01Y1330278D01*
G02X382922Y1331648I3503J-2D01*
G03Y1331804I-184J78D01*
G02X382642Y1333176I3223J1372D01*
G02X383188Y1335053I3503J-1D01*
G03X383213Y1335208I-169J107D01*
G02X383108Y1336056I3398J851D01*
G02X385773Y1339457I3503J0D01*
G03X385890Y1339537I-47J194D01*
G37*
G36*
G01X1391354Y1352488D02*
G02X1394856Y1355990I3502J0D01*
G01X1394857D01*
G02X1397027Y1355236I-1J-3502D01*
G03X1397258Y1355224I124J157D01*
G02X1399119Y1355760I1862J-2967D01*
G01X1399122D01*
G02X1402624Y1352258I0J-3502D01*
G01Y1352257D01*
G02X1402344Y1350886I-3502J1D01*
G03Y1350730I184J-78D01*
G02X1402624Y1349358I-3222J-1372D01*
G02X1402344Y1347986I-3502J0D01*
G03Y1347830I184J-78D01*
G02X1402624Y1346459I-3222J-1372D01*
G01Y1346458D01*
G02X1399122Y1342956I-3502J0D01*
G01X1399120D01*
G02X1397123Y1343582I1J3502D01*
G01X1397122D01*
G03X1397009Y1343618I-114J-164D01*
G01X1397008D01*
G03X1396808Y1343418I0J-200D01*
G01Y1343414D01*
G02X1396528Y1342043I-3502J1D01*
G03Y1341887I184J-78D01*
G02X1396808Y1340516I-3222J-1372D01*
G01Y1340515D01*
G02X1389804I-3502J0D01*
G01Y1340516D01*
G02X1390084Y1341887I3502J-1D01*
G03Y1342043I-184J78D01*
G02X1389916Y1342536I3222J1373D01*
G03X1389719Y1342686I-194J-50D01*
G01X1389662D01*
G02X1388513Y1342881I-3J3467D01*
G03X1388381I-66J-189D01*
G02X1387236Y1342686I-1146J3272D01*
G01X1387232D01*
G02Y1349620I0J3467D01*
G01X1387236D01*
G02X1388381Y1349425I-1J-3467D01*
G03X1388513I66J189D01*
G02X1389662Y1349620I1146J-3272D01*
G02X1390811Y1349425I3J-3467D01*
G03X1390943I66J189D01*
G02X1391354Y1349541I1146J-3273D01*
G01Y1349588D01*
G02X1391634Y1350960I3502J0D01*
G03Y1351116I-184J78D01*
G02X1391354Y1352487I3222J1372D01*
G01Y1352488D01*
G37*
G36*
G01X418121Y1355713D02*
G02X421315Y1357778I3194J-1438D01*
G01X421317D01*
G02X424818Y1354276I-1J-3502D01*
G02X424538Y1352904I-3503J0D01*
G03Y1352748I184J-78D01*
G02X424818Y1351376I-3223J-1372D01*
G01Y1351375D01*
G02X424505Y1349928I-3502J0D01*
G03X424499Y1349777I182J-83D01*
G02X424708Y1348586I-3294J-1192D01*
G02X424428Y1347214I-3503J0D01*
G03Y1347058I184J-78D01*
G02X424708Y1345686I-3223J-1372D01*
G02X421205Y1342184I-3503J1D01*
G01X421203D01*
G02X420507Y1342254I1J3502D01*
G03X420282Y1342132I-39J-196D01*
G02X420248Y1342052I-3208J1316D01*
G03Y1341894I184J-79D01*
G02X420530Y1340526I-3185J-1370D01*
G01Y1340523D01*
G02X413596I-3467J0D01*
G01Y1340526D01*
G02X413878Y1341894I3467J-2D01*
G03Y1342052I-184J79D01*
G02X413670Y1342707I3185J1372D01*
G02X413533Y1342704I-144J3465D01*
G02X412384Y1342900I0J3468D01*
G03X412252I-66J-189D01*
G02X411103Y1342704I-1149J3272D01*
G02Y1349640I0J3468D01*
G02X412252Y1349444I0J-3468D01*
G03X412384I66J189D01*
G02X413533Y1349640I1149J-3272D01*
G02X414682Y1349444I0J-3468D01*
G03X414814I66J189D01*
G02X415052Y1349518I1148J-3272D01*
G03X415198Y1349687I-53J193D01*
G02X415452Y1350638I3477J-419D01*
G03Y1350794I-184J78D01*
G02X415172Y1352166I3223J1372D01*
G02X417978Y1355599I3503J0D01*
G03X418121Y1355713I-39J196D01*
G37*
G36*
G01X791071Y1363081D02*
G02X790770Y1364500I3202J1421D01*
G02X797776I3503J0D01*
G02X797475Y1363081I-3503J2D01*
G03Y1362919I183J-81D01*
G02X797776Y1361500I-3202J-1421D01*
G02X797250Y1359655I-3503J1D01*
G03Y1359445I170J-105D01*
G02X797776Y1357600I-2977J-1846D01*
G02X797475Y1356181I-3503J2D01*
G03Y1356019I183J-81D01*
G02X797776Y1354600I-3202J-1421D01*
G02X790770I-3503J0D01*
G02X791071Y1356019I3503J-2D01*
G03Y1356181I-183J81D01*
G02X790770Y1357600I3202J1421D01*
G02X791296Y1359445I3503J-1D01*
G03Y1359655I-170J105D01*
G02X790770Y1361500I2977J1846D01*
G02X791071Y1362919I3503J-2D01*
G03Y1363081I-183J81D01*
G37*
G36*
G01X363406Y1368021D02*
G03X363540I67J188D01*
G02X364723Y1368226I1181J-3297D01*
G02X368226Y1364724I1J-3502D01*
G02X367918Y1363289I-3503J1D01*
G03X367910Y1363146I183J-82D01*
G02X368074Y1362085I-3338J-1059D01*
G02X367898Y1360988I-3502J-1D01*
G03X367909Y1360838I190J-61D01*
G02X368266Y1359298I-3145J-1541D01*
G01Y1359296D01*
G02X364764Y1355794I-3502J0D01*
G01X364761D01*
G02X363581Y1355999I1J3502D01*
G03X363447I-67J-188D01*
G02X362264Y1355794I-1181J3297D01*
G02X361081Y1355999I-2J3502D01*
G03X360947I-67J-188D01*
G02X359764Y1355794I-1181J3297D01*
G02X358345Y1356094I-1J3502D01*
G03X358183I-81J-183D01*
G02X356764Y1355794I-1418J3202D01*
G02X355581Y1355999I-2J3502D01*
G03X355447I-67J-188D01*
G02X354269Y1355794I-1181J3297D01*
G01X354264D01*
G02X353135Y1355981I0J3502D01*
G03X352993Y1355976I-64J-190D01*
G02X351632Y1355700I-1363J3227D01*
G02X348130Y1359203I1J3503D01*
G01Y1359206D01*
G02X348476Y1360723I3502J-1D01*
G03X348484Y1360878I-180J87D01*
G02X348270Y1362085I3288J1205D01*
G02X348577Y1363520I3502J1D01*
G03X348585Y1363663I-183J82D01*
G02X348420Y1364724I3338J1062D01*
G02X351923Y1368226I3503J-1D01*
G01X351926D01*
G02X353106Y1368021I-1J-3502D01*
G03X353240I67J188D01*
G02X354423Y1368226I1181J-3297D01*
G02X355606Y1368021I2J-3502D01*
G03X355740I67J188D01*
G02X356923Y1368226I1181J-3297D01*
G02X358106Y1368021I2J-3502D01*
G03X358240I67J188D01*
G02X359423Y1368226I1181J-3297D01*
G02X360747Y1367967I2J-3502D01*
G03X360899I76J185D01*
G02X362223Y1368226I1322J-3243D01*
G02X363406Y1368021I2J-3502D01*
G37*
G36*
G01X330686Y1378896D02*
Y1378897D01*
G02X337692I3503J0D01*
G01Y1378896D01*
G02X337434Y1377577I-3503J0D01*
G03Y1377427I185J-75D01*
G02X337692Y1376108I-3245J-1319D01*
G02X337384Y1374673I-3503J1D01*
G03X337376Y1374530I183J-82D01*
G02X337540Y1373469I-3338J-1059D01*
G02X337364Y1372372I-3502J-1D01*
G03X337375Y1372222I190J-61D01*
G02X337732Y1370682I-3145J-1541D01*
G01Y1370680D01*
G02X330728I-3502J0D01*
G01Y1370684D01*
G02X330904Y1371777I3502J-3D01*
G03X330893Y1371927I-190J61D01*
G02X330536Y1373469I3145J1541D01*
G02X330843Y1374904I3502J1D01*
G03X330851Y1375047I-183J82D01*
G02X330686Y1376108I3338J1062D01*
G02X330944Y1377427I3503J0D01*
G03Y1377577I-185J75D01*
G02X330686Y1378896I3245J1319D01*
G37*
G36*
G01X1091180Y1379188D02*
G02X1094683Y1382690I3503J-1D01*
G01X1094684D01*
G02X1096854Y1381936I-1J-3502D01*
G03X1097085Y1381924I124J157D01*
G02X1098949Y1382460I1862J-2967D01*
G02X1102452Y1378958I1J-3502D01*
G02X1102172Y1377586I-3503J0D01*
G03Y1377430I184J-78D01*
G02X1102452Y1376058I-3223J-1372D01*
G02X1102172Y1374686I-3503J0D01*
G03Y1374530I184J-78D01*
G02X1102452Y1373158I-3223J-1372D01*
G02X1098949Y1369656I-3503J1D01*
G01X1098947D01*
G02X1097004Y1370245I1J3502D01*
G01X1096960Y1370274D01*
X1096853Y1370282D01*
X1096494Y1370105D01*
G03X1096383Y1369939I89J-179D01*
G02X1096111Y1368806I-3494J240D01*
G03X1096112Y1368650I185J-77D01*
G02X1096392Y1367278I-3223J-1372D01*
G02X1089386I-3503J0D01*
G02X1089666Y1368650I3503J0D01*
G03Y1368806I-184J78D01*
G02X1089513Y1369243I3222J1373D01*
G03X1089330Y1369390I-193J-53D01*
G02X1088340Y1369581I155J3464D01*
G03X1088208I-66J-189D01*
G02X1087063Y1369386I-1146J3272D01*
G01X1087059D01*
G02Y1376320I0J3467D01*
G01X1087063D01*
G02X1088208Y1376125I-1J-3467D01*
G03X1088340I66J189D01*
G02X1089489Y1376320I1146J-3272D01*
G02X1090638Y1376125I3J-3467D01*
G03X1090770I66J189D01*
G02X1091181Y1376241I1146J-3273D01*
G02X1091180Y1376286I3501J100D01*
G01Y1376290D01*
G02X1091460Y1377660I3503J-2D01*
G03Y1377816I-184J78D01*
G02X1091180Y1379188I3223J1372D01*
G37*
G36*
G01X1123780D02*
G02X1127283Y1382690I3503J-1D01*
G01X1127284D01*
G02X1129454Y1381936I-1J-3502D01*
G03X1129685Y1381924I124J157D01*
G02X1131549Y1382460I1862J-2967D01*
G02X1135052Y1378958I1J-3502D01*
G02X1134772Y1377586I-3503J0D01*
G03Y1377430I184J-78D01*
G02X1135052Y1376058I-3223J-1372D01*
G02X1134772Y1374686I-3503J0D01*
G03Y1374530I184J-78D01*
G02X1135052Y1373158I-3223J-1372D01*
G02X1131549Y1369656I-3503J1D01*
G01X1131548D01*
G02X1129594Y1370252I0J3502D01*
G01X1129593Y1370253D01*
G03X1129390Y1370264I-111J-167D01*
G01X1129030Y1370077D01*
X1128972Y1369984D01*
X1128971Y1369929D01*
G02X1128692Y1368636I-3502J79D01*
G03Y1368480I184J-78D01*
G02X1128972Y1367108I-3223J-1372D01*
G02X1121966I-3503J0D01*
G02X1122246Y1368480I3503J0D01*
G03Y1368636I-184J78D01*
G02X1122052Y1369237I3223J1372D01*
G03X1121870Y1369392I-195J-44D01*
G02X1120940Y1369581I219J3461D01*
G03X1120808I-66J-189D01*
G02X1119663Y1369386I-1146J3272D01*
G01X1119659D01*
G02Y1376320I0J3467D01*
G01X1119663D01*
G02X1120808Y1376125I-1J-3467D01*
G03X1120940I66J189D01*
G02X1122089Y1376320I1146J-3272D01*
G02X1123238Y1376125I3J-3467D01*
G03X1123370I66J189D01*
G02X1123781Y1376241I1146J-3273D01*
G02X1123780Y1376286I3501J100D01*
G01Y1376290D01*
G02X1124060Y1377660I3503J-2D01*
G03Y1377816I-184J78D01*
G02X1123780Y1379188I3223J1372D01*
G37*
G36*
G01X1156480D02*
G02X1159983Y1382690I3503J-1D01*
G01X1159984D01*
G02X1162154Y1381936I-1J-3502D01*
G03X1162385Y1381924I124J157D01*
G02X1164249Y1382460I1862J-2967D01*
G02X1167752Y1378958I1J-3502D01*
G02X1167472Y1377586I-3503J0D01*
G03Y1377430I184J-78D01*
G02X1167752Y1376058I-3223J-1372D01*
G02X1167472Y1374686I-3503J0D01*
G03Y1374530I184J-78D01*
G02X1167752Y1373158I-3223J-1372D01*
G02X1164249Y1369656I-3503J1D01*
G01X1164247D01*
G02X1162195Y1370321I1J3502D01*
G01X1162149Y1370354D01*
X1162036Y1370362D01*
X1161617Y1370144D01*
X1161560Y1370046D01*
X1161561Y1369989D01*
G02X1161562Y1369918I-3502J-85D01*
G02X1161282Y1368546I-3503J0D01*
G03Y1368390I184J-78D01*
G02X1161562Y1367018I-3223J-1372D01*
G02X1154556I-3503J0D01*
G02X1154836Y1368390I3503J0D01*
G03Y1368546I-184J78D01*
G02X1154622Y1369242I3223J1372D01*
G03X1154446Y1369403I-196J-38D01*
G02X1153640Y1369581I339J3451D01*
G03X1153508I-66J-189D01*
G02X1152363Y1369386I-1146J3272D01*
G01X1152359D01*
G02Y1376320I0J3467D01*
G01X1152363D01*
G02X1153508Y1376125I-1J-3467D01*
G03X1153640I66J189D01*
G02X1154789Y1376320I1146J-3272D01*
G02X1155938Y1376125I3J-3467D01*
G03X1156070I66J189D01*
G02X1156481Y1376241I1146J-3273D01*
G02X1156480Y1376286I3501J100D01*
G01Y1376290D01*
G02X1156760Y1377660I3503J-2D01*
G03Y1377816I-184J78D01*
G02X1156480Y1379188I3223J1372D01*
G37*
G36*
G01X1189380D02*
G02X1192883Y1382690I3503J-1D01*
G01X1192884D01*
G02X1195054Y1381936I-1J-3502D01*
G03X1195285Y1381924I124J157D01*
G02X1197149Y1382460I1862J-2967D01*
G02X1200652Y1378958I1J-3502D01*
G02X1200372Y1377586I-3503J0D01*
G03Y1377430I184J-78D01*
G02X1200652Y1376058I-3223J-1372D01*
G02X1200372Y1374686I-3503J0D01*
G03Y1374530I184J-78D01*
G02X1200652Y1373158I-3223J-1372D01*
G02X1197149Y1369656I-3503J1D01*
G01X1197146D01*
G02X1195174Y1370265I2J3502D01*
G01X1195129Y1370296D01*
X1195021Y1370304D01*
X1194609Y1370097D01*
X1194551Y1370006D01*
X1194549Y1369951D01*
G02X1194272Y1368716I-3500J136D01*
G03Y1368560I184J-78D01*
G02X1194552Y1367188I-3223J-1372D01*
G02X1187546I-3503J0D01*
G02X1187826Y1368560I3503J0D01*
G03X1187827Y1368716I-184J79D01*
G02X1187651Y1369241I3222J1372D01*
G03X1187469Y1369392I-194J-49D01*
G02X1186540Y1369581I220J3461D01*
G03X1186408I-66J-189D01*
G02X1185263Y1369386I-1146J3272D01*
G01X1185259D01*
G02Y1376320I0J3467D01*
G01X1185263D01*
G02X1186408Y1376125I-1J-3467D01*
G03X1186540I66J189D01*
G02X1187689Y1376320I1146J-3272D01*
G02X1188838Y1376125I3J-3467D01*
G03X1188970I66J189D01*
G02X1189381Y1376241I1146J-3273D01*
G02X1189380Y1376286I3501J100D01*
G01Y1376290D01*
G02X1189660Y1377660I3503J-2D01*
G03Y1377816I-184J78D01*
G02X1189380Y1379188I3223J1372D01*
G37*
G36*
G01X1222180D02*
G02X1225683Y1382690I3503J-1D01*
G01X1225684D01*
G02X1227854Y1381936I-1J-3502D01*
G03X1228085Y1381924I124J157D01*
G02X1229949Y1382460I1862J-2967D01*
G02X1233452Y1378958I1J-3502D01*
G02X1233172Y1377586I-3503J0D01*
G03Y1377430I184J-78D01*
G02X1233452Y1376058I-3223J-1372D01*
G02X1233172Y1374686I-3503J0D01*
G03Y1374530I184J-78D01*
G02X1233452Y1373158I-3223J-1372D01*
G02X1229949Y1369656I-3503J1D01*
G01X1229948D01*
G02X1228009Y1370242I0J3502D01*
G01X1227964Y1370272D01*
X1227857Y1370279D01*
X1227497Y1370097D01*
G03X1227388Y1369927I91J-178D01*
G02X1227112Y1368716I-3499J161D01*
G03Y1368560I184J-78D01*
G02X1227392Y1367188I-3223J-1372D01*
G02X1220386I-3503J0D01*
G02X1220666Y1368560I3503J0D01*
G03X1220667Y1368716I-184J79D01*
G02X1220491Y1369239I3221J1375D01*
G03X1220308Y1369391I-194J-48D01*
G02X1219340Y1369581I177J3463D01*
G03X1219208I-66J-189D01*
G02X1218063Y1369386I-1146J3272D01*
G01X1218059D01*
G02Y1376320I0J3467D01*
G01X1218063D01*
G02X1219208Y1376125I-1J-3467D01*
G03X1219340I66J189D01*
G02X1220489Y1376320I1146J-3272D01*
G02X1221638Y1376125I3J-3467D01*
G03X1221770I66J189D01*
G02X1222181Y1376241I1146J-3273D01*
G02X1222180Y1376286I3501J100D01*
G01Y1376290D01*
G02X1222460Y1377660I3503J-2D01*
G03Y1377816I-184J78D01*
G02X1222180Y1379188I3223J1372D01*
G37*
G36*
G01X119722Y1377835D02*
G02X119442Y1379207I3223J1372D01*
G02X122945Y1382710I3503J0D01*
G02X125116Y1381955I-1J-3503D01*
G03X125347Y1381943I124J157D01*
G02X127211Y1382480I1864J-2967D01*
G02X130714Y1378977I0J-3503D01*
G02X130434Y1377605I-3503J0D01*
G03Y1377449I184J-78D01*
G02X130714Y1376077I-3223J-1372D01*
G02X130434Y1374705I-3503J0D01*
G03Y1374549I184J-78D01*
G02X130714Y1373177I-3223J-1372D01*
G02X127211Y1369674I-3503J0D01*
G02X125355Y1370207I1J3503D01*
G03X125153Y1370213I-106J-169D01*
G01X124800Y1370022D01*
X124744Y1369930D01*
X124743Y1369876D01*
G02X124464Y1368575I-3502J71D01*
G03Y1368419I184J-78D01*
G02X124744Y1367047I-3223J-1372D01*
G02X122784Y1363903I-3502J0D01*
G03X122672Y1363714I88J-180D01*
G02X122674Y1363643I-1465J-77D01*
G02X119740I-1467J0D01*
G02X119743Y1363743I1467J6D01*
G03X119635Y1363934I-199J13D01*
G02X117738Y1367047I1606J3113D01*
G02X118018Y1368419I3503J0D01*
G03X118019Y1368575I-184J79D01*
G02X117781Y1369405I3222J1373D01*
G02X117754Y1369404I-142J3463D01*
G01X117748D01*
G02X116602Y1369600I3J3468D01*
G03X116470I-66J-189D01*
G02X115321Y1369404I-1149J3272D01*
G02Y1376340I0J3468D01*
G02X116470Y1376144I0J-3468D01*
G03X116602I66J189D01*
G02X117751Y1376340I1149J-3272D01*
G02X118900Y1376144I0J-3468D01*
G03X119032I66J189D01*
G02X119443Y1376260I1146J-3273D01*
G02X119442Y1376305I3501J100D01*
G01Y1376309D01*
G02X119722Y1377679I3503J-2D01*
G03Y1377835I-184J78D01*
G37*
G36*
G01X152322D02*
G02X152042Y1379207I3223J1372D01*
G02X155545Y1382710I3503J0D01*
G02X157716Y1381955I-1J-3503D01*
G03X157947Y1381943I124J157D01*
G02X159811Y1382480I1864J-2967D01*
G02X163314Y1378977I0J-3503D01*
G02X163034Y1377605I-3503J0D01*
G03Y1377449I184J-78D01*
G02X163314Y1376077I-3223J-1372D01*
G02X163034Y1374705I-3503J0D01*
G03Y1374549I184J-78D01*
G02X163314Y1373177I-3223J-1372D01*
G02X159811Y1369674I-3503J0D01*
G02X157865Y1370265I1J3503D01*
G01X157819Y1370295D01*
X157709Y1370301D01*
X157350Y1370111D01*
G03X157243Y1369938I93J-177D01*
G01Y1369937D01*
G02X156963Y1368605I-3502J41D01*
G03X156964Y1368449I185J-77D01*
G02X157244Y1367077I-3223J-1372D01*
G02X150238I-3503J0D01*
G02X150518Y1368449I3503J0D01*
G03X150519Y1368605I-184J79D01*
G02X150315Y1369253I3223J1371D01*
G03X150132Y1369411I-196J-42D01*
G02X149202Y1369600I219J3461D01*
G03X149070I-66J-189D01*
G02X147921Y1369404I-1149J3272D01*
G02Y1376340I0J3468D01*
G02X149070Y1376144I0J-3468D01*
G03X149202I66J189D01*
G02X150351Y1376340I1149J-3272D01*
G02X151500Y1376144I0J-3468D01*
G03X151632I66J189D01*
G02X152043Y1376260I1146J-3273D01*
G02X152042Y1376305I3501J100D01*
G01Y1376309D01*
G02X152322Y1377679I3503J-2D01*
G03Y1377835I-184J78D01*
G37*
G36*
G01X185022D02*
G02X184742Y1379207I3223J1372D01*
G02X188245Y1382710I3503J0D01*
G02X190416Y1381955I-1J-3503D01*
G03X190647Y1381943I124J157D01*
G02X192511Y1382480I1864J-2967D01*
G02X196014Y1378977I0J-3503D01*
G02X195734Y1377605I-3503J0D01*
G03Y1377449I184J-78D01*
G02X196014Y1376077I-3223J-1372D01*
G02X195734Y1374705I-3503J0D01*
G03Y1374549I184J-78D01*
G02X196014Y1373177I-3223J-1372D01*
G02X192511Y1369674I-3503J0D01*
G02X190595Y1370245I1J3503D01*
G01X190550Y1370275D01*
X190445Y1370281D01*
X190087Y1370101D01*
G03X189977Y1369934I90J-179D01*
G02X189704Y1368775I-3496J212D01*
G03Y1368619I184J-78D01*
G02X189984Y1367247I-3223J-1372D01*
G02X182978I-3503J0D01*
G02X183258Y1368619I3503J0D01*
G03Y1368775I-184J78D01*
G02X183058Y1369405I3224J1370D01*
G02X183051Y1369404I-489J3398D01*
G02X181902Y1369600I0J3468D01*
G03X181770I-66J-189D01*
G02X180621Y1369404I-1149J3272D01*
G02Y1376340I0J3468D01*
G02X181770Y1376144I0J-3468D01*
G03X181902I66J189D01*
G02X183051Y1376340I1149J-3272D01*
G02X184200Y1376144I0J-3468D01*
G03X184332I66J189D01*
G02X184743Y1376260I1146J-3273D01*
G02X184742Y1376305I3501J100D01*
G01Y1376309D01*
G02X185022Y1377679I3503J-2D01*
G03Y1377835I-184J78D01*
G37*
G36*
G01X217922D02*
G02X217642Y1379207I3223J1372D01*
G02X221145Y1382710I3503J0D01*
G02X223316Y1381955I-1J-3503D01*
G03X223547Y1381943I124J157D01*
G02X225411Y1382480I1864J-2967D01*
G02X228914Y1378977I0J-3503D01*
G02X228634Y1377605I-3503J0D01*
G03Y1377449I184J-78D01*
G02X228914Y1376077I-3223J-1372D01*
G02X228634Y1374705I-3503J0D01*
G03Y1374549I184J-78D01*
G02X228914Y1373177I-3223J-1372D01*
G02X225411Y1369674I-3503J0D01*
G02X223516Y1370231I0J3502D01*
G01X223471Y1370260D01*
X223364Y1370266D01*
X222960Y1370056D01*
X222902Y1369966D01*
X222900Y1369913D01*
G02X222624Y1368695I-3499J153D01*
G03Y1368539I184J-78D01*
G02X222904Y1367167I-3223J-1372D01*
G02X215898I-3503J0D01*
G02X216178Y1368539I3503J0D01*
G03X216179Y1368695I-184J79D01*
G02X215962Y1369405I3222J1373D01*
G01X215960D01*
G02X215942Y1369404I-20J199D01*
G02X214802Y1369600I9J3468D01*
G03X214670I-66J-189D01*
G02X213521Y1369404I-1149J3272D01*
G02Y1376340I0J3468D01*
G02X214670Y1376144I0J-3468D01*
G03X214802I66J189D01*
G02X215951Y1376340I1149J-3272D01*
G02X217100Y1376144I0J-3468D01*
G03X217232I66J189D01*
G02X217643Y1376260I1146J-3273D01*
G02X217642Y1376305I3501J100D01*
G01Y1376309D01*
G02X217922Y1377679I3503J-2D01*
G03Y1377835I-184J78D01*
G37*
G36*
G01X250722D02*
G02X250442Y1379207I3223J1372D01*
G02X253945Y1382710I3503J0D01*
G02X256116Y1381955I-1J-3503D01*
G03X256347Y1381943I124J157D01*
G02X258211Y1382480I1864J-2967D01*
G02X261714Y1378977I0J-3503D01*
G02X261434Y1377605I-3503J0D01*
G03Y1377449I184J-78D01*
G02X261714Y1376077I-3223J-1372D01*
G02X261434Y1374705I-3503J0D01*
G03Y1374549I184J-78D01*
G02X261714Y1373177I-3223J-1372D01*
G02X258211Y1369674I-3503J0D01*
G02X256286Y1370251I1J3503D01*
G01X256285Y1370252D01*
G03X256088Y1370264I-109J-168D01*
G01X255731Y1370090D01*
X255671Y1370002D01*
X255667Y1369950D01*
G02X255396Y1368861I-3456J282D01*
G03Y1368703I184J-79D01*
G02X255678Y1367335I-3185J-1370D01*
G01Y1367332D01*
G02X248744I-3467J0D01*
G01Y1367335D01*
G02X249026Y1368703I3467J-2D01*
G03Y1368861I-184J79D01*
G02X248843Y1369406I3184J1372D01*
G02X248752Y1369404I-122J3465D01*
G01X248750D01*
G02X247602Y1369600I1J3468D01*
G03X247470I-66J-189D01*
G02X246321Y1369404I-1149J3272D01*
G02Y1376340I0J3468D01*
G02X247470Y1376144I0J-3468D01*
G03X247602I66J189D01*
G02X248751Y1376340I1149J-3272D01*
G02X249900Y1376144I0J-3468D01*
G03X250032I66J189D01*
G02X250443Y1376260I1146J-3273D01*
G02X250442Y1376305I3501J100D01*
G01Y1376309D01*
G02X250722Y1377679I3503J-2D01*
G03Y1377835I-184J78D01*
G37*
G36*
G01X320560Y1377966D02*
G02X320206Y1379500I3149J1535D01*
G02X327212I3503J0D01*
G01Y1379499D01*
G02X326859Y1377967I-3504J1D01*
G03Y1377793I180J-87D01*
G02X327212Y1376259I-3149J-1532D01*
G02X326905Y1374824I-3502J-1D01*
G03X326897Y1374681I183J-82D01*
G02X327062Y1373620I-3338J-1062D01*
G02X326886Y1372524I-3503J0D01*
G03X326896Y1372373I190J-63D01*
G02X327254Y1370831I-3145J-1543D01*
G02X320248I-3503J0D01*
G02X320424Y1371927I3503J0D01*
G03X320414Y1372078I-190J63D01*
G02X320056Y1373620I3145J1543D01*
G02X320364Y1375055I3503J-1D01*
G03X320372Y1375198I-183J82D01*
G02X320208Y1376259I3338J1059D01*
G02X320560Y1377791I3502J2D01*
G03Y1377966I-180J88D01*
G37*
G36*
G01X301918Y1388359D02*
G02X301660Y1389678I3245J1319D01*
G02X308666I3503J0D01*
G02X308408Y1388359I-3503J0D01*
G03Y1388209I185J-75D01*
G02X308666Y1386890I-3245J-1319D01*
G01Y1386889D01*
G02X308358Y1385454I-3503J1D01*
G03X308350Y1385311I183J-82D01*
G02X308514Y1384250I-3338J-1059D01*
G02X308338Y1383153I-3502J-1D01*
G03X308349Y1383003I190J-61D01*
G02X308706Y1381463I-3145J-1541D01*
G01Y1381461D01*
G02X301702I-3502J0D01*
G01Y1381465D01*
G02X301878Y1382558I3502J-3D01*
G03X301867Y1382708I-190J61D01*
G02X301510Y1384250I3145J1541D01*
G02X301817Y1385685I3502J1D01*
G03X301825Y1385828I-183J82D01*
G02X301660Y1386889I3338J1062D01*
G01Y1386890D01*
G02X301918Y1388209I3503J0D01*
G03Y1388359I-185J75D01*
G37*
G36*
G01X1345029Y1393101D02*
G02X1346212Y1393306I1181J-3297D01*
G02X1347395Y1393101I2J-3502D01*
G03X1347529I67J188D01*
G02X1348707Y1393306I1181J-3297D01*
G01X1348712D01*
G02X1350387Y1392879I-1J-3502D01*
G03X1350577I95J176D01*
G02X1352225Y1393290I1646J-3091D01*
G02X1355728Y1389788I1J-3502D01*
G02X1355431Y1388378I-3503J2D01*
G03Y1388216I183J-81D01*
G02X1355728Y1386804I-3205J-1411D01*
G02X1355428Y1385385I-3502J-1D01*
G03Y1385223I183J-81D01*
G02X1355728Y1383806I-3202J-1418D01*
G01Y1383804D01*
G02X1352226Y1380302I-3502J0D01*
G01X1352221D01*
G02X1351121Y1380480I2J3502D01*
G03X1350977Y1380473I-63J-190D01*
G02X1349557Y1380172I-1420J3201D01*
G01X1349555D01*
G02X1348137Y1380472I0J3502D01*
G03X1347975I-81J-183D01*
G02X1346557Y1380172I-1418J3202D01*
G01X1346555D01*
G02X1345137Y1380472I0J3502D01*
G03X1344975I-81J-183D01*
G02X1343557Y1380172I-1418J3202D01*
G01X1343555D01*
G02X1342137Y1380472I0J3502D01*
G03X1341975I-81J-183D01*
G02X1340557Y1380172I-1418J3202D01*
G01X1340555D01*
G02X1339137Y1380472I0J3502D01*
G03X1338975I-81J-183D01*
G02X1337558Y1380172I-1418J3202D01*
G01X1337556D01*
G02X1334054Y1383674I0J3502D01*
G01Y1383676D01*
G02X1334354Y1385093I3502J-1D01*
G03Y1385255I-183J81D01*
G02X1334054Y1386674I3202J1418D01*
G02X1334350Y1388084I3502J1D01*
G03Y1388246I-183J81D01*
G02X1334052Y1389658I3205J1414D01*
G02X1337555Y1393160I3503J-1D01*
G01X1337556D01*
G02X1339163Y1392769I-1J-3502D01*
G03X1339360Y1392777I91J178D01*
G02X1341212Y1393306I1851J-2973D01*
G02X1342395Y1393101I2J-3502D01*
G03X1342529I67J188D01*
G02X1343712Y1393306I1181J-3297D01*
G02X1344895Y1393101I2J-3502D01*
G03X1345029I67J188D01*
G37*
G36*
G01X291534Y1388747D02*
G02X291180Y1390281I3149J1535D01*
G02X298186I3503J0D01*
G01Y1390280D01*
G02X297833Y1388748I-3504J1D01*
G03Y1388574I180J-87D01*
G02X298186Y1387040I-3149J-1532D01*
G02X297879Y1385605I-3502J-1D01*
G03X297871Y1385462I183J-82D01*
G02X298036Y1384401I-3338J-1062D01*
G02X297860Y1383305I-3503J0D01*
G03X297870Y1383154I190J-63D01*
G02X298228Y1381612I-3145J-1543D01*
G02X291222I-3503J0D01*
G02X291398Y1382708I3503J0D01*
G03X291388Y1382859I-190J63D01*
G02X291030Y1384401I3145J1543D01*
G02X291338Y1385836I3503J-1D01*
G03X291346Y1385979I-183J82D01*
G02X291182Y1387040I3338J1059D01*
G02X291534Y1388572I3502J2D01*
G03Y1388747I-180J88D01*
G37*
G36*
G01X1674732Y1396505D02*
Y1396507D01*
G02X1678234Y1400008I3502J-1D01*
G02X1680405Y1399253I-1J-3503D01*
G03X1680636Y1399241I124J157D01*
G02X1682500Y1399778I1864J-2967D01*
G02X1686002Y1396275I-1J-3503D01*
G01Y1396274D01*
G02X1685722Y1394903I-3502J1D01*
G03Y1394747I184J-78D01*
G02X1686002Y1393375I-3222J-1372D01*
G02X1685722Y1392003I-3502J0D01*
G03Y1391847I184J-78D01*
G02X1686002Y1390475I-3222J-1372D01*
G01Y1390473D01*
G02X1682500Y1386972I-3502J1D01*
G02X1679699Y1388372I0J3502D01*
G03X1679581Y1388447I-159J-121D01*
G02X1679532Y1388458I743J3423D01*
G01X1679373Y1388289D01*
G03X1679325Y1388102I146J-137D01*
G02X1679434Y1387235I-3394J-867D01*
G02X1679154Y1385863I-3503J0D01*
G03Y1385707I184J-78D01*
G02X1679434Y1384335I-3223J-1372D01*
G02X1672428I-3503J0D01*
G02X1672708Y1385707I3503J0D01*
G03Y1385863I-184J78D01*
G02X1672484Y1386616I3224J1369D01*
G03X1672328Y1386776I-197J-36D01*
G02X1671891Y1386898I712J3394D01*
G03X1671759I-66J-189D01*
G02X1670610Y1386702I-1149J3272D01*
G02Y1393638I0J3468D01*
G02X1671759Y1393442I0J-3468D01*
G03X1671891I66J189D01*
G02X1673040Y1393638I1149J-3272D01*
G02X1674189Y1393442I0J-3468D01*
G03X1674321I66J189D01*
G02X1674732Y1393558I1146J-3273D01*
G01Y1393605D01*
G02X1675012Y1394977I3502J0D01*
G03Y1395133I-184J78D01*
G02X1674732Y1396505I3222J1372D01*
G37*
G36*
G01X1707514Y1396605D02*
Y1396607D01*
G02X1711016Y1400108I3502J-1D01*
G02X1713187Y1399353I-1J-3503D01*
G03X1713418Y1399341I124J157D01*
G02X1715282Y1399878I1864J-2967D01*
G02X1718784Y1396375I-1J-3503D01*
G01Y1396374D01*
G02X1718504Y1395003I-3502J1D01*
G03Y1394847I184J-78D01*
G02X1718784Y1393475I-3222J-1372D01*
G02X1718504Y1392103I-3502J0D01*
G03Y1391947I184J-78D01*
G02X1718784Y1390575I-3222J-1372D01*
G01Y1390573D01*
G02X1715282Y1387072I-3502J1D01*
G02X1712481Y1388472I0J3502D01*
G03X1712363Y1388547I-159J-121D01*
G02X1712314Y1388558I743J3423D01*
G01X1712155Y1388389D01*
G03X1712107Y1388202I146J-137D01*
G02X1712216Y1387335I-3394J-867D01*
G02X1711936Y1385963I-3503J0D01*
G03Y1385807I184J-78D01*
G02X1712216Y1384435I-3223J-1372D01*
G02X1705210I-3503J0D01*
G02X1705490Y1385807I3503J0D01*
G03Y1385963I-184J78D01*
G02X1705266Y1386716I3224J1369D01*
G03X1705110Y1386876I-197J-36D01*
G02X1704673Y1386998I712J3394D01*
G03X1704541I-66J-189D01*
G02X1703392Y1386802I-1149J3272D01*
G02Y1393738I0J3468D01*
G02X1704541Y1393542I0J-3468D01*
G03X1704673I66J189D01*
G02X1705822Y1393738I1149J-3272D01*
G02X1706971Y1393542I0J-3468D01*
G03X1707103I66J189D01*
G02X1707514Y1393658I1146J-3273D01*
G01Y1393705D01*
G02X1707794Y1395077I3502J0D01*
G03Y1395233I-184J78D01*
G02X1707514Y1396605I3222J1372D01*
G37*
G36*
G01X726998Y1397216D02*
G02X730501Y1400718I3503J-1D01*
G01X730502D01*
G02X732672Y1399964I-1J-3502D01*
G03X732903Y1399952I124J157D01*
G02X734767Y1400488I1862J-2967D01*
G02X738270Y1396986I1J-3502D01*
G02X737990Y1395614I-3503J0D01*
G03Y1395458I184J-78D01*
G02X738270Y1394086I-3223J-1372D01*
G02X737990Y1392714I-3503J0D01*
G03Y1392558I184J-78D01*
G02X738270Y1391186I-3223J-1372D01*
G02X734767Y1387684I-3503J1D01*
G02X731966Y1389083I0J3504D01*
G03X731849Y1389158I-160J-120D01*
G02X731821Y1389164I720J3428D01*
G01X731661Y1388997D01*
G03X731611Y1388814I145J-138D01*
G02X731700Y1388026I-3413J-785D01*
G02X731420Y1386654I-3502J0D01*
G03Y1386498I184J-78D01*
G02X731700Y1385127I-3222J-1372D01*
G01Y1385126D01*
G02X724696I-3502J0D01*
G01Y1385127D01*
G02X724976Y1386498I3502J-1D01*
G03Y1386654I-184J78D01*
G02X724766Y1387328I3222J1373D01*
G03X724610Y1387484I-196J-40D01*
G02X724158Y1387609I696J3397D01*
G03X724026I-66J-189D01*
G02X722881Y1387414I-1146J3272D01*
G01X722877D01*
G02Y1394348I0J3467D01*
G01X722881D01*
G02X724026Y1394153I-1J-3467D01*
G03X724158I66J189D01*
G02X725307Y1394348I1146J-3272D01*
G02X726456Y1394153I3J-3467D01*
G03X726588I66J189D01*
G02X726999Y1394269I1146J-3273D01*
G02X726998Y1394314I3501J100D01*
G01Y1394318D01*
G02X727278Y1395688I3503J-2D01*
G03Y1395844I-184J78D01*
G02X726998Y1397216I3223J1372D01*
G37*
G36*
G01X759780Y1397316D02*
G02X763283Y1400818I3503J-1D01*
G01X763284D01*
G02X765454Y1400064I-1J-3502D01*
G03X765685Y1400052I124J157D01*
G02X767549Y1400588I1862J-2967D01*
G02X771052Y1397086I1J-3502D01*
G02X770772Y1395714I-3503J0D01*
G03Y1395558I184J-78D01*
G02X771052Y1394186I-3223J-1372D01*
G02X770772Y1392814I-3503J0D01*
G03Y1392658I184J-78D01*
G02X771052Y1391286I-3223J-1372D01*
G02X767549Y1387784I-3503J1D01*
G02X764748Y1389183I0J3504D01*
G03X764631Y1389258I-160J-120D01*
G02X764581Y1389269I728J3426D01*
G01X764422Y1389099D01*
G03X764373Y1388913I145J-138D01*
G02X764482Y1388046I-3393J-867D01*
G02X764202Y1386674I-3502J0D01*
G03Y1386518I184J-78D01*
G02X764482Y1385147I-3222J-1372D01*
G01Y1385146D01*
G02X757478I-3502J0D01*
G01Y1385147D01*
G02X757758Y1386518I3502J-1D01*
G03X757757Y1386674I-185J77D01*
G02X757533Y1387427I3224J1369D01*
G03X757377Y1387587I-197J-36D01*
G02X756940Y1387709I712J3394D01*
G03X756808I-66J-189D01*
G02X755663Y1387514I-1146J3272D01*
G01X755659D01*
G02Y1394448I0J3467D01*
G01X755663D01*
G02X756808Y1394253I-1J-3467D01*
G03X756940I66J189D01*
G02X758089Y1394448I1146J-3272D01*
G02X759238Y1394253I3J-3467D01*
G03X759370I66J189D01*
G02X759781Y1394369I1146J-3273D01*
G02X759780Y1394414I3501J100D01*
G01Y1394418D01*
G02X760060Y1395788I3503J-2D01*
G03Y1395944I-184J78D01*
G02X759780Y1397316I3223J1372D01*
G37*
G36*
G01X1136147Y1407174D02*
G03X1136283I68J188D01*
G02X1137465Y1407380I1184J-3297D01*
G02X1140968Y1403877I0J-3503D01*
G02X1140762Y1402695I-3503J2D01*
G03Y1402559I188J-68D01*
G02X1140968Y1401377I-3297J-1184D01*
G02X1140718Y1400079I-3503J2D01*
G03X1140716Y1399936I186J-74D01*
G02X1140928Y1398737I-3291J-1200D01*
G02X1137425Y1395234I-3503J0D01*
G02X1136243Y1395440I2J3503D01*
G03X1136107I-68J-188D01*
G02X1134925Y1395234I-1184J3297D01*
G02X1133743Y1395440I2J3503D01*
G03X1133607I-68J-188D01*
G02X1132425Y1395234I-1184J3297D01*
G02X1131243Y1395440I2J3503D01*
G03X1131107I-68J-188D01*
G02X1129925Y1395234I-1184J3297D01*
G02X1128743Y1395440I2J3503D01*
G03X1128607I-68J-188D01*
G02X1127425Y1395234I-1184J3297D01*
G02X1123922Y1398737I0J3503D01*
G02X1124172Y1400035I3503J-2D01*
G03X1124174Y1400178I-186J74D01*
G02X1123962Y1401377I3291J1200D01*
G02X1124168Y1402559I3503J-2D01*
G03Y1402695I-188J68D01*
G02X1123962Y1403877I3297J1184D01*
G02X1127465Y1407380I3503J0D01*
G02X1128647Y1407174I-2J-3503D01*
G03X1128783I68J188D01*
G02X1129965Y1407380I1184J-3297D01*
G02X1131147Y1407174I-2J-3503D01*
G03X1131283I68J188D01*
G02X1132465Y1407380I1184J-3297D01*
G02X1133647Y1407174I-2J-3503D01*
G03X1133783I68J188D01*
G02X1134965Y1407380I1184J-3297D01*
G02X1136147Y1407174I-2J-3503D01*
G37*
G36*
G01X197990Y1413173D02*
G03X198124I67J188D01*
G02X199307Y1413378I1181J-3297D01*
G02X202810Y1409876I1J-3502D01*
G02X202672Y1408904I-3503J2D01*
G03X202683Y1408766I192J-54D01*
G02X202998Y1407315I-3188J-1452D01*
G01Y1407313D01*
G02X202792Y1406131I-3503J2D01*
G03Y1405995I188J-68D01*
G02X202998Y1404813I-3297J-1184D01*
G02X199495Y1401310I-3503J0D01*
G02X198313Y1401516I2J3503D01*
G03X198177I-68J-188D01*
G02X196995Y1401310I-1184J3297D01*
G02X195813Y1401516I2J3503D01*
G03X195677I-68J-188D01*
G02X194495Y1401310I-1184J3297D01*
G02X193313Y1401516I2J3503D01*
G03X193177I-68J-188D01*
G02X191995Y1401310I-1184J3297D01*
G02X190434Y1401678I2J3503D01*
G03X190256I-89J-179D01*
G02X188695Y1401310I-1563J3135D01*
G02X185192Y1404813I0J3503D01*
G02X185398Y1405995I3503J-2D01*
G03Y1406131I-188J68D01*
G02X185192Y1407313I3297J1184D01*
G02X185330Y1408285I3503J-2D01*
G03X185319Y1408423I-192J54D01*
G02X185004Y1409874I3188J1452D01*
G01Y1409876D01*
G02X188507Y1413378I3503J-1D01*
G02X190068Y1413011I0J-3503D01*
G03X190246I89J179D01*
G02X191807Y1413378I1561J-3136D01*
G01X191810D01*
G02X192990Y1413173I-1J-3502D01*
G03X193124I67J188D01*
G02X194307Y1413378I1181J-3297D01*
G02X195490Y1413173I2J-3502D01*
G03X195624I67J188D01*
G02X196807Y1413378I1181J-3297D01*
G02X197990Y1413173I2J-3502D01*
G37*
G36*
G01X169700Y1414247D02*
Y1414249D01*
G02X176704I3502J0D01*
G01Y1414248D01*
G02X176327Y1412668I-3502J1D01*
G03X176315Y1412517I178J-90D01*
G02X176478Y1411460I-3340J-1056D01*
G02X176341Y1410488I-3502J-2D01*
G03X176351Y1410350I192J-55D01*
G02X176666Y1408897I-3187J-1452D01*
G02X176461Y1407714I-3502J-2D01*
G03Y1407580I188J-67D01*
G02X176666Y1406400I-3297J-1181D01*
G01Y1406397D01*
G02X169662I-3502J0D01*
G01Y1406400D01*
G02X169867Y1407580I3502J-1D01*
G03Y1407714I-188J67D01*
G02X169662Y1408897I3297J1181D01*
G02X169799Y1409869I3502J2D01*
G03X169789Y1410007I-192J55D01*
G02X169474Y1411460I3187J1452D01*
G02X169851Y1413041I3502J0D01*
G03X169863Y1413192I-178J90D01*
G02X169700Y1414247I3340J1056D01*
G37*
G36*
G01X159760Y1413343D02*
G02X159596Y1414400I3339J1059D01*
G02X166602I3503J0D01*
G02X166224Y1412819I-3503J2D01*
G03X166212Y1412668I178J-90D01*
G02X166376Y1411611I-3339J-1059D01*
G02X166238Y1410639I-3503J2D01*
G03X166249Y1410501I192J-54D01*
G02X166564Y1409050I-3188J-1452D01*
G01Y1409048D01*
G02X166358Y1407866I-3503J2D01*
G03Y1407730I188J-68D01*
G02X166564Y1406548I-3297J-1184D01*
G02X159558I-3503J0D01*
G02X159764Y1407730I3503J-2D01*
G03Y1407866I-188J68D01*
G02X159558Y1409048I3297J1184D01*
G02X159696Y1410020I3503J-2D01*
G03X159685Y1410158I-192J54D01*
G02X159370Y1411609I3188J1452D01*
G01Y1411611D01*
G02X159748Y1413192I3503J-2D01*
G03X159760Y1413343I-178J90D01*
G37*
G36*
G01X1715866Y1426415D02*
G03X1716028I81J183D01*
G02X1717447Y1426716I1421J-3202D01*
G02X1720950Y1423213I0J-3503D01*
G02X1720649Y1421794I-3503J2D01*
G03Y1421632I183J-81D01*
G02X1720950Y1420213I-3202J-1421D01*
G02X1720649Y1418794I-3503J2D01*
G03Y1418632I183J-81D01*
G02X1720950Y1417213I-3202J-1421D01*
G02X1717447Y1413710I-3503J0D01*
G02X1716028Y1414011I2J3503D01*
G03X1715866I-81J-183D01*
G02X1714447Y1413710I-1421J3202D01*
G02X1710944Y1417213I0J3503D01*
G02X1711245Y1418632I3503J-2D01*
G03Y1418794I-183J81D01*
G02X1710944Y1420213I3202J1421D01*
G02X1711245Y1421632I3503J-2D01*
G03Y1421794I-183J81D01*
G02X1710944Y1423213I3202J1421D01*
G02X1714447Y1426716I3503J0D01*
G02X1715866Y1426415I-2J-3503D01*
G37*
G36*
G01X733999Y1429324D02*
G02X735416Y1429624I1418J-3202D01*
G01X735418D01*
G02X738920Y1426122I0J-3502D01*
G01Y1426120D01*
G02X738620Y1424703I-3502J1D01*
G03Y1424541I183J-81D01*
G02X738920Y1423122I-3202J-1418D01*
G02X738620Y1421703I-3502J-1D01*
G03Y1421541I183J-81D01*
G02X738920Y1420124I-3202J-1418D01*
G01Y1420122D01*
G02X735418Y1416620I-3502J0D01*
G01X735416D01*
G02X733999Y1416920I1J3502D01*
G03X733837I-81J-183D01*
G02X732420Y1416620I-1418J3202D01*
G01X732418D01*
G02X728916Y1420122I0J3502D01*
G01Y1420124D01*
G02X729216Y1421541I3502J-1D01*
G03Y1421703I-183J81D01*
G02X728916Y1423122I3202J1418D01*
G02X729216Y1424541I3502J1D01*
G03Y1424703I-183J81D01*
G02X728916Y1426120I3202J1418D01*
G01Y1426122D01*
G02X732418Y1429624I3502J0D01*
G01X732420D01*
G02X733837Y1429324I-1J-3502D01*
G03X733999I81J183D01*
G37*
G36*
G01X176051Y1451392D02*
G02Y1454398I0J1503D01*
G01X179451D01*
G02Y1451392I0J-1503D01*
G01X176051D01*
G37*
G36*
G01X202851D02*
G02Y1454398I0J1503D01*
G01X206251D01*
G02Y1451392I0J-1503D01*
G01X202851D01*
G37*
G36*
G01X229651D02*
G02Y1454398I0J1503D01*
G01X233051D01*
G02Y1451392I0J-1503D01*
G01X229651D01*
G37*
G36*
G01X256451D02*
G02Y1454398I0J1503D01*
G01X259851D01*
G02Y1451392I0J-1503D01*
G01X256451D01*
G37*
G36*
G01X269851D02*
G02Y1454398I0J1503D01*
G01X273251D01*
G02Y1451392I0J-1503D01*
G01X269851D01*
G37*
G36*
G01X304113D02*
G02Y1454398I0J1503D01*
G01X307513D01*
G02Y1451392I0J-1503D01*
G01X304113D01*
G37*
G36*
G01X330913D02*
G02Y1454398I0J1503D01*
G01X334313D01*
G02Y1451392I0J-1503D01*
G01X330913D01*
G37*
G36*
G01X357713D02*
G02Y1454398I0J1503D01*
G01X361113D01*
G02Y1451392I0J-1503D01*
G01X357713D01*
G37*
G36*
G01X384513D02*
G02Y1454398I0J1503D01*
G01X387913D01*
G02Y1451392I0J-1503D01*
G01X384513D01*
G37*
G36*
G01X397913D02*
G02Y1454398I0J1503D01*
G01X401313D01*
G02Y1451392I0J-1503D01*
G01X397913D01*
G37*
G36*
G01X440224D02*
G02Y1454398I0J1503D01*
G01X443624D01*
G02Y1451392I0J-1503D01*
G01X440224D01*
G37*
G36*
G01X467024D02*
G02Y1454398I0J1503D01*
G01X470424D01*
G02Y1451392I0J-1503D01*
G01X467024D01*
G37*
G36*
G01X493824D02*
G02Y1454398I0J1503D01*
G01X497224D01*
G02Y1451392I0J-1503D01*
G01X493824D01*
G37*
G36*
G01X520624D02*
G02Y1454398I0J1503D01*
G01X524024D01*
G02Y1451392I0J-1503D01*
G01X520624D01*
G37*
G36*
G01X534024D02*
G02Y1454398I0J1503D01*
G01X537424D01*
G02Y1451392I0J-1503D01*
G01X534024D01*
G37*
G36*
G01X568286D02*
G02Y1454398I0J1503D01*
G01X571686D01*
G02Y1451392I0J-1503D01*
G01X568286D01*
G37*
G36*
G01X595086D02*
G02Y1454398I0J1503D01*
G01X598486D01*
G02Y1451392I0J-1503D01*
G01X595086D01*
G37*
G36*
G01X621886D02*
G02Y1454398I0J1503D01*
G01X625286D01*
G02Y1451392I0J-1503D01*
G01X621886D01*
G37*
G36*
G01X648686D02*
G02Y1454398I0J1503D01*
G01X652086D01*
G02Y1451392I0J-1503D01*
G01X648686D01*
G37*
G36*
G01X662086D02*
G02Y1454398I0J1503D01*
G01X665486D01*
G02Y1451392I0J-1503D01*
G01X662086D01*
G37*
G36*
G01X691276Y1453610D02*
G02Y1456614I0J1502D01*
G01X694676D01*
G02Y1453610I0J-1502D01*
G01X691276D01*
G37*
G36*
G01X169351Y1461092D02*
G02Y1464098I0J1503D01*
G01X172751D01*
G02Y1461092I0J-1503D01*
G01X169351D01*
G37*
G36*
G01X196151D02*
G02Y1464098I0J1503D01*
G01X199551D01*
G02Y1461092I0J-1503D01*
G01X196151D01*
G37*
G36*
G01X222951D02*
G02Y1464098I0J1503D01*
G01X226351D01*
G02Y1461092I0J-1503D01*
G01X222951D01*
G37*
G36*
G01X249751D02*
G02Y1464098I0J1503D01*
G01X253151D01*
G02Y1461092I0J-1503D01*
G01X249751D01*
G37*
G36*
G01X297413D02*
G02Y1464098I0J1503D01*
G01X300813D01*
G02Y1461092I0J-1503D01*
G01X297413D01*
G37*
G36*
G01X324213D02*
G02Y1464098I0J1503D01*
G01X327613D01*
G02Y1461092I0J-1503D01*
G01X324213D01*
G37*
G36*
G01X351013D02*
G02Y1464098I0J1503D01*
G01X354413D01*
G02Y1461092I0J-1503D01*
G01X351013D01*
G37*
G36*
G01X377813D02*
G02Y1464098I0J1503D01*
G01X381213D01*
G02Y1461092I0J-1503D01*
G01X377813D01*
G37*
G36*
G01X433524D02*
G02Y1464098I0J1503D01*
G01X436924D01*
G02Y1461092I0J-1503D01*
G01X433524D01*
G37*
G36*
G01X460324D02*
G02Y1464098I0J1503D01*
G01X463724D01*
G02Y1461092I0J-1503D01*
G01X460324D01*
G37*
G36*
G01X487124D02*
G02Y1464098I0J1503D01*
G01X490524D01*
G02Y1461092I0J-1503D01*
G01X487124D01*
G37*
G36*
G01X513924D02*
G02Y1464098I0J1503D01*
G01X517324D01*
G02Y1461092I0J-1503D01*
G01X513924D01*
G37*
G36*
G01X561586D02*
G02Y1464098I0J1503D01*
G01X564986D01*
G02Y1461092I0J-1503D01*
G01X561586D01*
G37*
G36*
G01X588386D02*
G02Y1464098I0J1503D01*
G01X591786D01*
G02Y1461092I0J-1503D01*
G01X588386D01*
G37*
G36*
G01X615186D02*
G02Y1464098I0J1503D01*
G01X618586D01*
G02Y1461092I0J-1503D01*
G01X615186D01*
G37*
G36*
G01X641986D02*
G02Y1464098I0J1503D01*
G01X645386D01*
G02Y1461092I0J-1503D01*
G01X641986D01*
G37*
G36*
G01X189451Y1470792D02*
G02Y1473798I0J1503D01*
G01X192851D01*
G02Y1470792I0J-1503D01*
G01X189451D01*
G37*
G36*
G01X216251D02*
G02Y1473798I0J1503D01*
G01X219651D01*
G02Y1470792I0J-1503D01*
G01X216251D01*
G37*
G36*
G01X243051D02*
G02Y1473798I0J1503D01*
G01X246451D01*
G02Y1470792I0J-1503D01*
G01X243051D01*
G37*
G36*
G01X317513D02*
G02Y1473798I0J1503D01*
G01X320913D01*
G02Y1470792I0J-1503D01*
G01X317513D01*
G37*
G36*
G01X344313D02*
G02Y1473798I0J1503D01*
G01X347713D01*
G02Y1470792I0J-1503D01*
G01X344313D01*
G37*
G36*
G01X371113D02*
G02Y1473798I0J1503D01*
G01X374513D01*
G02Y1470792I0J-1503D01*
G01X371113D01*
G37*
G36*
G01X453624D02*
G02Y1473798I0J1503D01*
G01X457024D01*
G02Y1470792I0J-1503D01*
G01X453624D01*
G37*
G36*
G01X480424D02*
G02Y1473798I0J1503D01*
G01X483824D01*
G02Y1470792I0J-1503D01*
G01X480424D01*
G37*
G36*
G01X507224D02*
G02Y1473798I0J1503D01*
G01X510624D01*
G02Y1470792I0J-1503D01*
G01X507224D01*
G37*
G36*
G01X581686D02*
G02Y1473798I0J1503D01*
G01X585086D01*
G02Y1470792I0J-1503D01*
G01X581686D01*
G37*
G36*
G01X608486D02*
G02Y1473798I0J1503D01*
G01X611886D01*
G02Y1470792I0J-1503D01*
G01X608486D01*
G37*
G36*
G01X635286D02*
G02Y1473798I0J1503D01*
G01X638686D01*
G02Y1470792I0J-1503D01*
G01X635286D01*
G37*
G36*
G01X1183924Y1484392D02*
G02Y1487398I0J1503D01*
G01X1187324D01*
G02Y1484392I0J-1503D01*
G01X1183924D01*
G37*
G36*
G01X1210724D02*
G02Y1487398I0J1503D01*
G01X1214124D01*
G02Y1484392I0J-1503D01*
G01X1210724D01*
G37*
G36*
G01X1237524D02*
G02Y1487398I0J1503D01*
G01X1240924D01*
G02Y1484392I0J-1503D01*
G01X1237524D01*
G37*
G36*
G01X1264324D02*
G02Y1487398I0J1503D01*
G01X1267724D01*
G02Y1484392I0J-1503D01*
G01X1264324D01*
G37*
G36*
G01X1277724D02*
G02Y1487398I0J1503D01*
G01X1281124D01*
G02Y1484392I0J-1503D01*
G01X1277724D01*
G37*
G36*
G01X1311986D02*
G02Y1487398I0J1503D01*
G01X1315386D01*
G02Y1484392I0J-1503D01*
G01X1311986D01*
G37*
G36*
G01X1338786D02*
G02Y1487398I0J1503D01*
G01X1342186D01*
G02Y1484392I0J-1503D01*
G01X1338786D01*
G37*
G36*
G01X1365586D02*
G02Y1487398I0J1503D01*
G01X1368986D01*
G02Y1484392I0J-1503D01*
G01X1365586D01*
G37*
G36*
G01X1392386D02*
G02Y1487398I0J1503D01*
G01X1395786D01*
G02Y1484392I0J-1503D01*
G01X1392386D01*
G37*
G36*
G01X1405786D02*
G02Y1487398I0J1503D01*
G01X1409186D01*
G02Y1484392I0J-1503D01*
G01X1405786D01*
G37*
G36*
G01X1448098D02*
G02Y1487398I0J1503D01*
G01X1451498D01*
G02Y1484392I0J-1503D01*
G01X1448098D01*
G37*
G36*
G01X1474898D02*
G02Y1487398I0J1503D01*
G01X1478298D01*
G02Y1484392I0J-1503D01*
G01X1474898D01*
G37*
G36*
G01X1501698D02*
G02Y1487398I0J1503D01*
G01X1505098D01*
G02Y1484392I0J-1503D01*
G01X1501698D01*
G37*
G36*
G01X1528498D02*
G02Y1487398I0J1503D01*
G01X1531898D01*
G02Y1484392I0J-1503D01*
G01X1528498D01*
G37*
G36*
G01X1541898D02*
G02Y1487398I0J1503D01*
G01X1545298D01*
G02Y1484392I0J-1503D01*
G01X1541898D01*
G37*
G36*
G01X1576160D02*
G02Y1487398I0J1503D01*
G01X1579560D01*
G02Y1484392I0J-1503D01*
G01X1576160D01*
G37*
G36*
G01X1602960D02*
G02Y1487398I0J1503D01*
G01X1606360D01*
G02Y1484392I0J-1503D01*
G01X1602960D01*
G37*
G36*
G01X1629760D02*
G02Y1487398I0J1503D01*
G01X1633160D01*
G02Y1484392I0J-1503D01*
G01X1629760D01*
G37*
G36*
G01X1656560D02*
G02Y1487398I0J1503D01*
G01X1659960D01*
G02Y1484392I0J-1503D01*
G01X1656560D01*
G37*
G36*
G01X1669960D02*
G02Y1487398I0J1503D01*
G01X1673360D01*
G02Y1484392I0J-1503D01*
G01X1669960D01*
G37*
G36*
G01X1177224Y1494092D02*
G02Y1497098I0J1503D01*
G01X1180624D01*
G02Y1494092I0J-1503D01*
G01X1177224D01*
G37*
G36*
G01X1204024D02*
G02Y1497098I0J1503D01*
G01X1207424D01*
G02Y1494092I0J-1503D01*
G01X1204024D01*
G37*
G36*
G01X1230824D02*
G02Y1497098I0J1503D01*
G01X1234224D01*
G02Y1494092I0J-1503D01*
G01X1230824D01*
G37*
G36*
G01X1257624D02*
G02Y1497098I0J1503D01*
G01X1261024D01*
G02Y1494092I0J-1503D01*
G01X1257624D01*
G37*
G36*
G01X1305286D02*
G02Y1497098I0J1503D01*
G01X1308686D01*
G02Y1494092I0J-1503D01*
G01X1305286D01*
G37*
G36*
G01X1332086D02*
G02Y1497098I0J1503D01*
G01X1335486D01*
G02Y1494092I0J-1503D01*
G01X1332086D01*
G37*
G36*
G01X1358886D02*
G02Y1497098I0J1503D01*
G01X1362286D01*
G02Y1494092I0J-1503D01*
G01X1358886D01*
G37*
G36*
G01X1385686D02*
G02Y1497098I0J1503D01*
G01X1389086D01*
G02Y1494092I0J-1503D01*
G01X1385686D01*
G37*
G36*
G01X1441398D02*
G02Y1497098I0J1503D01*
G01X1444798D01*
G02Y1494092I0J-1503D01*
G01X1441398D01*
G37*
G36*
G01X1468198D02*
G02Y1497098I0J1503D01*
G01X1471598D01*
G02Y1494092I0J-1503D01*
G01X1468198D01*
G37*
G36*
G01X1494998D02*
G02Y1497098I0J1503D01*
G01X1498398D01*
G02Y1494092I0J-1503D01*
G01X1494998D01*
G37*
G36*
G01X1521798D02*
G02Y1497098I0J1503D01*
G01X1525198D01*
G02Y1494092I0J-1503D01*
G01X1521798D01*
G37*
G36*
G01X1569460D02*
G02Y1497098I0J1503D01*
G01X1572860D01*
G02Y1494092I0J-1503D01*
G01X1569460D01*
G37*
G36*
G01X1596260D02*
G02Y1497098I0J1503D01*
G01X1599660D01*
G02Y1494092I0J-1503D01*
G01X1596260D01*
G37*
G36*
G01X1623060D02*
G02Y1497098I0J1503D01*
G01X1626460D01*
G02Y1494092I0J-1503D01*
G01X1623060D01*
G37*
G36*
G01X1649860D02*
G02Y1497098I0J1503D01*
G01X1653260D01*
G02Y1494092I0J-1503D01*
G01X1649860D01*
G37*
G36*
G01X1197324Y1503792D02*
G02Y1506798I0J1503D01*
G01X1200724D01*
G02Y1503792I0J-1503D01*
G01X1197324D01*
G37*
G36*
G01X1224124D02*
G02Y1506798I0J1503D01*
G01X1227524D01*
G02Y1503792I0J-1503D01*
G01X1224124D01*
G37*
G36*
G01X1250924D02*
G02Y1506798I0J1503D01*
G01X1254324D01*
G02Y1503792I0J-1503D01*
G01X1250924D01*
G37*
G36*
G01X1325386D02*
G02Y1506798I0J1503D01*
G01X1328786D01*
G02Y1503792I0J-1503D01*
G01X1325386D01*
G37*
G36*
G01X1352186D02*
G02Y1506798I0J1503D01*
G01X1355586D01*
G02Y1503792I0J-1503D01*
G01X1352186D01*
G37*
G36*
G01X1378986D02*
G02Y1506798I0J1503D01*
G01X1382386D01*
G02Y1503792I0J-1503D01*
G01X1378986D01*
G37*
G36*
G01X1461498D02*
G02Y1506798I0J1503D01*
G01X1464898D01*
G02Y1503792I0J-1503D01*
G01X1461498D01*
G37*
G36*
G01X1488298D02*
G02Y1506798I0J1503D01*
G01X1491698D01*
G02Y1503792I0J-1503D01*
G01X1488298D01*
G37*
G36*
G01X1515098D02*
G02Y1506798I0J1503D01*
G01X1518498D01*
G02Y1503792I0J-1503D01*
G01X1515098D01*
G37*
G36*
G01X1589560D02*
G02Y1506798I0J1503D01*
G01X1592960D01*
G02Y1503792I0J-1503D01*
G01X1589560D01*
G37*
G36*
G01X1616360D02*
G02Y1506798I0J1503D01*
G01X1619760D01*
G02Y1503792I0J-1503D01*
G01X1616360D01*
G37*
G36*
G01X1643160D02*
G02Y1506798I0J1503D01*
G01X1646560D01*
G02Y1503792I0J-1503D01*
G01X1643160D01*
G37*
G36*
G01X188668Y1520261D02*
X188670Y1520264D01*
G02X189730Y1520900I1060J-565D01*
G02X190932Y1519698I0J-1202D01*
G01Y1519697D01*
G02X190772Y1519098I-1203J1D01*
G01X189227Y1516425D01*
X189225Y1516421D01*
G02X188155Y1515768I-1070J550D01*
G01X188153D01*
G02X186952Y1516970I1J1202D01*
G01Y1516972D01*
G02X187102Y1517551I1203J-3D01*
G01X188668Y1520261D01*
G37*
G36*
G01X193392D02*
X193394Y1520264D01*
G02X194454Y1520900I1060J-565D01*
G02X195656Y1519698I0J-1202D01*
G01Y1519697D01*
G02X195496Y1519098I-1203J1D01*
G01X193951Y1516425D01*
X193949Y1516421D01*
G02X192879Y1515768I-1070J550D01*
G01X192877D01*
G02X191676Y1516970I1J1202D01*
G01Y1516972D01*
G02X191826Y1517551I1203J-3D01*
G01X193392Y1520261D01*
G37*
G36*
G01X198116D02*
X198118Y1520264D01*
G02X199178Y1520900I1060J-565D01*
G02X200380Y1519698I0J-1202D01*
G01Y1519697D01*
G02X200220Y1519098I-1203J1D01*
G01X198675Y1516425D01*
X198673Y1516421D01*
G02X197603Y1515768I-1070J550D01*
G01X197601D01*
G02X196400Y1516970I1J1202D01*
G01Y1516972D01*
G02X196550Y1517551I1203J-3D01*
G01X198116Y1520261D01*
G37*
G36*
G01X202843Y1520264D02*
G02X203903Y1520900I1060J-565D01*
G01X203905D01*
G02X205106Y1519698I-1J-1202D01*
G02X204945Y1519098I-1204J1D01*
G01X203400Y1516425D01*
X203398Y1516421D01*
G02X202328Y1515768I-1070J550D01*
G02X201126Y1516970I0J1202D01*
G01Y1516972D01*
G02X201275Y1517551I1202J-1D01*
G01X202841Y1520261D01*
X202843Y1520264D01*
G37*
G36*
G01X207567D02*
G02X208627Y1520900I1060J-565D01*
G01X208629D01*
G02X209830Y1519698I-1J-1202D01*
G02X209669Y1519098I-1204J1D01*
G01X208124Y1516425D01*
X208122Y1516421D01*
G02X207052Y1515768I-1070J550D01*
G02X205850Y1516970I0J1202D01*
G01Y1516972D01*
G02X205999Y1517551I1202J-1D01*
G01X207565Y1520261D01*
X207567Y1520264D01*
G37*
G36*
G01X212290Y1520261D02*
X212292Y1520264D01*
G02X213352Y1520900I1060J-565D01*
G02X214554Y1519698I0J-1202D01*
G01Y1519697D01*
G02X214394Y1519098I-1203J1D01*
G01X212849Y1516425D01*
X212847Y1516421D01*
G02X211777Y1515768I-1070J550D01*
G01X211775D01*
G02X210574Y1516970I1J1202D01*
G01Y1516972D01*
G02X210724Y1517551I1203J-3D01*
G01X212290Y1520261D01*
G37*
G36*
G01X217014D02*
X217016Y1520264D01*
G02X218076Y1520900I1060J-565D01*
G02X219278Y1519698I0J-1202D01*
G01Y1519697D01*
G02X219118Y1519098I-1203J1D01*
G01X217573Y1516425D01*
X217571Y1516421D01*
G02X216501Y1515768I-1070J550D01*
G01X216499D01*
G02X215298Y1516970I1J1202D01*
G01Y1516972D01*
G02X215448Y1517551I1203J-3D01*
G01X217014Y1520261D01*
G37*
G36*
G01X221738D02*
X221740Y1520264D01*
G02X222800Y1520900I1060J-565D01*
G02X224002Y1519698I0J-1202D01*
G01Y1519697D01*
G02X223842Y1519098I-1203J1D01*
G01X222297Y1516425D01*
X222295Y1516421D01*
G02X221225Y1515768I-1070J550D01*
G01X221223D01*
G02X220022Y1516970I1J1202D01*
G01Y1516972D01*
G02X220172Y1517551I1203J-3D01*
G01X221738Y1520261D01*
G37*
G36*
G01X226465Y1520264D02*
G02X227525Y1520900I1060J-565D01*
G01X227526D01*
G02X228728Y1519698I0J-1202D01*
G01Y1519697D01*
G02X228568Y1519098I-1203J1D01*
G01X227023Y1516425D01*
X227021Y1516421D01*
G02X225951Y1515768I-1070J550D01*
G01X225950D01*
G02X224748Y1516970I0J1202D01*
G01Y1516972D01*
G02X224897Y1517551I1202J-1D01*
G01X226463Y1520261D01*
X226465Y1520264D01*
G37*
G36*
G01X231189D02*
G02X232249Y1520900I1060J-565D01*
G01X232250D01*
G02X233452Y1519698I0J-1202D01*
G01Y1519697D01*
G02X233292Y1519098I-1203J1D01*
G01X231747Y1516425D01*
X231745Y1516421D01*
G02X230675Y1515768I-1070J550D01*
G01X230674D01*
G02X229472Y1516970I0J1202D01*
G01Y1516972D01*
G02X229621Y1517551I1202J-1D01*
G01X231187Y1520261D01*
X231189Y1520264D01*
G37*
G36*
G01X250087D02*
G02X251147Y1520900I1060J-565D01*
G01X251148D01*
G02X252350Y1519698I0J-1202D01*
G01Y1519697D01*
G02X252190Y1519098I-1203J1D01*
G01X250645Y1516425D01*
X250643Y1516421D01*
G02X249573Y1515768I-1070J550D01*
G01X249572D01*
G02X248370Y1516970I0J1202D01*
G01Y1516972D01*
G02X248519Y1517551I1202J-1D01*
G01X250085Y1520261D01*
X250087Y1520264D01*
G37*
G36*
G01X254811D02*
G02X255871Y1520900I1060J-565D01*
G01X255872D01*
G02X257074Y1519698I0J-1202D01*
G01Y1519697D01*
G02X256914Y1519098I-1203J1D01*
G01X255369Y1516425D01*
X255367Y1516421D01*
G02X254297Y1515768I-1070J550D01*
G01X254296D01*
G02X253094Y1516970I0J1202D01*
G01Y1516972D01*
G02X253243Y1517551I1202J-1D01*
G01X254809Y1520261D01*
X254811Y1520264D01*
G37*
G36*
G01X316730Y1520261D02*
X316732Y1520264D01*
G02X317792Y1520900I1060J-565D01*
G02X318994Y1519698I0J-1202D01*
G01Y1519697D01*
G02X318834Y1519098I-1203J1D01*
G01X317289Y1516425D01*
X317287Y1516421D01*
G02X316217Y1515768I-1070J550D01*
G01X316215D01*
G02X315014Y1516970I1J1202D01*
G01Y1516972D01*
G02X315164Y1517551I1203J-3D01*
G01X316730Y1520261D01*
G37*
G36*
G01X321454D02*
X321456Y1520264D01*
G02X322516Y1520900I1060J-565D01*
G02X323718Y1519698I0J-1202D01*
G01Y1519697D01*
G02X323558Y1519098I-1203J1D01*
G01X322013Y1516425D01*
X322011Y1516421D01*
G02X320941Y1515768I-1070J550D01*
G01X320939D01*
G02X319738Y1516970I1J1202D01*
G01Y1516972D01*
G02X319888Y1517551I1203J-3D01*
G01X321454Y1520261D01*
G37*
G36*
G01X326178D02*
X326180Y1520264D01*
G02X327240Y1520900I1060J-565D01*
G02X328442Y1519698I0J-1202D01*
G01Y1519697D01*
G02X328282Y1519098I-1203J1D01*
G01X326737Y1516425D01*
X326735Y1516421D01*
G02X325665Y1515768I-1070J550D01*
G01X325663D01*
G02X324462Y1516970I1J1202D01*
G01Y1516972D01*
G02X324612Y1517551I1203J-3D01*
G01X326178Y1520261D01*
G37*
G36*
G01X330905Y1520264D02*
G02X331965Y1520900I1060J-565D01*
G01X331967D01*
G02X333168Y1519698I-1J-1202D01*
G02X333007Y1519098I-1204J1D01*
G01X331462Y1516425D01*
X331460Y1516421D01*
G02X330390Y1515768I-1070J550D01*
G02X329188Y1516970I0J1202D01*
G01Y1516972D01*
G02X329337Y1517551I1202J-1D01*
G01X330903Y1520261D01*
X330905Y1520264D01*
G37*
G36*
G01X335629D02*
G02X336689Y1520900I1060J-565D01*
G01X336691D01*
G02X337892Y1519698I-1J-1202D01*
G02X337731Y1519098I-1204J1D01*
G01X336186Y1516425D01*
X336184Y1516421D01*
G02X335114Y1515768I-1070J550D01*
G02X333912Y1516970I0J1202D01*
G01Y1516972D01*
G02X334061Y1517551I1202J-1D01*
G01X335627Y1520261D01*
X335629Y1520264D01*
G37*
G36*
G01X340352Y1520261D02*
X340354Y1520264D01*
G02X341414Y1520900I1060J-565D01*
G02X342616Y1519698I0J-1202D01*
G01Y1519697D01*
G02X342456Y1519098I-1203J1D01*
G01X340911Y1516425D01*
X340909Y1516421D01*
G02X339839Y1515768I-1070J550D01*
G01X339837D01*
G02X338636Y1516970I1J1202D01*
G01Y1516972D01*
G02X338786Y1517551I1203J-3D01*
G01X340352Y1520261D01*
G37*
G36*
G01X345076D02*
X345078Y1520264D01*
G02X346138Y1520900I1060J-565D01*
G02X347340Y1519698I0J-1202D01*
G01Y1519697D01*
G02X347180Y1519098I-1203J1D01*
G01X345635Y1516425D01*
X345633Y1516421D01*
G02X344563Y1515768I-1070J550D01*
G01X344561D01*
G02X343360Y1516970I1J1202D01*
G01Y1516972D01*
G02X343510Y1517551I1203J-3D01*
G01X345076Y1520261D01*
G37*
G36*
G01X349800D02*
X349802Y1520264D01*
G02X350862Y1520900I1060J-565D01*
G02X352064Y1519698I0J-1202D01*
G01Y1519697D01*
G02X351904Y1519098I-1203J1D01*
G01X350359Y1516425D01*
X350357Y1516421D01*
G02X349287Y1515768I-1070J550D01*
G01X349285D01*
G02X348084Y1516970I1J1202D01*
G01Y1516972D01*
G02X348234Y1517551I1203J-3D01*
G01X349800Y1520261D01*
G37*
G36*
G01X354527Y1520264D02*
G02X355587Y1520900I1060J-565D01*
G01X355589D01*
G02X356790Y1519698I-1J-1202D01*
G02X356629Y1519098I-1204J1D01*
G01X355084Y1516425D01*
X355082Y1516421D01*
G02X354012Y1515768I-1070J550D01*
G02X352810Y1516970I0J1202D01*
G01Y1516972D01*
G02X352959Y1517551I1202J-1D01*
G01X354525Y1520261D01*
X354527Y1520264D01*
G37*
G36*
G01X359251D02*
G02X360311Y1520900I1060J-565D01*
G01X360313D01*
G02X361514Y1519698I-1J-1202D01*
G02X361353Y1519098I-1204J1D01*
G01X359808Y1516425D01*
X359806Y1516421D01*
G02X358736Y1515768I-1070J550D01*
G02X357534Y1516970I0J1202D01*
G01Y1516972D01*
G02X357683Y1517551I1202J-1D01*
G01X359249Y1520261D01*
X359251Y1520264D01*
G37*
G36*
G01X363974Y1520261D02*
X363976Y1520264D01*
G02X365036Y1520900I1060J-565D01*
G02X366238Y1519698I0J-1202D01*
G01Y1519697D01*
G02X366078Y1519098I-1203J1D01*
G01X364533Y1516425D01*
X364531Y1516421D01*
G02X363461Y1515768I-1070J550D01*
G01X363459D01*
G02X362258Y1516970I1J1202D01*
G01Y1516972D01*
G02X362408Y1517551I1203J-3D01*
G01X363974Y1520261D01*
G37*
G36*
G01X368698D02*
X368700Y1520264D01*
G02X369760Y1520900I1060J-565D01*
G02X370962Y1519698I0J-1202D01*
G01Y1519697D01*
G02X370802Y1519098I-1203J1D01*
G01X369257Y1516425D01*
X369255Y1516421D01*
G02X368185Y1515768I-1070J550D01*
G01X368183D01*
G02X366982Y1516970I1J1202D01*
G01Y1516972D01*
G02X367132Y1517551I1203J-3D01*
G01X368698Y1520261D01*
G37*
G36*
G01X373422D02*
X373424Y1520264D01*
G02X374484Y1520900I1060J-565D01*
G02X375686Y1519698I0J-1202D01*
G01Y1519697D01*
G02X375526Y1519098I-1203J1D01*
G01X373981Y1516425D01*
X373979Y1516421D01*
G02X372909Y1515768I-1070J550D01*
G01X372907D01*
G02X371706Y1516970I1J1202D01*
G01Y1516972D01*
G02X371856Y1517551I1203J-3D01*
G01X373422Y1520261D01*
G37*
G36*
G01X378149Y1520264D02*
G02X379209Y1520900I1060J-565D01*
G01X379211D01*
G02X380412Y1519698I-1J-1202D01*
G02X380251Y1519098I-1204J1D01*
G01X378706Y1516425D01*
X378704Y1516421D01*
G02X377634Y1515768I-1070J550D01*
G02X376432Y1516970I0J1202D01*
G01Y1516972D01*
G02X376581Y1517551I1202J-1D01*
G01X378147Y1520261D01*
X378149Y1520264D01*
G37*
G36*
G01X382873D02*
G02X383933Y1520900I1060J-565D01*
G01X383935D01*
G02X385136Y1519698I-1J-1202D01*
G02X384975Y1519098I-1204J1D01*
G01X383430Y1516425D01*
X383428Y1516421D01*
G02X382358Y1515768I-1070J550D01*
G02X381156Y1516970I0J1202D01*
G01Y1516972D01*
G02X381305Y1517551I1202J-1D01*
G01X382871Y1520261D01*
X382873Y1520264D01*
G37*
G36*
G01X387596Y1520261D02*
X387598Y1520264D01*
G02X388658Y1520900I1060J-565D01*
G02X389860Y1519698I0J-1202D01*
G01Y1519697D01*
G02X389700Y1519098I-1203J1D01*
G01X388155Y1516425D01*
X388153Y1516421D01*
G02X387083Y1515768I-1070J550D01*
G01X387081D01*
G02X385880Y1516970I1J1202D01*
G01Y1516972D01*
G02X386030Y1517551I1203J-3D01*
G01X387596Y1520261D01*
G37*
G36*
G01X452843Y1520264D02*
G02X453903Y1520900I1060J-565D01*
G01X453905D01*
G02X455106Y1519698I-1J-1202D01*
G02X454945Y1519098I-1204J1D01*
G01X453400Y1516425D01*
X453398Y1516421D01*
G02X452328Y1515768I-1070J550D01*
G02X451126Y1516970I0J1202D01*
G01Y1516972D01*
G02X451275Y1517551I1202J-1D01*
G01X452841Y1520261D01*
X452843Y1520264D01*
G37*
G36*
G01X457567D02*
G02X458627Y1520900I1060J-565D01*
G01X458629D01*
G02X459830Y1519698I-1J-1202D01*
G02X459669Y1519098I-1204J1D01*
G01X458124Y1516425D01*
X458122Y1516421D01*
G02X457052Y1515768I-1070J550D01*
G02X455850Y1516970I0J1202D01*
G01Y1516972D01*
G02X455999Y1517551I1202J-1D01*
G01X457565Y1520261D01*
X457567Y1520264D01*
G37*
G36*
G01X462291D02*
G02X463351Y1520900I1060J-565D01*
G01X463353D01*
G02X464554Y1519698I-1J-1202D01*
G02X464393Y1519098I-1204J1D01*
G01X462848Y1516425D01*
X462846Y1516421D01*
G02X461776Y1515768I-1070J550D01*
G02X460574Y1516970I0J1202D01*
G01Y1516972D01*
G02X460723Y1517551I1202J-1D01*
G01X462289Y1520261D01*
X462291Y1520264D01*
G37*
G36*
G01X467014Y1520261D02*
X467016Y1520264D01*
G02X468076Y1520900I1060J-565D01*
G02X469278Y1519698I0J-1202D01*
G01Y1519697D01*
G02X469118Y1519098I-1203J1D01*
G01X467573Y1516425D01*
X467571Y1516421D01*
G02X466501Y1515768I-1070J550D01*
G01X466499D01*
G02X465298Y1516970I1J1202D01*
G01Y1516972D01*
G02X465448Y1517551I1203J-3D01*
G01X467014Y1520261D01*
G37*
G36*
G01X471738D02*
X471740Y1520264D01*
G02X472800Y1520900I1060J-565D01*
G02X474002Y1519698I0J-1202D01*
G01Y1519697D01*
G02X473842Y1519098I-1203J1D01*
G01X472297Y1516425D01*
X472295Y1516421D01*
G02X471225Y1515768I-1070J550D01*
G01X471223D01*
G02X470022Y1516970I1J1202D01*
G01Y1516972D01*
G02X470172Y1517551I1203J-3D01*
G01X471738Y1520261D01*
G37*
G36*
G01X476465Y1520264D02*
G02X477525Y1520900I1060J-565D01*
G01X477527D01*
G02X478728Y1519698I-1J-1202D01*
G02X478567Y1519098I-1204J1D01*
G01X477022Y1516425D01*
X477020Y1516421D01*
G02X475950Y1515768I-1070J550D01*
G02X474748Y1516970I0J1202D01*
G01Y1516972D01*
G02X474897Y1517551I1202J-1D01*
G01X476463Y1520261D01*
X476465Y1520264D01*
G37*
G36*
G01X481189D02*
G02X482249Y1520900I1060J-565D01*
G01X482251D01*
G02X483452Y1519698I-1J-1202D01*
G02X483291Y1519098I-1204J1D01*
G01X481746Y1516425D01*
X481744Y1516421D01*
G02X480674Y1515768I-1070J550D01*
G02X479472Y1516970I0J1202D01*
G01Y1516972D01*
G02X479621Y1517551I1202J-1D01*
G01X481187Y1520261D01*
X481189Y1520264D01*
G37*
G36*
G01X485913D02*
G02X486973Y1520900I1060J-565D01*
G01X486975D01*
G02X488176Y1519698I-1J-1202D01*
G02X488015Y1519098I-1204J1D01*
G01X486470Y1516425D01*
X486468Y1516421D01*
G02X485398Y1515768I-1070J550D01*
G02X484196Y1516970I0J1202D01*
G01Y1516972D01*
G02X484345Y1517551I1202J-1D01*
G01X485911Y1520261D01*
X485913Y1520264D01*
G37*
G36*
G01X490636Y1520261D02*
X490638Y1520264D01*
G02X491698Y1520900I1060J-565D01*
G02X492900Y1519698I0J-1202D01*
G01Y1519697D01*
G02X492740Y1519098I-1203J1D01*
G01X491195Y1516425D01*
X491193Y1516421D01*
G02X490123Y1515768I-1070J550D01*
G01X490121D01*
G02X488920Y1516970I1J1202D01*
G01Y1516972D01*
G02X489070Y1517551I1203J-3D01*
G01X490636Y1520261D01*
G37*
G36*
G01X495360D02*
X495362Y1520264D01*
G02X496422Y1520900I1060J-565D01*
G02X497624Y1519698I0J-1202D01*
G01Y1519697D01*
G02X497464Y1519098I-1203J1D01*
G01X495919Y1516425D01*
X495917Y1516421D01*
G02X494847Y1515768I-1070J550D01*
G01X494845D01*
G02X493644Y1516970I1J1202D01*
G01Y1516972D01*
G02X493794Y1517551I1203J-3D01*
G01X495360Y1520261D01*
G37*
G36*
G01X500087Y1520264D02*
G02X501147Y1520900I1060J-565D01*
G01X501149D01*
G02X502350Y1519698I-1J-1202D01*
G02X502189Y1519098I-1204J1D01*
G01X500644Y1516425D01*
X500642Y1516421D01*
G02X499572Y1515768I-1070J550D01*
G02X498370Y1516970I0J1202D01*
G01Y1516972D01*
G02X498519Y1517551I1202J-1D01*
G01X500085Y1520261D01*
X500087Y1520264D01*
G37*
G36*
G01X504811D02*
G02X505871Y1520900I1060J-565D01*
G01X505873D01*
G02X507074Y1519698I-1J-1202D01*
G02X506913Y1519098I-1204J1D01*
G01X505368Y1516425D01*
X505366Y1516421D01*
G02X504296Y1515768I-1070J550D01*
G02X503094Y1516970I0J1202D01*
G01Y1516972D01*
G02X503243Y1517551I1202J-1D01*
G01X504809Y1520261D01*
X504811Y1520264D01*
G37*
G36*
G01X509535D02*
G02X510595Y1520900I1060J-565D01*
G01X510597D01*
G02X511798Y1519698I-1J-1202D01*
G02X511637Y1519098I-1204J1D01*
G01X510092Y1516425D01*
X510090Y1516421D01*
G02X509020Y1515768I-1070J550D01*
G02X507818Y1516970I0J1202D01*
G01Y1516972D01*
G02X507967Y1517551I1202J-1D01*
G01X509533Y1520261D01*
X509535Y1520264D01*
G37*
G36*
G01X514258Y1520261D02*
X514260Y1520264D01*
G02X515320Y1520900I1060J-565D01*
G02X516522Y1519698I0J-1202D01*
G01Y1519697D01*
G02X516362Y1519098I-1203J1D01*
G01X514817Y1516425D01*
X514815Y1516421D01*
G02X513745Y1515768I-1070J550D01*
G01X513743D01*
G02X512542Y1516970I1J1202D01*
G01Y1516972D01*
G02X512692Y1517551I1203J-3D01*
G01X514258Y1520261D01*
G37*
G36*
G01X518982D02*
X518984Y1520264D01*
G02X520044Y1520900I1060J-565D01*
G02X521246Y1519698I0J-1202D01*
G01Y1519697D01*
G02X521086Y1519098I-1203J1D01*
G01X519541Y1516425D01*
X519539Y1516421D01*
G02X518469Y1515768I-1070J550D01*
G01X518467D01*
G02X517266Y1516970I1J1202D01*
G01Y1516972D01*
G02X517416Y1517551I1203J-3D01*
G01X518982Y1520261D01*
G37*
G36*
G01X523709Y1520264D02*
G02X524769Y1520900I1060J-565D01*
G01X524771D01*
G02X525972Y1519698I-1J-1202D01*
G02X525811Y1519098I-1204J1D01*
G01X524266Y1516425D01*
X524264Y1516421D01*
G02X523194Y1515768I-1070J550D01*
G02X521992Y1516970I0J1202D01*
G01Y1516972D01*
G02X522141Y1517551I1202J-1D01*
G01X523707Y1520261D01*
X523709Y1520264D01*
G37*
G36*
G01X580905D02*
G02X581965Y1520900I1060J-565D01*
G01X581967D01*
G02X583168Y1519698I-1J-1202D01*
G02X583007Y1519098I-1204J1D01*
G01X581462Y1516425D01*
X581460Y1516421D01*
G02X580390Y1515768I-1070J550D01*
G02X579188Y1516970I0J1202D01*
G01Y1516972D01*
G02X579337Y1517551I1202J-1D01*
G01X580903Y1520261D01*
X580905Y1520264D01*
G37*
G36*
G01X585629D02*
G02X586689Y1520900I1060J-565D01*
G01X586691D01*
G02X587892Y1519698I-1J-1202D01*
G02X587731Y1519098I-1204J1D01*
G01X586186Y1516425D01*
X586184Y1516421D01*
G02X585114Y1515768I-1070J550D01*
G02X583912Y1516970I0J1202D01*
G01Y1516972D01*
G02X584061Y1517551I1202J-1D01*
G01X585627Y1520261D01*
X585629Y1520264D01*
G37*
G36*
G01X590353D02*
G02X591413Y1520900I1060J-565D01*
G01X591415D01*
G02X592616Y1519698I-1J-1202D01*
G02X592455Y1519098I-1204J1D01*
G01X590910Y1516425D01*
X590908Y1516421D01*
G02X589838Y1515768I-1070J550D01*
G02X588636Y1516970I0J1202D01*
G01Y1516972D01*
G02X588785Y1517551I1202J-1D01*
G01X590351Y1520261D01*
X590353Y1520264D01*
G37*
G36*
G01X595076Y1520261D02*
X595078Y1520264D01*
G02X596138Y1520900I1060J-565D01*
G02X597340Y1519698I0J-1202D01*
G01Y1519697D01*
G02X597180Y1519098I-1203J1D01*
G01X595635Y1516425D01*
X595633Y1516421D01*
G02X594563Y1515768I-1070J550D01*
G01X594561D01*
G02X593360Y1516970I1J1202D01*
G01Y1516972D01*
G02X593510Y1517551I1203J-3D01*
G01X595076Y1520261D01*
G37*
G36*
G01X599800D02*
X599802Y1520264D01*
G02X600862Y1520900I1060J-565D01*
G02X602064Y1519698I0J-1202D01*
G01Y1519697D01*
G02X601904Y1519098I-1203J1D01*
G01X600359Y1516425D01*
X600357Y1516421D01*
G02X599287Y1515768I-1070J550D01*
G01X599285D01*
G02X598084Y1516970I1J1202D01*
G01Y1516972D01*
G02X598234Y1517551I1203J-3D01*
G01X599800Y1520261D01*
G37*
G36*
G01X604527Y1520264D02*
G02X605587Y1520900I1060J-565D01*
G01X605589D01*
G02X606790Y1519698I-1J-1202D01*
G02X606629Y1519098I-1204J1D01*
G01X605084Y1516425D01*
X605082Y1516421D01*
G02X604012Y1515768I-1070J550D01*
G02X602810Y1516970I0J1202D01*
G01Y1516972D01*
G02X602959Y1517551I1202J-1D01*
G01X604525Y1520261D01*
X604527Y1520264D01*
G37*
G36*
G01X609251D02*
G02X610311Y1520900I1060J-565D01*
G01X610313D01*
G02X611514Y1519698I-1J-1202D01*
G02X611353Y1519098I-1204J1D01*
G01X609808Y1516425D01*
X609806Y1516421D01*
G02X608736Y1515768I-1070J550D01*
G02X607534Y1516970I0J1202D01*
G01Y1516972D01*
G02X607683Y1517551I1202J-1D01*
G01X609249Y1520261D01*
X609251Y1520264D01*
G37*
G36*
G01X613975D02*
G02X615035Y1520900I1060J-565D01*
G01X615037D01*
G02X616238Y1519698I-1J-1202D01*
G02X616077Y1519098I-1204J1D01*
G01X614532Y1516425D01*
X614530Y1516421D01*
G02X613460Y1515768I-1070J550D01*
G02X612258Y1516970I0J1202D01*
G01Y1516972D01*
G02X612407Y1517551I1202J-1D01*
G01X613973Y1520261D01*
X613975Y1520264D01*
G37*
G36*
G01X618698Y1520261D02*
X618700Y1520264D01*
G02X619760Y1520900I1060J-565D01*
G02X620962Y1519698I0J-1202D01*
G01Y1519697D01*
G02X620802Y1519098I-1203J1D01*
G01X619257Y1516425D01*
X619255Y1516421D01*
G02X618185Y1515768I-1070J550D01*
G01X618183D01*
G02X616982Y1516970I1J1202D01*
G01Y1516972D01*
G02X617132Y1517551I1203J-3D01*
G01X618698Y1520261D01*
G37*
G36*
G01X623422D02*
X623424Y1520264D01*
G02X624484Y1520900I1060J-565D01*
G02X625686Y1519698I0J-1202D01*
G01Y1519697D01*
G02X625526Y1519098I-1203J1D01*
G01X623981Y1516425D01*
X623979Y1516421D01*
G02X622909Y1515768I-1070J550D01*
G01X622907D01*
G02X621706Y1516970I1J1202D01*
G01Y1516972D01*
G02X621856Y1517551I1203J-3D01*
G01X623422Y1520261D01*
G37*
G36*
G01X628149Y1520264D02*
G02X629209Y1520900I1060J-565D01*
G01X629211D01*
G02X630412Y1519698I-1J-1202D01*
G02X630251Y1519098I-1204J1D01*
G01X628706Y1516425D01*
X628704Y1516421D01*
G02X627634Y1515768I-1070J550D01*
G02X626432Y1516970I0J1202D01*
G01Y1516972D01*
G02X626581Y1517551I1202J-1D01*
G01X628147Y1520261D01*
X628149Y1520264D01*
G37*
G36*
G01X632873D02*
G02X633933Y1520900I1060J-565D01*
G01X633935D01*
G02X635136Y1519698I-1J-1202D01*
G02X634975Y1519098I-1204J1D01*
G01X633430Y1516425D01*
X633428Y1516421D01*
G02X632358Y1515768I-1070J550D01*
G02X631156Y1516970I0J1202D01*
G01Y1516972D01*
G02X631305Y1517551I1202J-1D01*
G01X632871Y1520261D01*
X632873Y1520264D01*
G37*
G36*
G01X637597D02*
G02X638657Y1520900I1060J-565D01*
G01X638659D01*
G02X639860Y1519698I-1J-1202D01*
G02X639699Y1519098I-1204J1D01*
G01X638154Y1516425D01*
X638152Y1516421D01*
G02X637082Y1515768I-1070J550D01*
G02X635880Y1516970I0J1202D01*
G01Y1516972D01*
G02X636029Y1517551I1202J-1D01*
G01X637595Y1520261D01*
X637597Y1520264D01*
G37*
G36*
G01X642320Y1520261D02*
X642322Y1520264D01*
G02X643382Y1520900I1060J-565D01*
G02X644584Y1519698I0J-1202D01*
G01Y1519697D01*
G02X644424Y1519098I-1203J1D01*
G01X642879Y1516425D01*
X642877Y1516421D01*
G02X641807Y1515768I-1070J550D01*
G01X641805D01*
G02X640604Y1516970I1J1202D01*
G01Y1516972D01*
G02X640754Y1517551I1203J-3D01*
G01X642320Y1520261D01*
G37*
G36*
G01X647044D02*
X647046Y1520264D01*
G02X648106Y1520900I1060J-565D01*
G02X649308Y1519698I0J-1202D01*
G01Y1519697D01*
G02X649148Y1519098I-1203J1D01*
G01X647603Y1516425D01*
X647601Y1516421D01*
G02X646531Y1515768I-1070J550D01*
G01X646529D01*
G02X645328Y1516970I1J1202D01*
G01Y1516972D01*
G02X645478Y1517551I1203J-3D01*
G01X647044Y1520261D01*
G37*
G36*
G01X651771Y1520264D02*
G02X652831Y1520900I1060J-565D01*
G01X652833D01*
G02X654034Y1519698I-1J-1202D01*
G02X653873Y1519098I-1204J1D01*
G01X652328Y1516425D01*
X652326Y1516421D01*
G02X651256Y1515768I-1070J550D01*
G02X650054Y1516970I0J1202D01*
G01Y1516972D01*
G02X650203Y1517551I1202J-1D01*
G01X651769Y1520261D01*
X651771Y1520264D01*
G37*
G36*
G01X236974Y1520900D02*
X236975D01*
G02X238178Y1519698I1J-1202D01*
G02X238017Y1519098I-1204J1D01*
G01X236472Y1516425D01*
X236470Y1516421D01*
G02X235400Y1515768I-1070J550D01*
G01X235399D01*
G02X234196Y1516970I-1J1202D01*
G01Y1516972D01*
G02X234346Y1517551I1203J-3D01*
G01X235912Y1520261D01*
X235914Y1520264D01*
G02X236974Y1520900I1060J-565D01*
G37*
G36*
G01X241698D02*
X241699D01*
G02X242902Y1519698I1J-1202D01*
G02X242741Y1519098I-1204J1D01*
G01X241196Y1516425D01*
X241194Y1516421D01*
G02X240124Y1515768I-1070J550D01*
G01X240123D01*
G02X238920Y1516970I-1J1202D01*
G01Y1516972D01*
G02X239070Y1517551I1203J-3D01*
G01X240636Y1520261D01*
X240638Y1520264D01*
G02X241698Y1520900I1060J-565D01*
G37*
G36*
G01X246422D02*
X246423D01*
G02X247626Y1519698I1J-1202D01*
G02X247465Y1519098I-1204J1D01*
G01X245920Y1516425D01*
X245918Y1516421D01*
G02X244848Y1515768I-1070J550D01*
G01X244847D01*
G02X243644Y1516970I-1J1202D01*
G01Y1516972D01*
G02X243794Y1517551I1203J-3D01*
G01X245360Y1520261D01*
X245362Y1520264D01*
G02X246422Y1520900I1060J-565D01*
G37*
G36*
G01X260596D02*
X260597D01*
G02X261800Y1519698I1J-1202D01*
G02X261639Y1519098I-1204J1D01*
G01X260094Y1516425D01*
X260092Y1516421D01*
G02X259022Y1515768I-1070J550D01*
G01X259021D01*
G02X257818Y1516970I-1J1202D01*
G01Y1516972D01*
G02X257968Y1517551I1203J-3D01*
G01X259534Y1520261D01*
X259536Y1520264D01*
G02X260596Y1520900I1060J-565D01*
G37*
G36*
G01X188668Y1533899D02*
X188670Y1533902D01*
G02X189730Y1534538I1060J-565D01*
G02X190932Y1533336I0J-1202D01*
G01Y1533335D01*
G02X190772Y1532736I-1203J1D01*
G01X189227Y1530063D01*
X189225Y1530059D01*
G02X188155Y1529406I-1070J550D01*
G01X188153D01*
G02X186952Y1530608I1J1202D01*
G01Y1530610D01*
G02X187102Y1531189I1203J-3D01*
G01X188668Y1533899D01*
G37*
G36*
G01X193392D02*
X193394Y1533902D01*
G02X194454Y1534538I1060J-565D01*
G02X195656Y1533336I0J-1202D01*
G01Y1533335D01*
G02X195496Y1532736I-1203J1D01*
G01X193951Y1530063D01*
X193949Y1530059D01*
G02X192879Y1529406I-1070J550D01*
G01X192877D01*
G02X191676Y1530608I1J1202D01*
G01Y1530610D01*
G02X191826Y1531189I1203J-3D01*
G01X193392Y1533899D01*
G37*
G36*
G01X198116D02*
X198118Y1533902D01*
G02X199178Y1534538I1060J-565D01*
G02X200380Y1533336I0J-1202D01*
G01Y1533335D01*
G02X200220Y1532736I-1203J1D01*
G01X198675Y1530063D01*
X198673Y1530059D01*
G02X197603Y1529406I-1070J550D01*
G01X197601D01*
G02X196400Y1530608I1J1202D01*
G01Y1530610D01*
G02X196550Y1531189I1203J-3D01*
G01X198116Y1533899D01*
G37*
G36*
G01X202843Y1533902D02*
G02X203903Y1534538I1060J-565D01*
G01X203905D01*
G02X205106Y1533336I-1J-1202D01*
G02X204945Y1532736I-1204J1D01*
G01X203400Y1530063D01*
X203398Y1530059D01*
G02X202328Y1529406I-1070J550D01*
G02X201126Y1530608I0J1202D01*
G01Y1530610D01*
G02X201275Y1531189I1202J-1D01*
G01X202841Y1533899D01*
X202843Y1533902D01*
G37*
G36*
G01X207567D02*
G02X208627Y1534538I1060J-565D01*
G01X208629D01*
G02X209830Y1533336I-1J-1202D01*
G02X209669Y1532736I-1204J1D01*
G01X208124Y1530063D01*
X208122Y1530059D01*
G02X207052Y1529406I-1070J550D01*
G02X205850Y1530608I0J1202D01*
G01Y1530610D01*
G02X205999Y1531189I1202J-1D01*
G01X207565Y1533899D01*
X207567Y1533902D01*
G37*
G36*
G01X212290Y1533899D02*
X212292Y1533902D01*
G02X213352Y1534538I1060J-565D01*
G02X214554Y1533336I0J-1202D01*
G01Y1533335D01*
G02X214394Y1532736I-1203J1D01*
G01X212849Y1530063D01*
X212847Y1530059D01*
G02X211777Y1529406I-1070J550D01*
G01X211775D01*
G02X210574Y1530608I1J1202D01*
G01Y1530610D01*
G02X210724Y1531189I1203J-3D01*
G01X212290Y1533899D01*
G37*
G36*
G01X217014D02*
X217016Y1533902D01*
G02X218076Y1534538I1060J-565D01*
G02X219278Y1533336I0J-1202D01*
G01Y1533335D01*
G02X219118Y1532736I-1203J1D01*
G01X217573Y1530063D01*
X217571Y1530059D01*
G02X216501Y1529406I-1070J550D01*
G01X216499D01*
G02X215298Y1530608I1J1202D01*
G01Y1530610D01*
G02X215448Y1531189I1203J-3D01*
G01X217014Y1533899D01*
G37*
G36*
G01X221738D02*
X221740Y1533902D01*
G02X222800Y1534538I1060J-565D01*
G02X224002Y1533336I0J-1202D01*
G01Y1533335D01*
G02X223842Y1532736I-1203J1D01*
G01X222297Y1530063D01*
X222295Y1530059D01*
G02X221225Y1529406I-1070J550D01*
G01X221223D01*
G02X220022Y1530608I1J1202D01*
G01Y1530610D01*
G02X220172Y1531189I1203J-3D01*
G01X221738Y1533899D01*
G37*
G36*
G01X226465Y1533902D02*
G02X227525Y1534538I1060J-565D01*
G01X227527D01*
G02X228728Y1533336I-1J-1202D01*
G02X228567Y1532736I-1204J1D01*
G01X227022Y1530063D01*
X227020Y1530059D01*
G02X225950Y1529406I-1070J550D01*
G02X224748Y1530608I0J1202D01*
G01Y1530610D01*
G02X224897Y1531189I1202J-1D01*
G01X226463Y1533899D01*
X226465Y1533902D01*
G37*
G36*
G01X231189D02*
G02X232249Y1534538I1060J-565D01*
G01X232251D01*
G02X233452Y1533336I-1J-1202D01*
G02X233291Y1532736I-1204J1D01*
G01X231746Y1530063D01*
X231744Y1530059D01*
G02X230674Y1529406I-1070J550D01*
G02X229472Y1530608I0J1202D01*
G01Y1530610D01*
G02X229621Y1531189I1202J-1D01*
G01X231187Y1533899D01*
X231189Y1533902D01*
G37*
G36*
G01X235912Y1533899D02*
X235914Y1533902D01*
G02X236974Y1534538I1060J-565D01*
G02X238176Y1533336I0J-1202D01*
G01Y1533335D01*
G02X238016Y1532736I-1203J1D01*
G01X236471Y1530063D01*
X236469Y1530059D01*
G02X235399Y1529406I-1070J550D01*
G01X235397D01*
G02X234196Y1530608I1J1202D01*
G01Y1530610D01*
G02X234346Y1531189I1203J-3D01*
G01X235912Y1533899D01*
G37*
G36*
G01X240636D02*
X240638Y1533902D01*
G02X241698Y1534538I1060J-565D01*
G02X242900Y1533336I0J-1202D01*
G01Y1533335D01*
G02X242740Y1532736I-1203J1D01*
G01X241195Y1530063D01*
X241193Y1530059D01*
G02X240123Y1529406I-1070J550D01*
G01X240121D01*
G02X238920Y1530608I1J1202D01*
G01Y1530610D01*
G02X239070Y1531189I1203J-3D01*
G01X240636Y1533899D01*
G37*
G36*
G01X245360D02*
X245362Y1533902D01*
G02X246422Y1534538I1060J-565D01*
G02X247624Y1533336I0J-1202D01*
G01Y1533335D01*
G02X247464Y1532736I-1203J1D01*
G01X245919Y1530063D01*
X245917Y1530059D01*
G02X244847Y1529406I-1070J550D01*
G01X244845D01*
G02X243644Y1530608I1J1202D01*
G01Y1530610D01*
G02X243794Y1531189I1203J-3D01*
G01X245360Y1533899D01*
G37*
G36*
G01X250087Y1533902D02*
G02X251147Y1534538I1060J-565D01*
G01X251149D01*
G02X252350Y1533336I-1J-1202D01*
G02X252189Y1532736I-1204J1D01*
G01X250644Y1530063D01*
X250642Y1530059D01*
G02X249572Y1529406I-1070J550D01*
G02X248370Y1530608I0J1202D01*
G01Y1530610D01*
G02X248519Y1531189I1202J-1D01*
G01X250085Y1533899D01*
X250087Y1533902D01*
G37*
G36*
G01X254811D02*
G02X255871Y1534538I1060J-565D01*
G01X255873D01*
G02X257074Y1533336I-1J-1202D01*
G02X256913Y1532736I-1204J1D01*
G01X255368Y1530063D01*
X255366Y1530059D01*
G02X254296Y1529406I-1070J550D01*
G02X253094Y1530608I0J1202D01*
G01Y1530610D01*
G02X253243Y1531189I1202J-1D01*
G01X254809Y1533899D01*
X254811Y1533902D01*
G37*
G36*
G01X259534Y1533899D02*
X259536Y1533902D01*
G02X260596Y1534538I1060J-565D01*
G02X261798Y1533336I0J-1202D01*
G01Y1533335D01*
G02X261638Y1532736I-1203J1D01*
G01X260093Y1530063D01*
X260091Y1530059D01*
G02X259021Y1529406I-1070J550D01*
G01X259019D01*
G02X257818Y1530608I1J1202D01*
G01Y1530610D01*
G02X257968Y1531189I1203J-3D01*
G01X259534Y1533899D01*
G37*
G36*
G01X316728Y1533895D02*
X316729Y1533898D01*
G02X317792Y1534538I1063J-563D01*
G02X318994Y1533336I0J-1202D01*
G01Y1533335D01*
G02X318841Y1532748I-1202J0D01*
G01X318836Y1532738D01*
X318835D01*
X318834Y1532736D01*
X317291Y1530066D01*
X317289Y1530061D01*
G02X315030Y1530800I-1072J545D01*
G02X315164Y1531189I1187J-191D01*
G01X316728Y1533895D01*
G37*
G36*
G01X321452D02*
X321453Y1533898D01*
G02X322516Y1534538I1063J-563D01*
G02X323718Y1533336I0J-1202D01*
G01Y1533335D01*
G02X323565Y1532748I-1202J0D01*
G01X323560Y1532738D01*
X323559D01*
X323558Y1532736D01*
X322015Y1530066D01*
X322013Y1530061D01*
G02X319754Y1530800I-1072J545D01*
G02X319888Y1531189I1187J-191D01*
G01X321452Y1533895D01*
G37*
G36*
G01X326176D02*
X326177Y1533898D01*
G02X327240Y1534538I1063J-563D01*
G02X328442Y1533336I0J-1202D01*
G01Y1533335D01*
G02X328289Y1532748I-1202J0D01*
G01X328284Y1532738D01*
X328283D01*
X328282Y1532736D01*
X326739Y1530066D01*
X326737Y1530061D01*
G02X324478Y1530800I-1072J545D01*
G02X324612Y1531189I1187J-191D01*
G01X326176Y1533895D01*
G37*
G36*
G01X330902Y1533898D02*
G02X331965Y1534538I1063J-563D01*
G01X331967D01*
G02X333168Y1533336I-1J-1202D01*
G01Y1533335D01*
G02X333014Y1532748I-1203J2D01*
G01X333009Y1532738D01*
X333008D01*
X333007Y1532736D01*
X331464Y1530066D01*
X331462Y1530061D01*
G02X329203Y1530800I-1072J545D01*
G02X329337Y1531189I1187J-191D01*
G01X330901Y1533895D01*
X330902Y1533898D01*
G37*
G36*
G01X335626D02*
G02X336689Y1534538I1063J-563D01*
G01X336691D01*
G02X337892Y1533336I-1J-1202D01*
G01Y1533335D01*
G02X337738Y1532748I-1203J2D01*
G01X337733Y1532738D01*
X337732D01*
X337731Y1532736D01*
X336188Y1530066D01*
X336186Y1530061D01*
G02X333927Y1530800I-1072J545D01*
G02X334061Y1531189I1187J-191D01*
G01X335625Y1533895D01*
X335626Y1533898D01*
G37*
G36*
G01X340350Y1533895D02*
X340351Y1533898D01*
G02X341414Y1534538I1063J-563D01*
G02X342616Y1533336I0J-1202D01*
G01Y1533335D01*
G02X342463Y1532748I-1202J0D01*
G01X342458Y1532738D01*
X342457D01*
X342456Y1532736D01*
X340913Y1530066D01*
X340911Y1530061D01*
G02X338652Y1530800I-1072J545D01*
G02X338786Y1531189I1187J-191D01*
G01X340350Y1533895D01*
G37*
G36*
G01X345074D02*
X345075Y1533898D01*
G02X346138Y1534538I1063J-563D01*
G02X347340Y1533336I0J-1202D01*
G01Y1533335D01*
G02X347187Y1532748I-1202J0D01*
G01X347182Y1532738D01*
X347181D01*
X347180Y1532736D01*
X345637Y1530066D01*
X345635Y1530061D01*
G02X343376Y1530800I-1072J545D01*
G02X343510Y1531189I1187J-191D01*
G01X345074Y1533895D01*
G37*
G36*
G01X349798D02*
X349799Y1533898D01*
G02X350862Y1534538I1063J-563D01*
G02X352064Y1533336I0J-1202D01*
G01Y1533335D01*
G02X351911Y1532748I-1202J0D01*
G01X351906Y1532738D01*
X351905D01*
X351904Y1532736D01*
X350361Y1530066D01*
X350359Y1530061D01*
G02X348100Y1530800I-1072J545D01*
G02X348234Y1531189I1187J-191D01*
G01X349798Y1533895D01*
G37*
G36*
G01X354524Y1533898D02*
G02X355587Y1534538I1063J-563D01*
G01X355589D01*
G02X356790Y1533336I-1J-1202D01*
G01Y1533335D01*
G02X356636Y1532748I-1203J2D01*
G01X356631Y1532738D01*
X356630D01*
X356629Y1532736D01*
X355086Y1530066D01*
X355084Y1530061D01*
G02X352825Y1530800I-1072J545D01*
G02X352959Y1531189I1187J-191D01*
G01X354523Y1533895D01*
X354524Y1533898D01*
G37*
G36*
G01X359248D02*
G02X360311Y1534538I1063J-563D01*
G01X360313D01*
G02X361514Y1533336I-1J-1202D01*
G01Y1533335D01*
G02X361360Y1532748I-1203J2D01*
G01X361355Y1532738D01*
X361354D01*
X361353Y1532736D01*
X359810Y1530066D01*
X359808Y1530061D01*
G02X357549Y1530800I-1072J545D01*
G02X357683Y1531189I1187J-191D01*
G01X359247Y1533895D01*
X359248Y1533898D01*
G37*
G36*
G01X363972Y1533895D02*
X363973Y1533898D01*
G02X365036Y1534538I1063J-563D01*
G02X366238Y1533336I0J-1202D01*
G01Y1533335D01*
G02X366085Y1532748I-1202J0D01*
G01X366080Y1532738D01*
X366079D01*
X366078Y1532736D01*
X364535Y1530066D01*
X364533Y1530061D01*
G02X362274Y1530800I-1072J545D01*
G02X362408Y1531189I1187J-191D01*
G01X363972Y1533895D01*
G37*
G36*
G01X368696D02*
X368697Y1533898D01*
G02X369760Y1534538I1063J-563D01*
G02X370962Y1533336I0J-1202D01*
G01Y1533335D01*
G02X370809Y1532748I-1202J0D01*
G01X370804Y1532738D01*
X370803D01*
X370802Y1532736D01*
X369259Y1530066D01*
X369257Y1530061D01*
G02X366998Y1530800I-1072J545D01*
G02X367132Y1531189I1187J-191D01*
G01X368696Y1533895D01*
G37*
G36*
G01X373420D02*
X373421Y1533898D01*
G02X374484Y1534538I1063J-563D01*
G02X375686Y1533336I0J-1202D01*
G01Y1533335D01*
G02X375533Y1532748I-1202J0D01*
G01X375528Y1532738D01*
X375527D01*
X375526Y1532736D01*
X373983Y1530066D01*
X373981Y1530061D01*
G02X371722Y1530800I-1072J545D01*
G02X371856Y1531189I1187J-191D01*
G01X373420Y1533895D01*
G37*
G36*
G01X378146Y1533898D02*
G02X379209Y1534538I1063J-563D01*
G01X379211D01*
G02X380412Y1533336I-1J-1202D01*
G01Y1533335D01*
G02X380258Y1532748I-1203J2D01*
G01X380253Y1532738D01*
X380252D01*
X380251Y1532736D01*
X378708Y1530066D01*
X378706Y1530061D01*
G02X376447Y1530800I-1072J545D01*
G02X376581Y1531189I1187J-191D01*
G01X378145Y1533895D01*
X378146Y1533898D01*
G37*
G36*
G01X382870D02*
G02X383933Y1534538I1063J-563D01*
G01X383935D01*
G02X385136Y1533336I-1J-1202D01*
G01Y1533335D01*
G02X384982Y1532748I-1203J2D01*
G01X384977Y1532738D01*
X384976D01*
X384975Y1532736D01*
X383432Y1530066D01*
X383430Y1530061D01*
G02X381171Y1530800I-1072J545D01*
G02X381305Y1531189I1187J-191D01*
G01X382869Y1533895D01*
X382870Y1533898D01*
G37*
G36*
G01X387594Y1533895D02*
X387595Y1533898D01*
G02X388658Y1534538I1063J-563D01*
G02X389860Y1533336I0J-1202D01*
G01Y1533335D01*
G02X389707Y1532748I-1202J0D01*
G01X389702Y1532738D01*
X389701D01*
X389700Y1532736D01*
X388157Y1530066D01*
X388155Y1530061D01*
G02X385896Y1530800I-1072J545D01*
G02X386030Y1531189I1187J-191D01*
G01X387594Y1533895D01*
G37*
G36*
G01X452843Y1533902D02*
G02X453903Y1534538I1060J-565D01*
G01X453905D01*
G02X455106Y1533336I-1J-1202D01*
G02X454945Y1532736I-1204J1D01*
G01X453400Y1530063D01*
X453398Y1530059D01*
G02X452328Y1529406I-1070J550D01*
G02X451126Y1530608I0J1202D01*
G01Y1530610D01*
G02X451275Y1531189I1202J-1D01*
G01X452841Y1533899D01*
X452843Y1533902D01*
G37*
G36*
G01X457567D02*
G02X458627Y1534538I1060J-565D01*
G01X458629D01*
G02X459830Y1533336I-1J-1202D01*
G02X459669Y1532736I-1204J1D01*
G01X458124Y1530063D01*
X458122Y1530059D01*
G02X457052Y1529406I-1070J550D01*
G02X455850Y1530608I0J1202D01*
G01Y1530610D01*
G02X455999Y1531189I1202J-1D01*
G01X457565Y1533899D01*
X457567Y1533902D01*
G37*
G36*
G01X462291D02*
G02X463351Y1534538I1060J-565D01*
G01X463353D01*
G02X464554Y1533336I-1J-1202D01*
G02X464393Y1532736I-1204J1D01*
G01X462848Y1530063D01*
X462846Y1530059D01*
G02X461776Y1529406I-1070J550D01*
G02X460574Y1530608I0J1202D01*
G01Y1530610D01*
G02X460723Y1531189I1202J-1D01*
G01X462289Y1533899D01*
X462291Y1533902D01*
G37*
G36*
G01X467014Y1533899D02*
X467016Y1533902D01*
G02X468076Y1534538I1060J-565D01*
G02X469278Y1533336I0J-1202D01*
G01Y1533335D01*
G02X469118Y1532736I-1203J1D01*
G01X467573Y1530063D01*
X467571Y1530059D01*
G02X466501Y1529406I-1070J550D01*
G01X466499D01*
G02X465298Y1530608I1J1202D01*
G01Y1530610D01*
G02X465448Y1531189I1203J-3D01*
G01X467014Y1533899D01*
G37*
G36*
G01X471738D02*
X471740Y1533902D01*
G02X472800Y1534538I1060J-565D01*
G02X474002Y1533336I0J-1202D01*
G01Y1533335D01*
G02X473842Y1532736I-1203J1D01*
G01X472297Y1530063D01*
X472295Y1530059D01*
G02X471225Y1529406I-1070J550D01*
G01X471223D01*
G02X470022Y1530608I1J1202D01*
G01Y1530610D01*
G02X470172Y1531189I1203J-3D01*
G01X471738Y1533899D01*
G37*
G36*
G01X476465Y1533902D02*
G02X477525Y1534538I1060J-565D01*
G01X477527D01*
G02X478728Y1533336I-1J-1202D01*
G02X478567Y1532736I-1204J1D01*
G01X477022Y1530063D01*
X477020Y1530059D01*
G02X475950Y1529406I-1070J550D01*
G02X474748Y1530608I0J1202D01*
G01Y1530610D01*
G02X474897Y1531189I1202J-1D01*
G01X476463Y1533899D01*
X476465Y1533902D01*
G37*
G36*
G01X481189D02*
G02X482249Y1534538I1060J-565D01*
G01X482251D01*
G02X483452Y1533336I-1J-1202D01*
G02X483291Y1532736I-1204J1D01*
G01X481746Y1530063D01*
X481744Y1530059D01*
G02X480674Y1529406I-1070J550D01*
G02X479472Y1530608I0J1202D01*
G01Y1530610D01*
G02X479621Y1531189I1202J-1D01*
G01X481187Y1533899D01*
X481189Y1533902D01*
G37*
G36*
G01X485913D02*
G02X486973Y1534538I1060J-565D01*
G01X486975D01*
G02X488176Y1533336I-1J-1202D01*
G02X488015Y1532736I-1204J1D01*
G01X486470Y1530063D01*
X486468Y1530059D01*
G02X485398Y1529406I-1070J550D01*
G02X484196Y1530608I0J1202D01*
G01Y1530610D01*
G02X484345Y1531189I1202J-1D01*
G01X485911Y1533899D01*
X485913Y1533902D01*
G37*
G36*
G01X490636Y1533899D02*
X490638Y1533902D01*
G02X491698Y1534538I1060J-565D01*
G02X492900Y1533336I0J-1202D01*
G01Y1533335D01*
G02X492740Y1532736I-1203J1D01*
G01X491195Y1530063D01*
X491193Y1530059D01*
G02X490123Y1529406I-1070J550D01*
G01X490121D01*
G02X488920Y1530608I1J1202D01*
G01Y1530610D01*
G02X489070Y1531189I1203J-3D01*
G01X490636Y1533899D01*
G37*
G36*
G01X495360D02*
X495362Y1533902D01*
G02X496422Y1534538I1060J-565D01*
G02X497624Y1533336I0J-1202D01*
G01Y1533335D01*
G02X497464Y1532736I-1203J1D01*
G01X495919Y1530063D01*
X495917Y1530059D01*
G02X494847Y1529406I-1070J550D01*
G01X494845D01*
G02X493644Y1530608I1J1202D01*
G01Y1530610D01*
G02X493794Y1531189I1203J-3D01*
G01X495360Y1533899D01*
G37*
G36*
G01X500087Y1533902D02*
G02X501147Y1534538I1060J-565D01*
G01X501149D01*
G02X502350Y1533336I-1J-1202D01*
G02X502189Y1532736I-1204J1D01*
G01X500644Y1530063D01*
X500642Y1530059D01*
G02X499572Y1529406I-1070J550D01*
G02X498370Y1530608I0J1202D01*
G01Y1530610D01*
G02X498519Y1531189I1202J-1D01*
G01X500085Y1533899D01*
X500087Y1533902D01*
G37*
G36*
G01X504811D02*
G02X505871Y1534538I1060J-565D01*
G01X505873D01*
G02X507074Y1533336I-1J-1202D01*
G02X506913Y1532736I-1204J1D01*
G01X505368Y1530063D01*
X505366Y1530059D01*
G02X504296Y1529406I-1070J550D01*
G02X503094Y1530608I0J1202D01*
G01Y1530610D01*
G02X503243Y1531189I1202J-1D01*
G01X504809Y1533899D01*
X504811Y1533902D01*
G37*
G36*
G01X509535D02*
G02X510595Y1534538I1060J-565D01*
G01X510597D01*
G02X511798Y1533336I-1J-1202D01*
G02X511637Y1532736I-1204J1D01*
G01X510092Y1530063D01*
X510090Y1530059D01*
G02X509020Y1529406I-1070J550D01*
G02X507818Y1530608I0J1202D01*
G01Y1530610D01*
G02X507967Y1531189I1202J-1D01*
G01X509533Y1533899D01*
X509535Y1533902D01*
G37*
G36*
G01X514258Y1533899D02*
X514260Y1533902D01*
G02X515320Y1534538I1060J-565D01*
G02X516522Y1533336I0J-1202D01*
G01Y1533335D01*
G02X516362Y1532736I-1203J1D01*
G01X514817Y1530063D01*
X514815Y1530059D01*
G02X513745Y1529406I-1070J550D01*
G01X513743D01*
G02X512542Y1530608I1J1202D01*
G01Y1530610D01*
G02X512692Y1531189I1203J-3D01*
G01X514258Y1533899D01*
G37*
G36*
G01X518982D02*
X518984Y1533902D01*
G02X520044Y1534538I1060J-565D01*
G02X521246Y1533336I0J-1202D01*
G01Y1533335D01*
G02X521086Y1532736I-1203J1D01*
G01X519541Y1530063D01*
X519539Y1530059D01*
G02X518469Y1529406I-1070J550D01*
G01X518467D01*
G02X517266Y1530608I1J1202D01*
G01Y1530610D01*
G02X517416Y1531189I1203J-3D01*
G01X518982Y1533899D01*
G37*
G36*
G01X523709Y1533902D02*
G02X524769Y1534538I1060J-565D01*
G01X524771D01*
G02X525972Y1533336I-1J-1202D01*
G02X525811Y1532736I-1204J1D01*
G01X524266Y1530063D01*
X524264Y1530059D01*
G02X523194Y1529406I-1070J550D01*
G02X521992Y1530608I0J1202D01*
G01Y1530610D01*
G02X522141Y1531189I1202J-1D01*
G01X523707Y1533899D01*
X523709Y1533902D01*
G37*
G36*
G01X580905D02*
G02X581965Y1534538I1060J-565D01*
G01X581967D01*
G02X583168Y1533336I-1J-1202D01*
G02X583007Y1532736I-1204J1D01*
G01X581462Y1530063D01*
X581460Y1530059D01*
G02X580390Y1529406I-1070J550D01*
G02X579188Y1530608I0J1202D01*
G01Y1530610D01*
G02X579337Y1531189I1202J-1D01*
G01X580903Y1533899D01*
X580905Y1533902D01*
G37*
G36*
G01X585629D02*
G02X586689Y1534538I1060J-565D01*
G01X586691D01*
G02X587892Y1533336I-1J-1202D01*
G02X587731Y1532736I-1204J1D01*
G01X586186Y1530063D01*
X586184Y1530059D01*
G02X585114Y1529406I-1070J550D01*
G02X583912Y1530608I0J1202D01*
G01Y1530610D01*
G02X584061Y1531189I1202J-1D01*
G01X585627Y1533899D01*
X585629Y1533902D01*
G37*
G36*
G01X590353D02*
G02X591413Y1534538I1060J-565D01*
G01X591415D01*
G02X592616Y1533336I-1J-1202D01*
G02X592455Y1532736I-1204J1D01*
G01X590910Y1530063D01*
X590908Y1530059D01*
G02X589838Y1529406I-1070J550D01*
G02X588636Y1530608I0J1202D01*
G01Y1530610D01*
G02X588785Y1531189I1202J-1D01*
G01X590351Y1533899D01*
X590353Y1533902D01*
G37*
G36*
G01X595076Y1533899D02*
X595078Y1533902D01*
G02X596138Y1534538I1060J-565D01*
G02X597340Y1533336I0J-1202D01*
G01Y1533335D01*
G02X597180Y1532736I-1203J1D01*
G01X595635Y1530063D01*
X595633Y1530059D01*
G02X594563Y1529406I-1070J550D01*
G01X594561D01*
G02X593360Y1530608I1J1202D01*
G01Y1530610D01*
G02X593510Y1531189I1203J-3D01*
G01X595076Y1533899D01*
G37*
G36*
G01X599800D02*
X599802Y1533902D01*
G02X600862Y1534538I1060J-565D01*
G02X602064Y1533336I0J-1202D01*
G01Y1533335D01*
G02X601904Y1532736I-1203J1D01*
G01X600359Y1530063D01*
X600357Y1530059D01*
G02X599287Y1529406I-1070J550D01*
G01X599285D01*
G02X598084Y1530608I1J1202D01*
G01Y1530610D01*
G02X598234Y1531189I1203J-3D01*
G01X599800Y1533899D01*
G37*
G36*
G01X604527Y1533902D02*
G02X605587Y1534538I1060J-565D01*
G01X605589D01*
G02X606790Y1533336I-1J-1202D01*
G02X606629Y1532736I-1204J1D01*
G01X605084Y1530063D01*
X605082Y1530059D01*
G02X604012Y1529406I-1070J550D01*
G02X602810Y1530608I0J1202D01*
G01Y1530610D01*
G02X602959Y1531189I1202J-1D01*
G01X604525Y1533899D01*
X604527Y1533902D01*
G37*
G36*
G01X609251D02*
G02X610311Y1534538I1060J-565D01*
G01X610313D01*
G02X611514Y1533336I-1J-1202D01*
G02X611353Y1532736I-1204J1D01*
G01X609808Y1530063D01*
X609806Y1530059D01*
G02X608736Y1529406I-1070J550D01*
G02X607534Y1530608I0J1202D01*
G01Y1530610D01*
G02X607683Y1531189I1202J-1D01*
G01X609249Y1533899D01*
X609251Y1533902D01*
G37*
G36*
G01X613975D02*
G02X615035Y1534538I1060J-565D01*
G01X615037D01*
G02X616238Y1533336I-1J-1202D01*
G02X616077Y1532736I-1204J1D01*
G01X614532Y1530063D01*
X614530Y1530059D01*
G02X613460Y1529406I-1070J550D01*
G02X612258Y1530608I0J1202D01*
G01Y1530610D01*
G02X612407Y1531189I1202J-1D01*
G01X613973Y1533899D01*
X613975Y1533902D01*
G37*
G36*
G01X618698Y1533899D02*
X618700Y1533902D01*
G02X619760Y1534538I1060J-565D01*
G02X620962Y1533336I0J-1202D01*
G01Y1533335D01*
G02X620802Y1532736I-1203J1D01*
G01X619257Y1530063D01*
X619255Y1530059D01*
G02X618185Y1529406I-1070J550D01*
G01X618183D01*
G02X616982Y1530608I1J1202D01*
G01Y1530610D01*
G02X617132Y1531189I1203J-3D01*
G01X618698Y1533899D01*
G37*
G36*
G01X623422D02*
X623424Y1533902D01*
G02X624484Y1534538I1060J-565D01*
G02X625686Y1533336I0J-1202D01*
G01Y1533335D01*
G02X625526Y1532736I-1203J1D01*
G01X623981Y1530063D01*
X623979Y1530059D01*
G02X622909Y1529406I-1070J550D01*
G01X622907D01*
G02X621706Y1530608I1J1202D01*
G01Y1530610D01*
G02X621856Y1531189I1203J-3D01*
G01X623422Y1533899D01*
G37*
G36*
G01X628149Y1533902D02*
G02X629209Y1534538I1060J-565D01*
G01X629211D01*
G02X630412Y1533336I-1J-1202D01*
G02X630251Y1532736I-1204J1D01*
G01X628706Y1530063D01*
X628704Y1530059D01*
G02X627634Y1529406I-1070J550D01*
G02X626432Y1530608I0J1202D01*
G01Y1530610D01*
G02X626581Y1531189I1202J-1D01*
G01X628147Y1533899D01*
X628149Y1533902D01*
G37*
G36*
G01X632873D02*
G02X633933Y1534538I1060J-565D01*
G01X633935D01*
G02X635136Y1533336I-1J-1202D01*
G02X634975Y1532736I-1204J1D01*
G01X633430Y1530063D01*
X633428Y1530059D01*
G02X632358Y1529406I-1070J550D01*
G02X631156Y1530608I0J1202D01*
G01Y1530610D01*
G02X631305Y1531189I1202J-1D01*
G01X632871Y1533899D01*
X632873Y1533902D01*
G37*
G36*
G01X637597D02*
G02X638657Y1534538I1060J-565D01*
G01X638659D01*
G02X639860Y1533336I-1J-1202D01*
G02X639699Y1532736I-1204J1D01*
G01X638154Y1530063D01*
X638152Y1530059D01*
G02X637082Y1529406I-1070J550D01*
G02X635880Y1530608I0J1202D01*
G01Y1530610D01*
G02X636029Y1531189I1202J-1D01*
G01X637595Y1533899D01*
X637597Y1533902D01*
G37*
G36*
G01X642320Y1533899D02*
X642322Y1533902D01*
G02X643382Y1534538I1060J-565D01*
G02X644584Y1533336I0J-1202D01*
G01Y1533335D01*
G02X644424Y1532736I-1203J1D01*
G01X642879Y1530063D01*
X642877Y1530059D01*
G02X641807Y1529406I-1070J550D01*
G01X641805D01*
G02X640604Y1530608I1J1202D01*
G01Y1530610D01*
G02X640754Y1531189I1203J-3D01*
G01X642320Y1533899D01*
G37*
G36*
G01X647044D02*
X647046Y1533902D01*
G02X648106Y1534538I1060J-565D01*
G02X649308Y1533336I0J-1202D01*
G01Y1533335D01*
G02X649148Y1532736I-1203J1D01*
G01X647603Y1530063D01*
X647601Y1530059D01*
G02X646531Y1529406I-1070J550D01*
G01X646529D01*
G02X645328Y1530608I1J1202D01*
G01Y1530610D01*
G02X645478Y1531189I1203J-3D01*
G01X647044Y1533899D01*
G37*
G36*
G01X651771Y1533902D02*
G02X652831Y1534538I1060J-565D01*
G01X652833D01*
G02X654034Y1533336I-1J-1202D01*
G02X653873Y1532736I-1204J1D01*
G01X652328Y1530063D01*
X652326Y1530059D01*
G02X651256Y1529406I-1070J550D01*
G02X650054Y1530608I0J1202D01*
G01Y1530610D01*
G02X650203Y1531189I1202J-1D01*
G01X651769Y1533899D01*
X651771Y1533902D01*
G37*
G36*
G01X1196543Y1553264D02*
G02X1197603Y1553900I1060J-565D01*
G01X1197605D01*
G02X1198806Y1552698I-1J-1202D01*
G02X1198645Y1552098I-1204J1D01*
G01X1197100Y1549425D01*
X1197098Y1549421D01*
G02X1196028Y1548768I-1070J550D01*
G02X1194826Y1549970I0J1202D01*
G01Y1549972D01*
G02X1194975Y1550551I1202J-1D01*
G01X1196541Y1553261D01*
X1196543Y1553264D01*
G37*
G36*
G01X1201267D02*
G02X1202327Y1553900I1060J-565D01*
G01X1202329D01*
G02X1203530Y1552698I-1J-1202D01*
G02X1203369Y1552098I-1204J1D01*
G01X1201824Y1549425D01*
X1201822Y1549421D01*
G02X1200752Y1548768I-1070J550D01*
G02X1199550Y1549970I0J1202D01*
G01Y1549972D01*
G02X1199699Y1550551I1202J-1D01*
G01X1201265Y1553261D01*
X1201267Y1553264D01*
G37*
G36*
G01X1205991D02*
G02X1207051Y1553900I1060J-565D01*
G01X1207052D01*
G02X1208254Y1552698I0J-1202D01*
G01Y1552697D01*
G02X1208094Y1552098I-1203J1D01*
G01X1206549Y1549425D01*
X1206547Y1549421D01*
G02X1205477Y1548768I-1070J550D01*
G01X1205476D01*
G02X1204274Y1549970I0J1202D01*
G01Y1549972D01*
G02X1204423Y1550551I1202J-1D01*
G01X1205989Y1553261D01*
X1205991Y1553264D01*
G37*
G36*
G01X1210714Y1553261D02*
X1210716Y1553264D01*
G02X1211776Y1553900I1060J-565D01*
G02X1212978Y1552698I0J-1202D01*
G01Y1552697D01*
G02X1212818Y1552098I-1203J1D01*
G01X1211273Y1549425D01*
X1211271Y1549421D01*
G02X1210201Y1548768I-1070J550D01*
G01X1210199D01*
G02X1208998Y1549970I1J1202D01*
G01Y1549972D01*
G02X1209148Y1550551I1203J-3D01*
G01X1210714Y1553261D01*
G37*
G36*
G01X1215438D02*
X1215440Y1553264D01*
G02X1216500Y1553900I1060J-565D01*
G02X1217702Y1552698I0J-1202D01*
G01Y1552697D01*
G02X1217542Y1552098I-1203J1D01*
G01X1215997Y1549425D01*
X1215995Y1549421D01*
G02X1214925Y1548768I-1070J550D01*
G01X1214923D01*
G02X1213722Y1549970I1J1202D01*
G01Y1549972D01*
G02X1213872Y1550551I1203J-3D01*
G01X1215438Y1553261D01*
G37*
G36*
G01X1220165Y1553264D02*
G02X1221225Y1553900I1060J-565D01*
G01X1221227D01*
G02X1222428Y1552698I-1J-1202D01*
G02X1222267Y1552098I-1204J1D01*
G01X1220722Y1549425D01*
X1220720Y1549421D01*
G02X1219650Y1548768I-1070J550D01*
G02X1218448Y1549970I0J1202D01*
G01Y1549972D01*
G02X1218597Y1550551I1202J-1D01*
G01X1220163Y1553261D01*
X1220165Y1553264D01*
G37*
G36*
G01X1224889D02*
G02X1225949Y1553900I1060J-565D01*
G01X1225951D01*
G02X1227152Y1552698I-1J-1202D01*
G02X1226991Y1552098I-1204J1D01*
G01X1225446Y1549425D01*
X1225444Y1549421D01*
G02X1224374Y1548768I-1070J550D01*
G02X1223172Y1549970I0J1202D01*
G01Y1549972D01*
G02X1223321Y1550551I1202J-1D01*
G01X1224887Y1553261D01*
X1224889Y1553264D01*
G37*
G36*
G01X1229613D02*
G02X1230673Y1553900I1060J-565D01*
G01X1230674D01*
G02X1231876Y1552698I0J-1202D01*
G01Y1552697D01*
G02X1231716Y1552098I-1203J1D01*
G01X1230171Y1549425D01*
X1230169Y1549421D01*
G02X1229099Y1548768I-1070J550D01*
G01X1229098D01*
G02X1227896Y1549970I0J1202D01*
G01Y1549972D01*
G02X1228045Y1550551I1202J-1D01*
G01X1229611Y1553261D01*
X1229613Y1553264D01*
G37*
G36*
G01X1239060Y1553261D02*
X1239062Y1553264D01*
G02X1240122Y1553900I1060J-565D01*
G02X1241324Y1552698I0J-1202D01*
G01Y1552696D01*
G02X1241237Y1552248I-1203J1D01*
G02X1241162Y1552093I-1118J445D01*
G01X1239617Y1549420D01*
X1239615Y1549416D01*
G02X1238545Y1548762I-1070J548D01*
G02X1237342Y1549965I0J1203D01*
G01Y1549967D01*
G02X1237430Y1550414I1203J-5D01*
G01Y1550416D01*
G02X1237494Y1550551I1117J-447D01*
G01X1239060Y1553261D01*
G37*
G36*
G01X1248511Y1553264D02*
G02X1249571Y1553900I1060J-565D01*
G01X1249573D01*
G02X1250774Y1552698I-1J-1202D01*
G02X1250686Y1552248I-1204J2D01*
G02X1250611Y1552093I-1118J445D01*
G01X1249066Y1549420D01*
X1249064Y1549416D01*
G02X1247994Y1548762I-1070J548D01*
G02X1246792Y1549965I1J1203D01*
G01Y1549967D01*
G02X1246879Y1550415I1202J-1D01*
G02X1246943Y1550551I1118J-443D01*
G01X1248509Y1553261D01*
X1248511Y1553264D01*
G37*
G36*
G01X1257958Y1553261D02*
X1257960Y1553264D01*
G02X1259020Y1553900I1060J-565D01*
G02X1260222Y1552698I0J-1202D01*
G01Y1552696D01*
G02X1260135Y1552248I-1203J1D01*
G02X1260060Y1552093I-1118J445D01*
G01X1258515Y1549420D01*
X1258513Y1549416D01*
G02X1257443Y1548762I-1070J548D01*
G02X1256240Y1549965I0J1203D01*
G01Y1549967D01*
G02X1256328Y1550414I1203J-5D01*
G01Y1550416D01*
G02X1256392Y1550551I1117J-447D01*
G01X1257958Y1553261D01*
G37*
G36*
G01X1324605Y1553264D02*
G02X1325665Y1553900I1060J-565D01*
G01X1325667D01*
G02X1326868Y1552698I-1J-1202D01*
G02X1326707Y1552098I-1204J1D01*
G01X1325162Y1549425D01*
X1325160Y1549421D01*
G02X1324090Y1548768I-1070J550D01*
G02X1322888Y1549970I0J1202D01*
G01Y1549972D01*
G02X1323037Y1550551I1202J-1D01*
G01X1324603Y1553261D01*
X1324605Y1553264D01*
G37*
G36*
G01X1329329D02*
G02X1330389Y1553900I1060J-565D01*
G01X1330391D01*
G02X1331592Y1552698I-1J-1202D01*
G02X1331431Y1552098I-1204J1D01*
G01X1329886Y1549425D01*
X1329884Y1549421D01*
G02X1328814Y1548768I-1070J550D01*
G02X1327612Y1549970I0J1202D01*
G01Y1549972D01*
G02X1327761Y1550551I1202J-1D01*
G01X1329327Y1553261D01*
X1329329Y1553264D01*
G37*
G36*
G01X1334053D02*
G02X1335113Y1553900I1060J-565D01*
G01X1335114D01*
G02X1336316Y1552698I0J-1202D01*
G01Y1552697D01*
G02X1336156Y1552098I-1203J1D01*
G01X1334611Y1549425D01*
X1334609Y1549421D01*
G02X1333539Y1548768I-1070J550D01*
G01X1333538D01*
G02X1332336Y1549970I0J1202D01*
G01Y1549972D01*
G02X1332485Y1550551I1202J-1D01*
G01X1334051Y1553261D01*
X1334053Y1553264D01*
G37*
G36*
G01X1338776Y1553261D02*
X1338778Y1553264D01*
G02X1339838Y1553900I1060J-565D01*
G02X1341040Y1552698I0J-1202D01*
G01Y1552697D01*
G02X1340880Y1552098I-1203J1D01*
G01X1339335Y1549425D01*
X1339333Y1549421D01*
G02X1338263Y1548768I-1070J550D01*
G01X1338261D01*
G02X1337060Y1549970I1J1202D01*
G01Y1549972D01*
G02X1337210Y1550551I1203J-3D01*
G01X1338776Y1553261D01*
G37*
G36*
G01X1343500D02*
X1343502Y1553264D01*
G02X1344562Y1553900I1060J-565D01*
G02X1345764Y1552698I0J-1202D01*
G01Y1552697D01*
G02X1345604Y1552098I-1203J1D01*
G01X1344059Y1549425D01*
X1344057Y1549421D01*
G02X1342987Y1548768I-1070J550D01*
G01X1342985D01*
G02X1341784Y1549970I1J1202D01*
G01Y1549972D01*
G02X1341934Y1550551I1203J-3D01*
G01X1343500Y1553261D01*
G37*
G36*
G01X1348227Y1553264D02*
G02X1349287Y1553900I1060J-565D01*
G01X1349289D01*
G02X1350490Y1552698I-1J-1202D01*
G02X1350329Y1552098I-1204J1D01*
G01X1348784Y1549425D01*
X1348782Y1549421D01*
G02X1347712Y1548768I-1070J550D01*
G02X1346510Y1549970I0J1202D01*
G01Y1549972D01*
G02X1346659Y1550551I1202J-1D01*
G01X1348225Y1553261D01*
X1348227Y1553264D01*
G37*
G36*
G01X1352951D02*
G02X1354011Y1553900I1060J-565D01*
G01X1354013D01*
G02X1355214Y1552698I-1J-1202D01*
G02X1355053Y1552098I-1204J1D01*
G01X1353508Y1549425D01*
X1353506Y1549421D01*
G02X1352436Y1548768I-1070J550D01*
G02X1351234Y1549970I0J1202D01*
G01Y1549972D01*
G02X1351383Y1550551I1202J-1D01*
G01X1352949Y1553261D01*
X1352951Y1553264D01*
G37*
G36*
G01X1357675D02*
G02X1358735Y1553900I1060J-565D01*
G01X1358736D01*
G02X1359938Y1552698I0J-1202D01*
G01Y1552697D01*
G02X1359778Y1552098I-1203J1D01*
G01X1358233Y1549425D01*
X1358231Y1549421D01*
G02X1357161Y1548768I-1070J550D01*
G01X1357160D01*
G02X1355958Y1549970I0J1202D01*
G01Y1549972D01*
G02X1356107Y1550551I1202J-1D01*
G01X1357673Y1553261D01*
X1357675Y1553264D01*
G37*
G36*
G01X1362398Y1553261D02*
X1362400Y1553264D01*
G02X1363460Y1553900I1060J-565D01*
G02X1364662Y1552698I0J-1202D01*
G01Y1552697D01*
G02X1364502Y1552098I-1203J1D01*
G01X1362957Y1549425D01*
X1362955Y1549421D01*
G02X1361885Y1548768I-1070J550D01*
G01X1361883D01*
G02X1360682Y1549970I1J1202D01*
G01Y1549972D01*
G02X1360832Y1550551I1203J-3D01*
G01X1362398Y1553261D01*
G37*
G36*
G01X1367122D02*
X1367124Y1553264D01*
G02X1368184Y1553900I1060J-565D01*
G02X1369386Y1552698I0J-1202D01*
G01Y1552697D01*
G02X1369226Y1552098I-1203J1D01*
G01X1367681Y1549425D01*
X1367679Y1549421D01*
G02X1366609Y1548768I-1070J550D01*
G01X1366607D01*
G02X1365406Y1549970I1J1202D01*
G01Y1549972D01*
G02X1365556Y1550551I1203J-3D01*
G01X1367122Y1553261D01*
G37*
G36*
G01X1371849Y1553264D02*
G02X1372909Y1553900I1060J-565D01*
G01X1372911D01*
G02X1374112Y1552698I-1J-1202D01*
G02X1373951Y1552098I-1204J1D01*
G01X1372406Y1549425D01*
X1372404Y1549421D01*
G02X1371334Y1548768I-1070J550D01*
G02X1370132Y1549970I0J1202D01*
G01Y1549972D01*
G02X1370281Y1550551I1202J-1D01*
G01X1371847Y1553261D01*
X1371849Y1553264D01*
G37*
G36*
G01X1376573D02*
G02X1377633Y1553900I1060J-565D01*
G01X1377635D01*
G02X1378836Y1552698I-1J-1202D01*
G02X1378675Y1552098I-1204J1D01*
G01X1377130Y1549425D01*
X1377128Y1549421D01*
G02X1376058Y1548768I-1070J550D01*
G02X1374856Y1549970I0J1202D01*
G01Y1549972D01*
G02X1375005Y1550551I1202J-1D01*
G01X1376571Y1553261D01*
X1376573Y1553264D01*
G37*
G36*
G01X1381297D02*
G02X1382357Y1553900I1060J-565D01*
G01X1382358D01*
G02X1383560Y1552698I0J-1202D01*
G01Y1552697D01*
G02X1383400Y1552098I-1203J1D01*
G01X1381855Y1549425D01*
X1381853Y1549421D01*
G02X1380783Y1548768I-1070J550D01*
G01X1380782D01*
G02X1379580Y1549970I0J1202D01*
G01Y1549972D01*
G02X1379729Y1550551I1202J-1D01*
G01X1381295Y1553261D01*
X1381297Y1553264D01*
G37*
G36*
G01X1386020Y1553261D02*
X1386022Y1553264D01*
G02X1387082Y1553900I1060J-565D01*
G02X1388284Y1552698I0J-1202D01*
G01Y1552697D01*
G02X1388124Y1552098I-1203J1D01*
G01X1386579Y1549425D01*
X1386577Y1549421D01*
G02X1385507Y1548768I-1070J550D01*
G01X1385505D01*
G02X1384304Y1549970I1J1202D01*
G01Y1549972D01*
G02X1384454Y1550551I1203J-3D01*
G01X1386020Y1553261D01*
G37*
G36*
G01X1395471Y1553264D02*
G02X1396531Y1553900I1060J-565D01*
G01X1396533D01*
G02X1397734Y1552698I-1J-1202D01*
G02X1397573Y1552098I-1204J1D01*
G01X1396028Y1549425D01*
X1396026Y1549421D01*
G02X1394956Y1548768I-1070J550D01*
G02X1393754Y1549970I0J1202D01*
G01Y1549972D01*
G02X1393903Y1550551I1202J-1D01*
G01X1395469Y1553261D01*
X1395471Y1553264D01*
G37*
G36*
G01X1460717D02*
G02X1461777Y1553900I1060J-565D01*
G01X1461779D01*
G02X1462980Y1552698I-1J-1202D01*
G02X1462819Y1552098I-1204J1D01*
G01X1461274Y1549425D01*
X1461272Y1549421D01*
G02X1460202Y1548768I-1070J550D01*
G02X1459000Y1549970I0J1202D01*
G01Y1549972D01*
G02X1459149Y1550551I1202J-1D01*
G01X1460715Y1553261D01*
X1460717Y1553264D01*
G37*
G36*
G01X1465441D02*
G02X1466501Y1553900I1060J-565D01*
G01X1466503D01*
G02X1467704Y1552698I-1J-1202D01*
G02X1467543Y1552098I-1204J1D01*
G01X1465998Y1549425D01*
X1465996Y1549421D01*
G02X1464926Y1548768I-1070J550D01*
G02X1463724Y1549970I0J1202D01*
G01Y1549972D01*
G02X1463873Y1550551I1202J-1D01*
G01X1465439Y1553261D01*
X1465441Y1553264D01*
G37*
G36*
G01X1470165D02*
G02X1471225Y1553900I1060J-565D01*
G01X1471227D01*
G02X1472428Y1552698I-1J-1202D01*
G02X1472267Y1552098I-1204J1D01*
G01X1470722Y1549425D01*
X1470720Y1549421D01*
G02X1469650Y1548768I-1070J550D01*
G02X1468448Y1549970I0J1202D01*
G01Y1549972D01*
G02X1468597Y1550551I1202J-1D01*
G01X1470163Y1553261D01*
X1470165Y1553264D01*
G37*
G36*
G01X1474888Y1553261D02*
X1474890Y1553264D01*
G02X1475950Y1553900I1060J-565D01*
G02X1477152Y1552698I0J-1202D01*
G01Y1552697D01*
G02X1476992Y1552098I-1203J1D01*
G01X1475447Y1549425D01*
X1475445Y1549421D01*
G02X1474375Y1548768I-1070J550D01*
G01X1474373D01*
G02X1473172Y1549970I1J1202D01*
G01Y1549972D01*
G02X1473322Y1550551I1203J-3D01*
G01X1474888Y1553261D01*
G37*
G36*
G01X1479612D02*
X1479614Y1553264D01*
G02X1480674Y1553900I1060J-565D01*
G02X1481876Y1552698I0J-1202D01*
G01Y1552697D01*
G02X1481716Y1552098I-1203J1D01*
G01X1480171Y1549425D01*
X1480169Y1549421D01*
G02X1479099Y1548768I-1070J550D01*
G01X1479097D01*
G02X1477896Y1549970I1J1202D01*
G01Y1549972D01*
G02X1478046Y1550551I1203J-3D01*
G01X1479612Y1553261D01*
G37*
G36*
G01X1484339Y1553264D02*
G02X1485399Y1553900I1060J-565D01*
G01X1485401D01*
G02X1486602Y1552698I-1J-1202D01*
G02X1486441Y1552098I-1204J1D01*
G01X1484896Y1549425D01*
X1484894Y1549421D01*
G02X1483824Y1548768I-1070J550D01*
G02X1482622Y1549970I0J1202D01*
G01Y1549972D01*
G02X1482771Y1550551I1202J-1D01*
G01X1484337Y1553261D01*
X1484339Y1553264D01*
G37*
G36*
G01X1489063D02*
G02X1490123Y1553900I1060J-565D01*
G01X1490125D01*
G02X1491326Y1552698I-1J-1202D01*
G02X1491165Y1552098I-1204J1D01*
G01X1489620Y1549425D01*
X1489618Y1549421D01*
G02X1488548Y1548768I-1070J550D01*
G02X1487346Y1549970I0J1202D01*
G01Y1549972D01*
G02X1487495Y1550551I1202J-1D01*
G01X1489061Y1553261D01*
X1489063Y1553264D01*
G37*
G36*
G01X1493787D02*
G02X1494847Y1553900I1060J-565D01*
G01X1494849D01*
G02X1496050Y1552698I-1J-1202D01*
G02X1495889Y1552098I-1204J1D01*
G01X1494344Y1549425D01*
X1494342Y1549421D01*
G02X1493272Y1548768I-1070J550D01*
G02X1492070Y1549970I0J1202D01*
G01Y1549972D01*
G02X1492219Y1550551I1202J-1D01*
G01X1493785Y1553261D01*
X1493787Y1553264D01*
G37*
G36*
G01X1498510Y1553261D02*
X1498512Y1553264D01*
G02X1499572Y1553900I1060J-565D01*
G02X1500774Y1552698I0J-1202D01*
G01Y1552697D01*
G02X1500614Y1552098I-1203J1D01*
G01X1499069Y1549425D01*
X1499067Y1549421D01*
G02X1497997Y1548768I-1070J550D01*
G01X1497995D01*
G02X1496794Y1549970I1J1202D01*
G01Y1549972D01*
G02X1496944Y1550551I1203J-3D01*
G01X1498510Y1553261D01*
G37*
G36*
G01X1503234D02*
X1503236Y1553264D01*
G02X1504296Y1553900I1060J-565D01*
G02X1505498Y1552698I0J-1202D01*
G01Y1552697D01*
G02X1505338Y1552098I-1203J1D01*
G01X1503793Y1549425D01*
X1503791Y1549421D01*
G02X1502721Y1548768I-1070J550D01*
G01X1502719D01*
G02X1501518Y1549970I1J1202D01*
G01Y1549972D01*
G02X1501668Y1550551I1203J-3D01*
G01X1503234Y1553261D01*
G37*
G36*
G01X1507961Y1553264D02*
G02X1509021Y1553900I1060J-565D01*
G01X1509023D01*
G02X1510224Y1552698I-1J-1202D01*
G02X1510063Y1552098I-1204J1D01*
G01X1508518Y1549425D01*
X1508516Y1549421D01*
G02X1507446Y1548768I-1070J550D01*
G02X1506244Y1549970I0J1202D01*
G01Y1549972D01*
G02X1506393Y1550551I1202J-1D01*
G01X1507959Y1553261D01*
X1507961Y1553264D01*
G37*
G36*
G01X1512685D02*
G02X1513745Y1553900I1060J-565D01*
G01X1513747D01*
G02X1514948Y1552698I-1J-1202D01*
G02X1514787Y1552098I-1204J1D01*
G01X1513242Y1549425D01*
X1513240Y1549421D01*
G02X1512170Y1548768I-1070J550D01*
G02X1510968Y1549970I0J1202D01*
G01Y1549972D01*
G02X1511117Y1550551I1202J-1D01*
G01X1512683Y1553261D01*
X1512685Y1553264D01*
G37*
G36*
G01X1517409D02*
G02X1518469Y1553900I1060J-565D01*
G01X1518471D01*
G02X1519672Y1552698I-1J-1202D01*
G02X1519511Y1552098I-1204J1D01*
G01X1517966Y1549425D01*
X1517964Y1549421D01*
G02X1516894Y1548768I-1070J550D01*
G02X1515692Y1549970I0J1202D01*
G01Y1549972D01*
G02X1515841Y1550551I1202J-1D01*
G01X1517407Y1553261D01*
X1517409Y1553264D01*
G37*
G36*
G01X1522132Y1553261D02*
X1522134Y1553264D01*
G02X1523194Y1553900I1060J-565D01*
G02X1524396Y1552698I0J-1202D01*
G01Y1552697D01*
G02X1524236Y1552098I-1203J1D01*
G01X1522691Y1549425D01*
X1522689Y1549421D01*
G02X1521619Y1548768I-1070J550D01*
G01X1521617D01*
G02X1520416Y1549970I1J1202D01*
G01Y1549972D01*
G02X1520566Y1550551I1203J-3D01*
G01X1522132Y1553261D01*
G37*
G36*
G01X1526856D02*
X1526858Y1553264D01*
G02X1527918Y1553900I1060J-565D01*
G02X1529120Y1552698I0J-1202D01*
G01Y1552697D01*
G02X1528960Y1552098I-1203J1D01*
G01X1527415Y1549425D01*
X1527413Y1549421D01*
G02X1526343Y1548768I-1070J550D01*
G01X1526341D01*
G02X1525140Y1549970I1J1202D01*
G01Y1549972D01*
G02X1525290Y1550551I1203J-3D01*
G01X1526856Y1553261D01*
G37*
G36*
G01X1531583Y1553264D02*
G02X1532643Y1553900I1060J-565D01*
G01X1532645D01*
G02X1533846Y1552698I-1J-1202D01*
G02X1533685Y1552098I-1204J1D01*
G01X1532140Y1549425D01*
X1532138Y1549421D01*
G02X1531068Y1548768I-1070J550D01*
G02X1529866Y1549970I0J1202D01*
G01Y1549972D01*
G02X1530015Y1550551I1202J-1D01*
G01X1531581Y1553261D01*
X1531583Y1553264D01*
G37*
G36*
G01X1588779D02*
G02X1589839Y1553900I1060J-565D01*
G01X1589841D01*
G02X1591042Y1552698I-1J-1202D01*
G02X1590881Y1552098I-1204J1D01*
G01X1589336Y1549425D01*
X1589334Y1549421D01*
G02X1588264Y1548768I-1070J550D01*
G02X1587062Y1549970I0J1202D01*
G01Y1549972D01*
G02X1587211Y1550551I1202J-1D01*
G01X1588777Y1553261D01*
X1588779Y1553264D01*
G37*
G36*
G01X1593503D02*
G02X1594563Y1553900I1060J-565D01*
G01X1594565D01*
G02X1595766Y1552698I-1J-1202D01*
G02X1595605Y1552098I-1204J1D01*
G01X1594060Y1549425D01*
X1594058Y1549421D01*
G02X1592988Y1548768I-1070J550D01*
G02X1591786Y1549970I0J1202D01*
G01Y1549972D01*
G02X1591935Y1550551I1202J-1D01*
G01X1593501Y1553261D01*
X1593503Y1553264D01*
G37*
G36*
G01X1598227D02*
G02X1599287Y1553900I1060J-565D01*
G01X1599289D01*
G02X1600490Y1552698I-1J-1202D01*
G02X1600329Y1552098I-1204J1D01*
G01X1598784Y1549425D01*
X1598782Y1549421D01*
G02X1597712Y1548768I-1070J550D01*
G02X1596510Y1549970I0J1202D01*
G01Y1549972D01*
G02X1596659Y1550551I1202J-1D01*
G01X1598225Y1553261D01*
X1598227Y1553264D01*
G37*
G36*
G01X1602950Y1553261D02*
X1602952Y1553264D01*
G02X1604012Y1553900I1060J-565D01*
G02X1605214Y1552698I0J-1202D01*
G01Y1552697D01*
G02X1605054Y1552098I-1203J1D01*
G01X1603509Y1549425D01*
X1603507Y1549421D01*
G02X1602437Y1548768I-1070J550D01*
G01X1602435D01*
G02X1601234Y1549970I1J1202D01*
G01Y1549972D01*
G02X1601384Y1550551I1203J-3D01*
G01X1602950Y1553261D01*
G37*
G36*
G01X1607674D02*
X1607676Y1553264D01*
G02X1608736Y1553900I1060J-565D01*
G02X1609938Y1552698I0J-1202D01*
G01Y1552697D01*
G02X1609778Y1552098I-1203J1D01*
G01X1608233Y1549425D01*
X1608231Y1549421D01*
G02X1607161Y1548768I-1070J550D01*
G01X1607159D01*
G02X1605958Y1549970I1J1202D01*
G01Y1549972D01*
G02X1606108Y1550551I1203J-3D01*
G01X1607674Y1553261D01*
G37*
G36*
G01X1612401Y1553264D02*
G02X1613461Y1553900I1060J-565D01*
G01X1613463D01*
G02X1614664Y1552698I-1J-1202D01*
G02X1614503Y1552098I-1204J1D01*
G01X1612958Y1549425D01*
X1612956Y1549421D01*
G02X1611886Y1548768I-1070J550D01*
G02X1610684Y1549970I0J1202D01*
G01Y1549972D01*
G02X1610833Y1550551I1202J-1D01*
G01X1612399Y1553261D01*
X1612401Y1553264D01*
G37*
G36*
G01X1617125D02*
G02X1618185Y1553900I1060J-565D01*
G01X1618187D01*
G02X1619388Y1552698I-1J-1202D01*
G02X1619227Y1552098I-1204J1D01*
G01X1617682Y1549425D01*
X1617680Y1549421D01*
G02X1616610Y1548768I-1070J550D01*
G02X1615408Y1549970I0J1202D01*
G01Y1549972D01*
G02X1615557Y1550551I1202J-1D01*
G01X1617123Y1553261D01*
X1617125Y1553264D01*
G37*
G36*
G01X1621849D02*
G02X1622909Y1553900I1060J-565D01*
G01X1622911D01*
G02X1624112Y1552698I-1J-1202D01*
G02X1623951Y1552098I-1204J1D01*
G01X1622406Y1549425D01*
X1622404Y1549421D01*
G02X1621334Y1548768I-1070J550D01*
G02X1620132Y1549970I0J1202D01*
G01Y1549972D01*
G02X1620281Y1550551I1202J-1D01*
G01X1621847Y1553261D01*
X1621849Y1553264D01*
G37*
G36*
G01X1626572Y1553261D02*
X1626574Y1553264D01*
G02X1627634Y1553900I1060J-565D01*
G02X1628836Y1552698I0J-1202D01*
G01Y1552697D01*
G02X1628676Y1552098I-1203J1D01*
G01X1627131Y1549425D01*
X1627129Y1549421D01*
G02X1626059Y1548768I-1070J550D01*
G01X1626057D01*
G02X1624856Y1549970I1J1202D01*
G01Y1549972D01*
G02X1625006Y1550551I1203J-3D01*
G01X1626572Y1553261D01*
G37*
G36*
G01X1631296D02*
X1631298Y1553264D01*
G02X1632358Y1553900I1060J-565D01*
G02X1633560Y1552698I0J-1202D01*
G01Y1552697D01*
G02X1633400Y1552098I-1203J1D01*
G01X1631855Y1549425D01*
X1631853Y1549421D01*
G02X1630783Y1548768I-1070J550D01*
G01X1630781D01*
G02X1629580Y1549970I1J1202D01*
G01Y1549972D01*
G02X1629730Y1550551I1203J-3D01*
G01X1631296Y1553261D01*
G37*
G36*
G01X1636023Y1553264D02*
G02X1637083Y1553900I1060J-565D01*
G01X1637085D01*
G02X1638286Y1552698I-1J-1202D01*
G02X1638125Y1552098I-1204J1D01*
G01X1636580Y1549425D01*
X1636578Y1549421D01*
G02X1635508Y1548768I-1070J550D01*
G02X1634306Y1549970I0J1202D01*
G01Y1549972D01*
G02X1634455Y1550551I1202J-1D01*
G01X1636021Y1553261D01*
X1636023Y1553264D01*
G37*
G36*
G01X1640747D02*
G02X1641807Y1553900I1060J-565D01*
G01X1641809D01*
G02X1643010Y1552698I-1J-1202D01*
G02X1642849Y1552098I-1204J1D01*
G01X1641304Y1549425D01*
X1641302Y1549421D01*
G02X1640232Y1548768I-1070J550D01*
G02X1639030Y1549970I0J1202D01*
G01Y1549972D01*
G02X1639179Y1550551I1202J-1D01*
G01X1640745Y1553261D01*
X1640747Y1553264D01*
G37*
G36*
G01X1645471D02*
G02X1646531Y1553900I1060J-565D01*
G01X1646533D01*
G02X1647734Y1552698I-1J-1202D01*
G02X1647573Y1552098I-1204J1D01*
G01X1646028Y1549425D01*
X1646026Y1549421D01*
G02X1644956Y1548768I-1070J550D01*
G02X1643754Y1549970I0J1202D01*
G01Y1549972D01*
G02X1643903Y1550551I1202J-1D01*
G01X1645469Y1553261D01*
X1645471Y1553264D01*
G37*
G36*
G01X1650194Y1553261D02*
X1650196Y1553264D01*
G02X1651256Y1553900I1060J-565D01*
G02X1652458Y1552698I0J-1202D01*
G01Y1552697D01*
G02X1652298Y1552098I-1203J1D01*
G01X1650753Y1549425D01*
X1650751Y1549421D01*
G02X1649681Y1548768I-1070J550D01*
G01X1649679D01*
G02X1648478Y1549970I1J1202D01*
G01Y1549972D01*
G02X1648628Y1550551I1203J-3D01*
G01X1650194Y1553261D01*
G37*
G36*
G01X1654918D02*
X1654920Y1553264D01*
G02X1655980Y1553900I1060J-565D01*
G02X1657182Y1552698I0J-1202D01*
G01Y1552697D01*
G02X1657022Y1552098I-1203J1D01*
G01X1655477Y1549425D01*
X1655475Y1549421D01*
G02X1654405Y1548768I-1070J550D01*
G01X1654403D01*
G02X1653202Y1549970I1J1202D01*
G01Y1549972D01*
G02X1653352Y1550551I1203J-3D01*
G01X1654918Y1553261D01*
G37*
G36*
G01X1659645Y1553264D02*
G02X1660705Y1553900I1060J-565D01*
G01X1660707D01*
G02X1661908Y1552698I-1J-1202D01*
G02X1661747Y1552098I-1204J1D01*
G01X1660202Y1549425D01*
X1660200Y1549421D01*
G02X1659130Y1548768I-1070J550D01*
G02X1657928Y1549970I0J1202D01*
G01Y1549972D01*
G02X1658077Y1550551I1202J-1D01*
G01X1659643Y1553261D01*
X1659645Y1553264D01*
G37*
G36*
G01X1253264Y1553314D02*
Y1553316D01*
G02X1254295Y1553900I1031J-618D01*
G01X1254296D01*
G02X1255498Y1552698I0J-1202D01*
G01Y1552697D01*
G02X1255338Y1552098I-1203J1D01*
G01X1253793Y1549425D01*
X1253791Y1549421D01*
G02X1253751Y1549349I-1071J548D01*
G02X1252718Y1548762I-1033J615D01*
G02X1251516Y1549965I1J1203D01*
G01Y1549967D01*
G02X1251665Y1550546I1202J-1D01*
G01X1253231Y1553256D01*
X1253233Y1553259D01*
G02X1253264Y1553314I1062J-562D01*
G37*
G36*
G01X1235398Y1553900D02*
X1235399D01*
G02X1236602Y1552698I1J-1202D01*
G02X1236441Y1552098I-1204J1D01*
G01X1234896Y1549425D01*
X1234894Y1549421D01*
G02X1233824Y1548768I-1070J550D01*
G01X1233823D01*
G02X1232620Y1549970I-1J1202D01*
G01Y1549972D01*
G02X1232770Y1550551I1203J-3D01*
G01X1234336Y1553261D01*
X1234338Y1553264D01*
G02X1235398Y1553900I1060J-565D01*
G37*
G36*
G01X1391806D02*
X1391807D01*
G02X1393010Y1552698I1J-1202D01*
G02X1392849Y1552098I-1204J1D01*
G01X1391304Y1549425D01*
X1391302Y1549421D01*
G02X1390232Y1548768I-1070J550D01*
G01X1390231D01*
G02X1389028Y1549970I-1J1202D01*
G01Y1549972D01*
G02X1389178Y1550551I1203J-3D01*
G01X1390744Y1553261D01*
X1390746Y1553264D01*
G02X1391806Y1553900I1060J-565D01*
G37*
G36*
G01X1243815Y1553314D02*
Y1553316D01*
G02X1244847Y1553900I1031J-618D01*
G02X1246050Y1552698I1J-1202D01*
G02X1245889Y1552098I-1204J1D01*
G01X1244344Y1549425D01*
X1244342Y1549421D01*
G02X1244302Y1549349I-1071J548D01*
G02X1243269Y1548762I-1033J615D01*
G02X1242066Y1549965I0J1203D01*
G01Y1549967D01*
G02X1242216Y1550546I1203J-3D01*
G01X1243782Y1553256D01*
X1243784Y1553259D01*
G02X1243815Y1553314I1062J-562D01*
G37*
G36*
G01X1262713D02*
Y1553316D01*
G02X1263745Y1553900I1031J-618D01*
G02X1264948Y1552698I1J-1202D01*
G02X1264787Y1552098I-1204J1D01*
G01X1263242Y1549425D01*
X1263240Y1549421D01*
G02X1263200Y1549349I-1071J548D01*
G02X1262167Y1548762I-1033J615D01*
G02X1260964Y1549965I0J1203D01*
G01Y1549967D01*
G02X1261114Y1550546I1203J-3D01*
G01X1262680Y1553256D01*
X1262682Y1553259D01*
G02X1262713Y1553314I1062J-562D01*
G37*
G36*
G01X1267437D02*
Y1553316D01*
G02X1268469Y1553900I1031J-618D01*
G02X1269672Y1552698I1J-1202D01*
G02X1269511Y1552098I-1204J1D01*
G01X1267966Y1549425D01*
X1267964Y1549421D01*
G02X1267924Y1549349I-1071J548D01*
G02X1266891Y1548762I-1033J615D01*
G02X1265688Y1549965I0J1203D01*
G01Y1549967D01*
G02X1265838Y1550546I1203J-3D01*
G01X1267404Y1553256D01*
X1267406Y1553259D01*
G02X1267437Y1553314I1062J-562D01*
G37*
G36*
G01X1196543Y1566902D02*
G02X1197603Y1567538I1060J-565D01*
G01X1197605D01*
G02X1198806Y1566336I-1J-1202D01*
G02X1198645Y1565736I-1204J1D01*
G01X1197100Y1563063D01*
X1197098Y1563059D01*
G02X1196028Y1562406I-1070J550D01*
G02X1194826Y1563608I0J1202D01*
G01Y1563610D01*
G02X1194975Y1564189I1202J-1D01*
G01X1196541Y1566899D01*
X1196543Y1566902D01*
G37*
G36*
G01X1201267D02*
G02X1202327Y1567538I1060J-565D01*
G01X1202329D01*
G02X1203530Y1566336I-1J-1202D01*
G02X1203369Y1565736I-1204J1D01*
G01X1201824Y1563063D01*
X1201822Y1563059D01*
G02X1200752Y1562406I-1070J550D01*
G02X1199550Y1563608I0J1202D01*
G01Y1563610D01*
G02X1199699Y1564189I1202J-1D01*
G01X1201265Y1566899D01*
X1201267Y1566902D01*
G37*
G36*
G01X1205991D02*
G02X1207051Y1567538I1060J-565D01*
G01X1207053D01*
G02X1208254Y1566336I-1J-1202D01*
G02X1208093Y1565736I-1204J1D01*
G01X1206548Y1563063D01*
X1206546Y1563059D01*
G02X1205476Y1562406I-1070J550D01*
G02X1204274Y1563608I0J1202D01*
G01Y1563610D01*
G02X1204423Y1564189I1202J-1D01*
G01X1205989Y1566899D01*
X1205991Y1566902D01*
G37*
G36*
G01X1210714Y1566899D02*
X1210716Y1566902D01*
G02X1211776Y1567538I1060J-565D01*
G02X1212978Y1566336I0J-1202D01*
G01Y1566335D01*
G02X1212818Y1565736I-1203J1D01*
G01X1211273Y1563063D01*
X1211271Y1563059D01*
G02X1210201Y1562406I-1070J550D01*
G01X1210199D01*
G02X1208998Y1563608I1J1202D01*
G01Y1563610D01*
G02X1209148Y1564189I1203J-3D01*
G01X1210714Y1566899D01*
G37*
G36*
G01X1215438D02*
X1215440Y1566902D01*
G02X1216500Y1567538I1060J-565D01*
G02X1217702Y1566336I0J-1202D01*
G01Y1566335D01*
G02X1217542Y1565736I-1203J1D01*
G01X1215997Y1563063D01*
X1215995Y1563059D01*
G02X1214925Y1562406I-1070J550D01*
G01X1214923D01*
G02X1213722Y1563608I1J1202D01*
G01Y1563610D01*
G02X1213872Y1564189I1203J-3D01*
G01X1215438Y1566899D01*
G37*
G36*
G01X1220165Y1566902D02*
G02X1221225Y1567538I1060J-565D01*
G01X1221227D01*
G02X1222428Y1566336I-1J-1202D01*
G02X1222267Y1565736I-1204J1D01*
G01X1220722Y1563063D01*
X1220720Y1563059D01*
G02X1219650Y1562406I-1070J550D01*
G02X1218448Y1563608I0J1202D01*
G01Y1563610D01*
G02X1218597Y1564189I1202J-1D01*
G01X1220163Y1566899D01*
X1220165Y1566902D01*
G37*
G36*
G01X1224889D02*
G02X1225949Y1567538I1060J-565D01*
G01X1225951D01*
G02X1227152Y1566336I-1J-1202D01*
G02X1226991Y1565736I-1204J1D01*
G01X1225446Y1563063D01*
X1225444Y1563059D01*
G02X1224374Y1562406I-1070J550D01*
G02X1223172Y1563608I0J1202D01*
G01Y1563610D01*
G02X1223321Y1564189I1202J-1D01*
G01X1224887Y1566899D01*
X1224889Y1566902D01*
G37*
G36*
G01X1229613D02*
G02X1230673Y1567538I1060J-565D01*
G01X1230675D01*
G02X1231876Y1566336I-1J-1202D01*
G02X1231715Y1565736I-1204J1D01*
G01X1230170Y1563063D01*
X1230168Y1563059D01*
G02X1229098Y1562406I-1070J550D01*
G02X1227896Y1563608I0J1202D01*
G01Y1563610D01*
G02X1228045Y1564189I1202J-1D01*
G01X1229611Y1566899D01*
X1229613Y1566902D01*
G37*
G36*
G01X1234336Y1566899D02*
X1234338Y1566902D01*
G02X1235398Y1567538I1060J-565D01*
G02X1236600Y1566336I0J-1202D01*
G01Y1566335D01*
G02X1236440Y1565736I-1203J1D01*
G01X1234895Y1563063D01*
X1234893Y1563059D01*
G02X1233823Y1562406I-1070J550D01*
G01X1233821D01*
G02X1232620Y1563608I1J1202D01*
G01Y1563610D01*
G02X1232770Y1564189I1203J-3D01*
G01X1234336Y1566899D01*
G37*
G36*
G01X1239060D02*
X1239062Y1566902D01*
G02X1240122Y1567538I1060J-565D01*
G02X1241324Y1566336I0J-1202D01*
G01Y1566335D01*
G02X1241164Y1565736I-1203J1D01*
G01X1239619Y1563063D01*
X1239617Y1563059D01*
G02X1238547Y1562406I-1070J550D01*
G01X1238545D01*
G02X1237344Y1563608I1J1202D01*
G01Y1563610D01*
G02X1237494Y1564189I1203J-3D01*
G01X1239060Y1566899D01*
G37*
G36*
G01X1243787Y1566902D02*
G02X1244847Y1567538I1060J-565D01*
G01X1244849D01*
G02X1246050Y1566336I-1J-1202D01*
G02X1245889Y1565736I-1204J1D01*
G01X1244344Y1563063D01*
X1244342Y1563059D01*
G02X1243272Y1562406I-1070J550D01*
G02X1242070Y1563608I0J1202D01*
G01Y1563610D01*
G02X1242219Y1564189I1202J-1D01*
G01X1243785Y1566899D01*
X1243787Y1566902D01*
G37*
G36*
G01X1248511D02*
G02X1249571Y1567538I1060J-565D01*
G01X1249573D01*
G02X1250774Y1566336I-1J-1202D01*
G02X1250613Y1565736I-1204J1D01*
G01X1249068Y1563063D01*
X1249066Y1563059D01*
G02X1247996Y1562406I-1070J550D01*
G02X1246794Y1563608I0J1202D01*
G01Y1563610D01*
G02X1246943Y1564189I1202J-1D01*
G01X1248509Y1566899D01*
X1248511Y1566902D01*
G37*
G36*
G01X1253235D02*
G02X1254295Y1567538I1060J-565D01*
G01X1254297D01*
G02X1255498Y1566336I-1J-1202D01*
G02X1255337Y1565736I-1204J1D01*
G01X1253792Y1563063D01*
X1253790Y1563059D01*
G02X1252720Y1562406I-1070J550D01*
G02X1251518Y1563608I0J1202D01*
G01Y1563610D01*
G02X1251667Y1564189I1202J-1D01*
G01X1253233Y1566899D01*
X1253235Y1566902D01*
G37*
G36*
G01X1257958Y1566899D02*
X1257960Y1566902D01*
G02X1259020Y1567538I1060J-565D01*
G02X1260222Y1566336I0J-1202D01*
G01Y1566335D01*
G02X1260062Y1565736I-1203J1D01*
G01X1258517Y1563063D01*
X1258515Y1563059D01*
G02X1257445Y1562406I-1070J550D01*
G01X1257443D01*
G02X1256242Y1563608I1J1202D01*
G01Y1563610D01*
G02X1256392Y1564189I1203J-3D01*
G01X1257958Y1566899D01*
G37*
G36*
G01X1262682D02*
X1262684Y1566902D01*
G02X1263744Y1567538I1060J-565D01*
G02X1264946Y1566336I0J-1202D01*
G01Y1566335D01*
G02X1264786Y1565736I-1203J1D01*
G01X1263241Y1563063D01*
X1263239Y1563059D01*
G02X1262169Y1562406I-1070J550D01*
G01X1262167D01*
G02X1260966Y1563608I1J1202D01*
G01Y1563610D01*
G02X1261116Y1564189I1203J-3D01*
G01X1262682Y1566899D01*
G37*
G36*
G01X1267409Y1566902D02*
G02X1268469Y1567538I1060J-565D01*
G01X1268471D01*
G02X1269672Y1566336I-1J-1202D01*
G02X1269511Y1565736I-1204J1D01*
G01X1267966Y1563063D01*
X1267964Y1563059D01*
G02X1266894Y1562406I-1070J550D01*
G02X1265692Y1563608I0J1202D01*
G01Y1563610D01*
G02X1265841Y1564189I1202J-1D01*
G01X1267407Y1566899D01*
X1267409Y1566902D01*
G37*
G36*
G01X1324605D02*
G02X1325665Y1567538I1060J-565D01*
G01X1325667D01*
G02X1326868Y1566336I-1J-1202D01*
G02X1326707Y1565736I-1204J1D01*
G01X1325162Y1563063D01*
X1325160Y1563059D01*
G02X1324090Y1562406I-1070J550D01*
G02X1322888Y1563608I0J1202D01*
G01Y1563610D01*
G02X1323037Y1564189I1202J-1D01*
G01X1324603Y1566899D01*
X1324605Y1566902D01*
G37*
G36*
G01X1329329D02*
G02X1330389Y1567538I1060J-565D01*
G01X1330391D01*
G02X1331592Y1566336I-1J-1202D01*
G02X1331431Y1565736I-1204J1D01*
G01X1329886Y1563063D01*
X1329884Y1563059D01*
G02X1328814Y1562406I-1070J550D01*
G02X1327612Y1563608I0J1202D01*
G01Y1563610D01*
G02X1327761Y1564189I1202J-1D01*
G01X1329327Y1566899D01*
X1329329Y1566902D01*
G37*
G36*
G01X1334053D02*
G02X1335113Y1567538I1060J-565D01*
G01X1335115D01*
G02X1336316Y1566336I-1J-1202D01*
G02X1336155Y1565736I-1204J1D01*
G01X1334610Y1563063D01*
X1334608Y1563059D01*
G02X1333538Y1562406I-1070J550D01*
G02X1332336Y1563608I0J1202D01*
G01Y1563610D01*
G02X1332485Y1564189I1202J-1D01*
G01X1334051Y1566899D01*
X1334053Y1566902D01*
G37*
G36*
G01X1338776Y1566899D02*
X1338778Y1566902D01*
G02X1339838Y1567538I1060J-565D01*
G02X1341040Y1566336I0J-1202D01*
G01Y1566335D01*
G02X1340880Y1565736I-1203J1D01*
G01X1339335Y1563063D01*
X1339333Y1563059D01*
G02X1338263Y1562406I-1070J550D01*
G01X1338261D01*
G02X1337060Y1563608I1J1202D01*
G01Y1563610D01*
G02X1337210Y1564189I1203J-3D01*
G01X1338776Y1566899D01*
G37*
G36*
G01X1343500D02*
X1343502Y1566902D01*
G02X1344562Y1567538I1060J-565D01*
G02X1345764Y1566336I0J-1202D01*
G01Y1566335D01*
G02X1345604Y1565736I-1203J1D01*
G01X1344059Y1563063D01*
X1344057Y1563059D01*
G02X1342987Y1562406I-1070J550D01*
G01X1342985D01*
G02X1341784Y1563608I1J1202D01*
G01Y1563610D01*
G02X1341934Y1564189I1203J-3D01*
G01X1343500Y1566899D01*
G37*
G36*
G01X1348227Y1566902D02*
G02X1349287Y1567538I1060J-565D01*
G01X1349289D01*
G02X1350490Y1566336I-1J-1202D01*
G02X1350329Y1565736I-1204J1D01*
G01X1348784Y1563063D01*
X1348782Y1563059D01*
G02X1347712Y1562406I-1070J550D01*
G02X1346510Y1563608I0J1202D01*
G01Y1563610D01*
G02X1346659Y1564189I1202J-1D01*
G01X1348225Y1566899D01*
X1348227Y1566902D01*
G37*
G36*
G01X1352951D02*
G02X1354011Y1567538I1060J-565D01*
G01X1354013D01*
G02X1355214Y1566336I-1J-1202D01*
G02X1355053Y1565736I-1204J1D01*
G01X1353508Y1563063D01*
X1353506Y1563059D01*
G02X1352436Y1562406I-1070J550D01*
G02X1351234Y1563608I0J1202D01*
G01Y1563610D01*
G02X1351383Y1564189I1202J-1D01*
G01X1352949Y1566899D01*
X1352951Y1566902D01*
G37*
G36*
G01X1357675D02*
G02X1358735Y1567538I1060J-565D01*
G01X1358737D01*
G02X1359938Y1566336I-1J-1202D01*
G02X1359777Y1565736I-1204J1D01*
G01X1358232Y1563063D01*
X1358230Y1563059D01*
G02X1357160Y1562406I-1070J550D01*
G02X1355958Y1563608I0J1202D01*
G01Y1563610D01*
G02X1356107Y1564189I1202J-1D01*
G01X1357673Y1566899D01*
X1357675Y1566902D01*
G37*
G36*
G01X1362398Y1566899D02*
X1362400Y1566902D01*
G02X1363460Y1567538I1060J-565D01*
G02X1364662Y1566336I0J-1202D01*
G01Y1566335D01*
G02X1364502Y1565736I-1203J1D01*
G01X1362957Y1563063D01*
X1362955Y1563059D01*
G02X1361885Y1562406I-1070J550D01*
G01X1361883D01*
G02X1360682Y1563608I1J1202D01*
G01Y1563610D01*
G02X1360832Y1564189I1203J-3D01*
G01X1362398Y1566899D01*
G37*
G36*
G01X1367122D02*
X1367124Y1566902D01*
G02X1368184Y1567538I1060J-565D01*
G02X1369386Y1566336I0J-1202D01*
G01Y1566335D01*
G02X1369226Y1565736I-1203J1D01*
G01X1367681Y1563063D01*
X1367679Y1563059D01*
G02X1366609Y1562406I-1070J550D01*
G01X1366607D01*
G02X1365406Y1563608I1J1202D01*
G01Y1563610D01*
G02X1365556Y1564189I1203J-3D01*
G01X1367122Y1566899D01*
G37*
G36*
G01X1371849Y1566902D02*
G02X1372909Y1567538I1060J-565D01*
G01X1372911D01*
G02X1374112Y1566336I-1J-1202D01*
G02X1373951Y1565736I-1204J1D01*
G01X1372406Y1563063D01*
X1372404Y1563059D01*
G02X1371334Y1562406I-1070J550D01*
G02X1370132Y1563608I0J1202D01*
G01Y1563610D01*
G02X1370281Y1564189I1202J-1D01*
G01X1371847Y1566899D01*
X1371849Y1566902D01*
G37*
G36*
G01X1376573D02*
G02X1377633Y1567538I1060J-565D01*
G01X1377635D01*
G02X1378836Y1566336I-1J-1202D01*
G02X1378675Y1565736I-1204J1D01*
G01X1377130Y1563063D01*
X1377128Y1563059D01*
G02X1376058Y1562406I-1070J550D01*
G02X1374856Y1563608I0J1202D01*
G01Y1563610D01*
G02X1375005Y1564189I1202J-1D01*
G01X1376571Y1566899D01*
X1376573Y1566902D01*
G37*
G36*
G01X1381297D02*
G02X1382357Y1567538I1060J-565D01*
G01X1382359D01*
G02X1383560Y1566336I-1J-1202D01*
G02X1383399Y1565736I-1204J1D01*
G01X1381854Y1563063D01*
X1381852Y1563059D01*
G02X1380782Y1562406I-1070J550D01*
G02X1379580Y1563608I0J1202D01*
G01Y1563610D01*
G02X1379729Y1564189I1202J-1D01*
G01X1381295Y1566899D01*
X1381297Y1566902D01*
G37*
G36*
G01X1386020Y1566899D02*
X1386022Y1566902D01*
G02X1387082Y1567538I1060J-565D01*
G02X1388284Y1566336I0J-1202D01*
G01Y1566335D01*
G02X1388124Y1565736I-1203J1D01*
G01X1386579Y1563063D01*
X1386577Y1563059D01*
G02X1385507Y1562406I-1070J550D01*
G01X1385505D01*
G02X1384304Y1563608I1J1202D01*
G01Y1563610D01*
G02X1384454Y1564189I1203J-3D01*
G01X1386020Y1566899D01*
G37*
G36*
G01X1390744D02*
X1390746Y1566902D01*
G02X1391806Y1567538I1060J-565D01*
G02X1393008Y1566336I0J-1202D01*
G01Y1566335D01*
G02X1392848Y1565736I-1203J1D01*
G01X1391303Y1563063D01*
X1391301Y1563059D01*
G02X1390231Y1562406I-1070J550D01*
G01X1390229D01*
G02X1389028Y1563608I1J1202D01*
G01Y1563610D01*
G02X1389178Y1564189I1203J-3D01*
G01X1390744Y1566899D01*
G37*
G36*
G01X1395471Y1566902D02*
G02X1396531Y1567538I1060J-565D01*
G01X1396533D01*
G02X1397734Y1566336I-1J-1202D01*
G02X1397573Y1565736I-1204J1D01*
G01X1396028Y1563063D01*
X1396026Y1563059D01*
G02X1394956Y1562406I-1070J550D01*
G02X1393754Y1563608I0J1202D01*
G01Y1563610D01*
G02X1393903Y1564189I1202J-1D01*
G01X1395469Y1566899D01*
X1395471Y1566902D01*
G37*
G36*
G01X1460717D02*
G02X1461777Y1567538I1060J-565D01*
G01X1461779D01*
G02X1462980Y1566336I-1J-1202D01*
G02X1462819Y1565736I-1204J1D01*
G01X1461274Y1563063D01*
X1461272Y1563059D01*
G02X1460202Y1562406I-1070J550D01*
G02X1459000Y1563608I0J1202D01*
G01Y1563610D01*
G02X1459149Y1564189I1202J-1D01*
G01X1460715Y1566899D01*
X1460717Y1566902D01*
G37*
G36*
G01X1465441D02*
G02X1466501Y1567538I1060J-565D01*
G01X1466503D01*
G02X1467704Y1566336I-1J-1202D01*
G02X1467543Y1565736I-1204J1D01*
G01X1465998Y1563063D01*
X1465996Y1563059D01*
G02X1464926Y1562406I-1070J550D01*
G02X1463724Y1563608I0J1202D01*
G01Y1563610D01*
G02X1463873Y1564189I1202J-1D01*
G01X1465439Y1566899D01*
X1465441Y1566902D01*
G37*
G36*
G01X1470165D02*
G02X1471225Y1567538I1060J-565D01*
G01X1471227D01*
G02X1472428Y1566336I-1J-1202D01*
G02X1472267Y1565736I-1204J1D01*
G01X1470722Y1563063D01*
X1470720Y1563059D01*
G02X1469650Y1562406I-1070J550D01*
G02X1468448Y1563608I0J1202D01*
G01Y1563610D01*
G02X1468597Y1564189I1202J-1D01*
G01X1470163Y1566899D01*
X1470165Y1566902D01*
G37*
G36*
G01X1474888Y1566899D02*
X1474890Y1566902D01*
G02X1475950Y1567538I1060J-565D01*
G02X1477152Y1566336I0J-1202D01*
G01Y1566335D01*
G02X1476992Y1565736I-1203J1D01*
G01X1475447Y1563063D01*
X1475445Y1563059D01*
G02X1474375Y1562406I-1070J550D01*
G01X1474373D01*
G02X1473172Y1563608I1J1202D01*
G01Y1563610D01*
G02X1473322Y1564189I1203J-3D01*
G01X1474888Y1566899D01*
G37*
G36*
G01X1479612D02*
X1479614Y1566902D01*
G02X1480674Y1567538I1060J-565D01*
G02X1481876Y1566336I0J-1202D01*
G01Y1566335D01*
G02X1481716Y1565736I-1203J1D01*
G01X1480171Y1563063D01*
X1480169Y1563059D01*
G02X1479099Y1562406I-1070J550D01*
G01X1479097D01*
G02X1477896Y1563608I1J1202D01*
G01Y1563610D01*
G02X1478046Y1564189I1203J-3D01*
G01X1479612Y1566899D01*
G37*
G36*
G01X1484339Y1566902D02*
G02X1485399Y1567538I1060J-565D01*
G01X1485401D01*
G02X1486602Y1566336I-1J-1202D01*
G02X1486441Y1565736I-1204J1D01*
G01X1484896Y1563063D01*
X1484894Y1563059D01*
G02X1483824Y1562406I-1070J550D01*
G02X1482622Y1563608I0J1202D01*
G01Y1563610D01*
G02X1482771Y1564189I1202J-1D01*
G01X1484337Y1566899D01*
X1484339Y1566902D01*
G37*
G36*
G01X1489063D02*
G02X1490123Y1567538I1060J-565D01*
G01X1490125D01*
G02X1491326Y1566336I-1J-1202D01*
G02X1491165Y1565736I-1204J1D01*
G01X1489620Y1563063D01*
X1489618Y1563059D01*
G02X1488548Y1562406I-1070J550D01*
G02X1487346Y1563608I0J1202D01*
G01Y1563610D01*
G02X1487495Y1564189I1202J-1D01*
G01X1489061Y1566899D01*
X1489063Y1566902D01*
G37*
G36*
G01X1493787D02*
G02X1494847Y1567538I1060J-565D01*
G01X1494849D01*
G02X1496050Y1566336I-1J-1202D01*
G02X1495889Y1565736I-1204J1D01*
G01X1494344Y1563063D01*
X1494342Y1563059D01*
G02X1493272Y1562406I-1070J550D01*
G02X1492070Y1563608I0J1202D01*
G01Y1563610D01*
G02X1492219Y1564189I1202J-1D01*
G01X1493785Y1566899D01*
X1493787Y1566902D01*
G37*
G36*
G01X1498510Y1566899D02*
X1498512Y1566902D01*
G02X1499572Y1567538I1060J-565D01*
G02X1500774Y1566336I0J-1202D01*
G01Y1566335D01*
G02X1500614Y1565736I-1203J1D01*
G01X1499069Y1563063D01*
X1499067Y1563059D01*
G02X1497997Y1562406I-1070J550D01*
G01X1497995D01*
G02X1496794Y1563608I1J1202D01*
G01Y1563610D01*
G02X1496944Y1564189I1203J-3D01*
G01X1498510Y1566899D01*
G37*
G36*
G01X1503234D02*
X1503236Y1566902D01*
G02X1504296Y1567538I1060J-565D01*
G02X1505498Y1566336I0J-1202D01*
G01Y1566335D01*
G02X1505338Y1565736I-1203J1D01*
G01X1503793Y1563063D01*
X1503791Y1563059D01*
G02X1502721Y1562406I-1070J550D01*
G01X1502719D01*
G02X1501518Y1563608I1J1202D01*
G01Y1563610D01*
G02X1501668Y1564189I1203J-3D01*
G01X1503234Y1566899D01*
G37*
G36*
G01X1507961Y1566902D02*
G02X1509021Y1567538I1060J-565D01*
G01X1509023D01*
G02X1510224Y1566336I-1J-1202D01*
G02X1510063Y1565736I-1204J1D01*
G01X1508518Y1563063D01*
X1508516Y1563059D01*
G02X1507446Y1562406I-1070J550D01*
G02X1506244Y1563608I0J1202D01*
G01Y1563610D01*
G02X1506393Y1564189I1202J-1D01*
G01X1507959Y1566899D01*
X1507961Y1566902D01*
G37*
G36*
G01X1512685D02*
G02X1513745Y1567538I1060J-565D01*
G01X1513747D01*
G02X1514948Y1566336I-1J-1202D01*
G02X1514787Y1565736I-1204J1D01*
G01X1513242Y1563063D01*
X1513240Y1563059D01*
G02X1512170Y1562406I-1070J550D01*
G02X1510968Y1563608I0J1202D01*
G01Y1563610D01*
G02X1511117Y1564189I1202J-1D01*
G01X1512683Y1566899D01*
X1512685Y1566902D01*
G37*
G36*
G01X1517409D02*
G02X1518469Y1567538I1060J-565D01*
G01X1518471D01*
G02X1519672Y1566336I-1J-1202D01*
G02X1519511Y1565736I-1204J1D01*
G01X1517966Y1563063D01*
X1517964Y1563059D01*
G02X1516894Y1562406I-1070J550D01*
G02X1515692Y1563608I0J1202D01*
G01Y1563610D01*
G02X1515841Y1564189I1202J-1D01*
G01X1517407Y1566899D01*
X1517409Y1566902D01*
G37*
G36*
G01X1522132Y1566899D02*
X1522134Y1566902D01*
G02X1523194Y1567538I1060J-565D01*
G02X1524396Y1566336I0J-1202D01*
G01Y1566335D01*
G02X1524236Y1565736I-1203J1D01*
G01X1522691Y1563063D01*
X1522689Y1563059D01*
G02X1521619Y1562406I-1070J550D01*
G01X1521617D01*
G02X1520416Y1563608I1J1202D01*
G01Y1563610D01*
G02X1520566Y1564189I1203J-3D01*
G01X1522132Y1566899D01*
G37*
G36*
G01X1526856D02*
X1526858Y1566902D01*
G02X1527918Y1567538I1060J-565D01*
G02X1529120Y1566336I0J-1202D01*
G01Y1566335D01*
G02X1528960Y1565736I-1203J1D01*
G01X1527415Y1563063D01*
X1527413Y1563059D01*
G02X1526343Y1562406I-1070J550D01*
G01X1526341D01*
G02X1525140Y1563608I1J1202D01*
G01Y1563610D01*
G02X1525290Y1564189I1203J-3D01*
G01X1526856Y1566899D01*
G37*
G36*
G01X1531583Y1566902D02*
G02X1532643Y1567538I1060J-565D01*
G01X1532645D01*
G02X1533846Y1566336I-1J-1202D01*
G02X1533685Y1565736I-1204J1D01*
G01X1532140Y1563063D01*
X1532138Y1563059D01*
G02X1531068Y1562406I-1070J550D01*
G02X1529866Y1563608I0J1202D01*
G01Y1563610D01*
G02X1530015Y1564189I1202J-1D01*
G01X1531581Y1566899D01*
X1531583Y1566902D01*
G37*
G36*
G01X1588779D02*
G02X1589839Y1567538I1060J-565D01*
G01X1589841D01*
G02X1591042Y1566336I-1J-1202D01*
G02X1590881Y1565736I-1204J1D01*
G01X1589336Y1563063D01*
X1589334Y1563059D01*
G02X1588264Y1562406I-1070J550D01*
G02X1587062Y1563608I0J1202D01*
G01Y1563610D01*
G02X1587211Y1564189I1202J-1D01*
G01X1588777Y1566899D01*
X1588779Y1566902D01*
G37*
G36*
G01X1593503D02*
G02X1594563Y1567538I1060J-565D01*
G01X1594565D01*
G02X1595766Y1566336I-1J-1202D01*
G02X1595605Y1565736I-1204J1D01*
G01X1594060Y1563063D01*
X1594058Y1563059D01*
G02X1592988Y1562406I-1070J550D01*
G02X1591786Y1563608I0J1202D01*
G01Y1563610D01*
G02X1591935Y1564189I1202J-1D01*
G01X1593501Y1566899D01*
X1593503Y1566902D01*
G37*
G36*
G01X1598227D02*
G02X1599287Y1567538I1060J-565D01*
G01X1599289D01*
G02X1600490Y1566336I-1J-1202D01*
G02X1600329Y1565736I-1204J1D01*
G01X1598784Y1563063D01*
X1598782Y1563059D01*
G02X1597712Y1562406I-1070J550D01*
G02X1596510Y1563608I0J1202D01*
G01Y1563610D01*
G02X1596659Y1564189I1202J-1D01*
G01X1598225Y1566899D01*
X1598227Y1566902D01*
G37*
G36*
G01X1602950Y1566899D02*
X1602952Y1566902D01*
G02X1604012Y1567538I1060J-565D01*
G02X1605214Y1566336I0J-1202D01*
G01Y1566335D01*
G02X1605054Y1565736I-1203J1D01*
G01X1603509Y1563063D01*
X1603507Y1563059D01*
G02X1602437Y1562406I-1070J550D01*
G01X1602435D01*
G02X1601234Y1563608I1J1202D01*
G01Y1563610D01*
G02X1601384Y1564189I1203J-3D01*
G01X1602950Y1566899D01*
G37*
G36*
G01X1607674D02*
X1607676Y1566902D01*
G02X1608736Y1567538I1060J-565D01*
G02X1609938Y1566336I0J-1202D01*
G01Y1566335D01*
G02X1609778Y1565736I-1203J1D01*
G01X1608233Y1563063D01*
X1608231Y1563059D01*
G02X1607161Y1562406I-1070J550D01*
G01X1607159D01*
G02X1605958Y1563608I1J1202D01*
G01Y1563610D01*
G02X1606108Y1564189I1203J-3D01*
G01X1607674Y1566899D01*
G37*
G36*
G01X1612401Y1566902D02*
G02X1613461Y1567538I1060J-565D01*
G01X1613463D01*
G02X1614664Y1566336I-1J-1202D01*
G02X1614503Y1565736I-1204J1D01*
G01X1612958Y1563063D01*
X1612956Y1563059D01*
G02X1611886Y1562406I-1070J550D01*
G02X1610684Y1563608I0J1202D01*
G01Y1563610D01*
G02X1610833Y1564189I1202J-1D01*
G01X1612399Y1566899D01*
X1612401Y1566902D01*
G37*
G36*
G01X1617125D02*
G02X1618185Y1567538I1060J-565D01*
G01X1618187D01*
G02X1619388Y1566336I-1J-1202D01*
G02X1619227Y1565736I-1204J1D01*
G01X1617682Y1563063D01*
X1617680Y1563059D01*
G02X1616610Y1562406I-1070J550D01*
G02X1615408Y1563608I0J1202D01*
G01Y1563610D01*
G02X1615557Y1564189I1202J-1D01*
G01X1617123Y1566899D01*
X1617125Y1566902D01*
G37*
G36*
G01X1621849D02*
G02X1622909Y1567538I1060J-565D01*
G01X1622911D01*
G02X1624112Y1566336I-1J-1202D01*
G02X1623951Y1565736I-1204J1D01*
G01X1622406Y1563063D01*
X1622404Y1563059D01*
G02X1621334Y1562406I-1070J550D01*
G02X1620132Y1563608I0J1202D01*
G01Y1563610D01*
G02X1620281Y1564189I1202J-1D01*
G01X1621847Y1566899D01*
X1621849Y1566902D01*
G37*
G36*
G01X1626572Y1566899D02*
X1626574Y1566902D01*
G02X1627634Y1567538I1060J-565D01*
G02X1628836Y1566336I0J-1202D01*
G01Y1566335D01*
G02X1628676Y1565736I-1203J1D01*
G01X1627131Y1563063D01*
X1627129Y1563059D01*
G02X1626059Y1562406I-1070J550D01*
G01X1626057D01*
G02X1624856Y1563608I1J1202D01*
G01Y1563610D01*
G02X1625006Y1564189I1203J-3D01*
G01X1626572Y1566899D01*
G37*
G36*
G01X1631296D02*
X1631298Y1566902D01*
G02X1632358Y1567538I1060J-565D01*
G02X1633560Y1566336I0J-1202D01*
G01Y1566335D01*
G02X1633400Y1565736I-1203J1D01*
G01X1631855Y1563063D01*
X1631853Y1563059D01*
G02X1630783Y1562406I-1070J550D01*
G01X1630781D01*
G02X1629580Y1563608I1J1202D01*
G01Y1563610D01*
G02X1629730Y1564189I1203J-3D01*
G01X1631296Y1566899D01*
G37*
G36*
G01X1636023Y1566902D02*
G02X1637083Y1567538I1060J-565D01*
G01X1637085D01*
G02X1638286Y1566336I-1J-1202D01*
G02X1638125Y1565736I-1204J1D01*
G01X1636580Y1563063D01*
X1636578Y1563059D01*
G02X1635508Y1562406I-1070J550D01*
G02X1634306Y1563608I0J1202D01*
G01Y1563610D01*
G02X1634455Y1564189I1202J-1D01*
G01X1636021Y1566899D01*
X1636023Y1566902D01*
G37*
G36*
G01X1640747D02*
G02X1641807Y1567538I1060J-565D01*
G01X1641809D01*
G02X1643010Y1566336I-1J-1202D01*
G02X1642849Y1565736I-1204J1D01*
G01X1641304Y1563063D01*
X1641302Y1563059D01*
G02X1640232Y1562406I-1070J550D01*
G02X1639030Y1563608I0J1202D01*
G01Y1563610D01*
G02X1639179Y1564189I1202J-1D01*
G01X1640745Y1566899D01*
X1640747Y1566902D01*
G37*
G36*
G01X1645471D02*
G02X1646531Y1567538I1060J-565D01*
G01X1646533D01*
G02X1647734Y1566336I-1J-1202D01*
G02X1647573Y1565736I-1204J1D01*
G01X1646028Y1563063D01*
X1646026Y1563059D01*
G02X1644956Y1562406I-1070J550D01*
G02X1643754Y1563608I0J1202D01*
G01Y1563610D01*
G02X1643903Y1564189I1202J-1D01*
G01X1645469Y1566899D01*
X1645471Y1566902D01*
G37*
G36*
G01X1650194Y1566899D02*
X1650196Y1566902D01*
G02X1651256Y1567538I1060J-565D01*
G02X1652458Y1566336I0J-1202D01*
G01Y1566335D01*
G02X1652298Y1565736I-1203J1D01*
G01X1650753Y1563063D01*
X1650751Y1563059D01*
G02X1649681Y1562406I-1070J550D01*
G01X1649679D01*
G02X1648478Y1563608I1J1202D01*
G01Y1563610D01*
G02X1648628Y1564189I1203J-3D01*
G01X1650194Y1566899D01*
G37*
G36*
G01X1654918D02*
X1654920Y1566902D01*
G02X1655980Y1567538I1060J-565D01*
G02X1657182Y1566336I0J-1202D01*
G01Y1566335D01*
G02X1657022Y1565736I-1203J1D01*
G01X1655477Y1563063D01*
X1655475Y1563059D01*
G02X1654405Y1562406I-1070J550D01*
G01X1654403D01*
G02X1653202Y1563608I1J1202D01*
G01Y1563610D01*
G02X1653352Y1564189I1203J-3D01*
G01X1654918Y1566899D01*
G37*
G36*
G01X1659645Y1566902D02*
G02X1660705Y1567538I1060J-565D01*
G01X1660707D01*
G02X1661908Y1566336I-1J-1202D01*
G02X1661747Y1565736I-1204J1D01*
G01X1660202Y1563063D01*
X1660200Y1563059D01*
G02X1659130Y1562406I-1070J550D01*
G02X1657928Y1563608I0J1202D01*
G01Y1563610D01*
G02X1658077Y1564189I1202J-1D01*
G01X1659643Y1566899D01*
X1659645Y1566902D01*
G37*
G36*
G01X408001Y1575620D02*
G02X407422Y1576805I923J1185D01*
G02X410428I1503J0D01*
G02X409849Y1575620I-1502J0D01*
G03X409772Y1575463I123J-158D01*
G01Y1575147D01*
G03X409849Y1574990I200J1D01*
G02X410428Y1573805I-923J-1185D01*
G02X407422I-1503J0D01*
G02X408001Y1574990I1502J0D01*
G03X408078Y1575147I-123J158D01*
G01Y1575463D01*
G03X408001Y1575620I-200J-1D01*
G37*
G36*
G01X188166Y1590878D02*
G02Y1593882I0J1502D01*
G01X191566D01*
G02Y1590878I0J-1502D01*
G01X188166D01*
G37*
G36*
G01X200226D02*
G02Y1593882I0J1502D01*
G01X203626D01*
G02Y1590878I0J-1502D01*
G01X200226D01*
G37*
G36*
G01X212286D02*
G02Y1593882I0J1502D01*
G01X215686D01*
G02Y1590878I0J-1502D01*
G01X212286D01*
G37*
G36*
G01X224346D02*
G02Y1593882I0J1502D01*
G01X227746D01*
G02Y1590878I0J-1502D01*
G01X224346D01*
G37*
G36*
G01X236406D02*
G02Y1593882I0J1502D01*
G01X239806D01*
G02Y1590878I0J-1502D01*
G01X236406D01*
G37*
G36*
G01X248466D02*
G02Y1593882I0J1502D01*
G01X251866D01*
G02Y1590878I0J-1502D01*
G01X248466D01*
G37*
G36*
G01X260526D02*
G02Y1593882I0J1502D01*
G01X263926D01*
G02Y1590878I0J-1502D01*
G01X260526D01*
G37*
G36*
G01X272586D02*
G02Y1593882I0J1502D01*
G01X275986D01*
G02Y1590878I0J-1502D01*
G01X272586D01*
G37*
G36*
G01X284646D02*
G02Y1593882I0J1502D01*
G01X288046D01*
G02Y1590878I0J-1502D01*
G01X284646D01*
G37*
G36*
G01X296706D02*
G02Y1593882I0J1502D01*
G01X300106D01*
G02Y1590878I0J-1502D01*
G01X296706D01*
G37*
G36*
G01X308766D02*
G02Y1593882I0J1502D01*
G01X312166D01*
G02Y1590878I0J-1502D01*
G01X308766D01*
G37*
G36*
G01X320826D02*
G02Y1593882I0J1502D01*
G01X324226D01*
G02Y1590878I0J-1502D01*
G01X320826D01*
G37*
G36*
G01X332886D02*
G02Y1593882I0J1502D01*
G01X336286D01*
G02Y1590878I0J-1502D01*
G01X332886D01*
G37*
G36*
G01X344946D02*
G02Y1593882I0J1502D01*
G01X348346D01*
G02Y1590878I0J-1502D01*
G01X344946D01*
G37*
G36*
G01X357006D02*
G02Y1593882I0J1502D01*
G01X360406D01*
G02Y1590878I0J-1502D01*
G01X357006D01*
G37*
G36*
G01X369066D02*
G02Y1593882I0J1502D01*
G01X372466D01*
G02Y1590878I0J-1502D01*
G01X369066D01*
G37*
G36*
G01X452339D02*
G02Y1593882I0J1502D01*
G01X455739D01*
G02Y1590878I0J-1502D01*
G01X452339D01*
G37*
G36*
G01X464399D02*
G02Y1593882I0J1502D01*
G01X467799D01*
G02Y1590878I0J-1502D01*
G01X464399D01*
G37*
G36*
G01X476459D02*
G02Y1593882I0J1502D01*
G01X479859D01*
G02Y1590878I0J-1502D01*
G01X476459D01*
G37*
G36*
G01X488519D02*
G02Y1593882I0J1502D01*
G01X491919D01*
G02Y1590878I0J-1502D01*
G01X488519D01*
G37*
G36*
G01X500579D02*
G02Y1593882I0J1502D01*
G01X503979D01*
G02Y1590878I0J-1502D01*
G01X500579D01*
G37*
G36*
G01X512639D02*
G02Y1593882I0J1502D01*
G01X516039D01*
G02Y1590878I0J-1502D01*
G01X512639D01*
G37*
G36*
G01X524699D02*
G02Y1593882I0J1502D01*
G01X528099D01*
G02Y1590878I0J-1502D01*
G01X524699D01*
G37*
G36*
G01X536759D02*
G02Y1593882I0J1502D01*
G01X540159D01*
G02Y1590878I0J-1502D01*
G01X536759D01*
G37*
G36*
G01X548819D02*
G02Y1593882I0J1502D01*
G01X552219D01*
G02Y1590878I0J-1502D01*
G01X548819D01*
G37*
G36*
G01X560879D02*
G02Y1593882I0J1502D01*
G01X564279D01*
G02Y1590878I0J-1502D01*
G01X560879D01*
G37*
G36*
G01X572939D02*
G02Y1593882I0J1502D01*
G01X576339D01*
G02Y1590878I0J-1502D01*
G01X572939D01*
G37*
G36*
G01X584999D02*
G02Y1593882I0J1502D01*
G01X588399D01*
G02Y1590878I0J-1502D01*
G01X584999D01*
G37*
G36*
G01X597059D02*
G02Y1593882I0J1502D01*
G01X600459D01*
G02Y1590878I0J-1502D01*
G01X597059D01*
G37*
G36*
G01X609119D02*
G02Y1593882I0J1502D01*
G01X612519D01*
G02Y1590878I0J-1502D01*
G01X609119D01*
G37*
G36*
G01X621179D02*
G02Y1593882I0J1502D01*
G01X624579D01*
G02Y1590878I0J-1502D01*
G01X621179D01*
G37*
G36*
G01X633239D02*
G02Y1593882I0J1502D01*
G01X636639D01*
G02Y1590878I0J-1502D01*
G01X633239D01*
G37*
G36*
G01X422069Y1593930D02*
G02Y1596936I0J1503D01*
G01X425469D01*
G02Y1593930I0J-1503D01*
G01X422069D01*
G37*
G36*
G01X409929Y1595939D02*
G02X412054Y1598064I1063J1062D01*
G01X414459Y1595660D01*
G02X414899Y1594597I-1064J-1063D01*
G02X413396Y1593094I-1503J0D01*
G02X412333Y1593534I0J1504D01*
G01X409929Y1595939D01*
G37*
G36*
G01X194196Y1600878D02*
G02Y1603882I0J1502D01*
G01X197596D01*
G02Y1600878I0J-1502D01*
G01X194196D01*
G37*
G36*
G01X206256D02*
G02Y1603882I0J1502D01*
G01X209656D01*
G02Y1600878I0J-1502D01*
G01X206256D01*
G37*
G36*
G01X218316D02*
G02Y1603882I0J1502D01*
G01X221716D01*
G02Y1600878I0J-1502D01*
G01X218316D01*
G37*
G36*
G01X230376D02*
G02Y1603882I0J1502D01*
G01X233776D01*
G02Y1600878I0J-1502D01*
G01X230376D01*
G37*
G36*
G01X242436D02*
G02Y1603882I0J1502D01*
G01X245836D01*
G02Y1600878I0J-1502D01*
G01X242436D01*
G37*
G36*
G01X254496D02*
G02Y1603882I0J1502D01*
G01X257896D01*
G02Y1600878I0J-1502D01*
G01X254496D01*
G37*
G36*
G01X266556D02*
G02Y1603882I0J1502D01*
G01X269956D01*
G02Y1600878I0J-1502D01*
G01X266556D01*
G37*
G36*
G01X278616D02*
G02Y1603882I0J1502D01*
G01X282016D01*
G02Y1600878I0J-1502D01*
G01X278616D01*
G37*
G36*
G01X290676D02*
G02Y1603882I0J1502D01*
G01X294076D01*
G02Y1600878I0J-1502D01*
G01X290676D01*
G37*
G36*
G01X302736D02*
G02Y1603882I0J1502D01*
G01X306136D01*
G02Y1600878I0J-1502D01*
G01X302736D01*
G37*
G36*
G01X314796D02*
G02Y1603882I0J1502D01*
G01X318196D01*
G02Y1600878I0J-1502D01*
G01X314796D01*
G37*
G36*
G01X326856D02*
G02Y1603882I0J1502D01*
G01X330256D01*
G02Y1600878I0J-1502D01*
G01X326856D01*
G37*
G36*
G01X338916D02*
G02Y1603882I0J1502D01*
G01X342316D01*
G02Y1600878I0J-1502D01*
G01X338916D01*
G37*
G36*
G01X350976D02*
G02Y1603882I0J1502D01*
G01X354376D01*
G02Y1600878I0J-1502D01*
G01X350976D01*
G37*
G36*
G01X363036D02*
G02Y1603882I0J1502D01*
G01X366436D01*
G02Y1600878I0J-1502D01*
G01X363036D01*
G37*
G36*
G01X375096D02*
G02Y1603882I0J1502D01*
G01X378496D01*
G02Y1600878I0J-1502D01*
G01X375096D01*
G37*
G36*
G01X458369D02*
G02Y1603882I0J1502D01*
G01X461769D01*
G02Y1600878I0J-1502D01*
G01X458369D01*
G37*
G36*
G01X470429D02*
G02Y1603882I0J1502D01*
G01X473829D01*
G02Y1600878I0J-1502D01*
G01X470429D01*
G37*
G36*
G01X482489D02*
G02Y1603882I0J1502D01*
G01X485889D01*
G02Y1600878I0J-1502D01*
G01X482489D01*
G37*
G36*
G01X494549D02*
G02Y1603882I0J1502D01*
G01X497949D01*
G02Y1600878I0J-1502D01*
G01X494549D01*
G37*
G36*
G01X506609D02*
G02Y1603882I0J1502D01*
G01X510009D01*
G02Y1600878I0J-1502D01*
G01X506609D01*
G37*
G36*
G01X518669D02*
G02Y1603882I0J1502D01*
G01X522069D01*
G02Y1600878I0J-1502D01*
G01X518669D01*
G37*
G36*
G01X530729D02*
G02Y1603882I0J1502D01*
G01X534129D01*
G02Y1600878I0J-1502D01*
G01X530729D01*
G37*
G36*
G01X542789D02*
G02Y1603882I0J1502D01*
G01X546189D01*
G02Y1600878I0J-1502D01*
G01X542789D01*
G37*
G36*
G01X554849D02*
G02Y1603882I0J1502D01*
G01X558249D01*
G02Y1600878I0J-1502D01*
G01X554849D01*
G37*
G36*
G01X566909D02*
G02Y1603882I0J1502D01*
G01X570309D01*
G02Y1600878I0J-1502D01*
G01X566909D01*
G37*
G36*
G01X578969D02*
G02Y1603882I0J1502D01*
G01X582369D01*
G02Y1600878I0J-1502D01*
G01X578969D01*
G37*
G36*
G01X591029D02*
G02Y1603882I0J1502D01*
G01X594429D01*
G02Y1600878I0J-1502D01*
G01X591029D01*
G37*
G36*
G01X603089D02*
G02Y1603882I0J1502D01*
G01X606489D01*
G02Y1600878I0J-1502D01*
G01X603089D01*
G37*
G36*
G01X615149D02*
G02Y1603882I0J1502D01*
G01X618549D01*
G02Y1600878I0J-1502D01*
G01X615149D01*
G37*
G36*
G01X627209D02*
G02Y1603882I0J1502D01*
G01X630609D01*
G02Y1600878I0J-1502D01*
G01X627209D01*
G37*
G36*
G01X639269D02*
G02Y1603882I0J1502D01*
G01X642669D01*
G02Y1600878I0J-1502D01*
G01X639269D01*
G37*
G36*
G01X1113847Y1603052D02*
G02Y1606056I0J1502D01*
G01X1117247D01*
G02Y1603052I0J-1502D01*
G01X1113847D01*
G37*
G36*
G01X194196Y1612790D02*
G02Y1615794I0J1502D01*
G01X197596D01*
G02Y1612790I0J-1502D01*
G01X194196D01*
G37*
G36*
G01X206256D02*
G02Y1615794I0J1502D01*
G01X209656D01*
G02Y1612790I0J-1502D01*
G01X206256D01*
G37*
G36*
G01X218316D02*
G02Y1615794I0J1502D01*
G01X221716D01*
G02Y1612790I0J-1502D01*
G01X218316D01*
G37*
G36*
G01X230376D02*
G02Y1615794I0J1502D01*
G01X233776D01*
G02Y1612790I0J-1502D01*
G01X230376D01*
G37*
G36*
G01X242436D02*
G02Y1615794I0J1502D01*
G01X245836D01*
G02Y1612790I0J-1502D01*
G01X242436D01*
G37*
G36*
G01X254496D02*
G02Y1615794I0J1502D01*
G01X257896D01*
G02Y1612790I0J-1502D01*
G01X254496D01*
G37*
G36*
G01X266556D02*
G02Y1615794I0J1502D01*
G01X269956D01*
G02Y1612790I0J-1502D01*
G01X266556D01*
G37*
G36*
G01X278616D02*
G02Y1615794I0J1502D01*
G01X282016D01*
G02Y1612790I0J-1502D01*
G01X278616D01*
G37*
G36*
G01X290676D02*
G02Y1615794I0J1502D01*
G01X294076D01*
G02Y1612790I0J-1502D01*
G01X290676D01*
G37*
G36*
G01X302736D02*
G02Y1615794I0J1502D01*
G01X306136D01*
G02Y1612790I0J-1502D01*
G01X302736D01*
G37*
G36*
G01X314796D02*
G02Y1615794I0J1502D01*
G01X318196D01*
G02Y1612790I0J-1502D01*
G01X314796D01*
G37*
G36*
G01X326856D02*
G02Y1615794I0J1502D01*
G01X330256D01*
G02Y1612790I0J-1502D01*
G01X326856D01*
G37*
G36*
G01X338916D02*
G02Y1615794I0J1502D01*
G01X342316D01*
G02Y1612790I0J-1502D01*
G01X338916D01*
G37*
G36*
G01X350976D02*
G02Y1615794I0J1502D01*
G01X354376D01*
G02Y1612790I0J-1502D01*
G01X350976D01*
G37*
G36*
G01X363036D02*
G02Y1615794I0J1502D01*
G01X366436D01*
G02Y1612790I0J-1502D01*
G01X363036D01*
G37*
G36*
G01X375096D02*
G02Y1615794I0J1502D01*
G01X378496D01*
G02Y1612790I0J-1502D01*
G01X375096D01*
G37*
G36*
G01X458369D02*
G02Y1615794I0J1502D01*
G01X461769D01*
G02Y1612790I0J-1502D01*
G01X458369D01*
G37*
G36*
G01X470429D02*
G02Y1615794I0J1502D01*
G01X473829D01*
G02Y1612790I0J-1502D01*
G01X470429D01*
G37*
G36*
G01X482489D02*
G02Y1615794I0J1502D01*
G01X485889D01*
G02Y1612790I0J-1502D01*
G01X482489D01*
G37*
G36*
G01X494549D02*
G02Y1615794I0J1502D01*
G01X497949D01*
G02Y1612790I0J-1502D01*
G01X494549D01*
G37*
G36*
G01X506609D02*
G02Y1615794I0J1502D01*
G01X510009D01*
G02Y1612790I0J-1502D01*
G01X506609D01*
G37*
G36*
G01X518669D02*
G02Y1615794I0J1502D01*
G01X522069D01*
G02Y1612790I0J-1502D01*
G01X518669D01*
G37*
G36*
G01X530729D02*
G02Y1615794I0J1502D01*
G01X534129D01*
G02Y1612790I0J-1502D01*
G01X530729D01*
G37*
G36*
G01X542789D02*
G02Y1615794I0J1502D01*
G01X546189D01*
G02Y1612790I0J-1502D01*
G01X542789D01*
G37*
G36*
G01X554849D02*
G02Y1615794I0J1502D01*
G01X558249D01*
G02Y1612790I0J-1502D01*
G01X554849D01*
G37*
G36*
G01X566909D02*
G02Y1615794I0J1502D01*
G01X570309D01*
G02Y1612790I0J-1502D01*
G01X566909D01*
G37*
G36*
G01X578969D02*
G02Y1615794I0J1502D01*
G01X582369D01*
G02Y1612790I0J-1502D01*
G01X578969D01*
G37*
G36*
G01X591029D02*
G02Y1615794I0J1502D01*
G01X594429D01*
G02Y1612790I0J-1502D01*
G01X591029D01*
G37*
G36*
G01X603089D02*
G02Y1615794I0J1502D01*
G01X606489D01*
G02Y1612790I0J-1502D01*
G01X603089D01*
G37*
G36*
G01X615149D02*
G02Y1615794I0J1502D01*
G01X618549D01*
G02Y1612790I0J-1502D01*
G01X615149D01*
G37*
G36*
G01X627209D02*
G02Y1615794I0J1502D01*
G01X630609D01*
G02Y1612790I0J-1502D01*
G01X627209D01*
G37*
G36*
G01X639269D02*
G02Y1615794I0J1502D01*
G01X642669D01*
G02Y1612790I0J-1502D01*
G01X639269D01*
G37*
G36*
G01X188166Y1622790D02*
G02Y1625794I0J1502D01*
G01X191566D01*
G02Y1622790I0J-1502D01*
G01X188166D01*
G37*
G36*
G01X200226D02*
G02Y1625794I0J1502D01*
G01X203626D01*
G02Y1622790I0J-1502D01*
G01X200226D01*
G37*
G36*
G01X212286D02*
G02Y1625794I0J1502D01*
G01X215686D01*
G02Y1622790I0J-1502D01*
G01X212286D01*
G37*
G36*
G01X224346D02*
G02Y1625794I0J1502D01*
G01X227746D01*
G02Y1622790I0J-1502D01*
G01X224346D01*
G37*
G36*
G01X236406D02*
G02Y1625794I0J1502D01*
G01X239806D01*
G02Y1622790I0J-1502D01*
G01X236406D01*
G37*
G36*
G01X248466D02*
G02Y1625794I0J1502D01*
G01X251866D01*
G02Y1622790I0J-1502D01*
G01X248466D01*
G37*
G36*
G01X260526D02*
G02Y1625794I0J1502D01*
G01X263926D01*
G02Y1622790I0J-1502D01*
G01X260526D01*
G37*
G36*
G01X272586D02*
G02Y1625794I0J1502D01*
G01X275986D01*
G02Y1622790I0J-1502D01*
G01X272586D01*
G37*
G36*
G01X284646D02*
G02Y1625794I0J1502D01*
G01X288046D01*
G02Y1622790I0J-1502D01*
G01X284646D01*
G37*
G36*
G01X296706D02*
G02Y1625794I0J1502D01*
G01X300106D01*
G02Y1622790I0J-1502D01*
G01X296706D01*
G37*
G36*
G01X308766D02*
G02Y1625794I0J1502D01*
G01X312166D01*
G02Y1622790I0J-1502D01*
G01X308766D01*
G37*
G36*
G01X320826D02*
G02Y1625794I0J1502D01*
G01X324226D01*
G02Y1622790I0J-1502D01*
G01X320826D01*
G37*
G36*
G01X332886D02*
G02Y1625794I0J1502D01*
G01X336286D01*
G02Y1622790I0J-1502D01*
G01X332886D01*
G37*
G36*
G01X344946D02*
G02Y1625794I0J1502D01*
G01X348346D01*
G02Y1622790I0J-1502D01*
G01X344946D01*
G37*
G36*
G01X357006D02*
G02Y1625794I0J1502D01*
G01X360406D01*
G02Y1622790I0J-1502D01*
G01X357006D01*
G37*
G36*
G01X369066D02*
G02Y1625794I0J1502D01*
G01X372466D01*
G02Y1622790I0J-1502D01*
G01X369066D01*
G37*
G36*
G01X452339D02*
G02Y1625794I0J1502D01*
G01X455739D01*
G02Y1622790I0J-1502D01*
G01X452339D01*
G37*
G36*
G01X464399D02*
G02Y1625794I0J1502D01*
G01X467799D01*
G02Y1622790I0J-1502D01*
G01X464399D01*
G37*
G36*
G01X476459D02*
G02Y1625794I0J1502D01*
G01X479859D01*
G02Y1622790I0J-1502D01*
G01X476459D01*
G37*
G36*
G01X488519D02*
G02Y1625794I0J1502D01*
G01X491919D01*
G02Y1622790I0J-1502D01*
G01X488519D01*
G37*
G36*
G01X500579D02*
G02Y1625794I0J1502D01*
G01X503979D01*
G02Y1622790I0J-1502D01*
G01X500579D01*
G37*
G36*
G01X512639D02*
G02Y1625794I0J1502D01*
G01X516039D01*
G02Y1622790I0J-1502D01*
G01X512639D01*
G37*
G36*
G01X524699D02*
G02Y1625794I0J1502D01*
G01X528099D01*
G02Y1622790I0J-1502D01*
G01X524699D01*
G37*
G36*
G01X536759D02*
G02Y1625794I0J1502D01*
G01X540159D01*
G02Y1622790I0J-1502D01*
G01X536759D01*
G37*
G36*
G01X548819D02*
G02Y1625794I0J1502D01*
G01X552219D01*
G02Y1622790I0J-1502D01*
G01X548819D01*
G37*
G36*
G01X560879D02*
G02Y1625794I0J1502D01*
G01X564279D01*
G02Y1622790I0J-1502D01*
G01X560879D01*
G37*
G36*
G01X572939D02*
G02Y1625794I0J1502D01*
G01X576339D01*
G02Y1622790I0J-1502D01*
G01X572939D01*
G37*
G36*
G01X584999D02*
G02Y1625794I0J1502D01*
G01X588399D01*
G02Y1622790I0J-1502D01*
G01X584999D01*
G37*
G36*
G01X597059D02*
G02Y1625794I0J1502D01*
G01X600459D01*
G02Y1622790I0J-1502D01*
G01X597059D01*
G37*
G36*
G01X609119D02*
G02Y1625794I0J1502D01*
G01X612519D01*
G02Y1622790I0J-1502D01*
G01X609119D01*
G37*
G36*
G01X621179D02*
G02Y1625794I0J1502D01*
G01X624579D01*
G02Y1622790I0J-1502D01*
G01X621179D01*
G37*
G36*
G01X633239D02*
G02Y1625794I0J1502D01*
G01X636639D01*
G02Y1622790I0J-1502D01*
G01X633239D01*
G37*
G36*
G01X1196039Y1623878D02*
G02Y1626882I0J1502D01*
G01X1199439D01*
G02Y1623878I0J-1502D01*
G01X1196039D01*
G37*
G36*
G01X1208099D02*
G02Y1626882I0J1502D01*
G01X1211499D01*
G02Y1623878I0J-1502D01*
G01X1208099D01*
G37*
G36*
G01X1220159D02*
G02Y1626882I0J1502D01*
G01X1223559D01*
G02Y1623878I0J-1502D01*
G01X1220159D01*
G37*
G36*
G01X1232219D02*
G02Y1626882I0J1502D01*
G01X1235619D01*
G02Y1623878I0J-1502D01*
G01X1232219D01*
G37*
G36*
G01X1244279D02*
G02Y1626882I0J1502D01*
G01X1247679D01*
G02Y1623878I0J-1502D01*
G01X1244279D01*
G37*
G36*
G01X1256339D02*
G02Y1626882I0J1502D01*
G01X1259739D01*
G02Y1623878I0J-1502D01*
G01X1256339D01*
G37*
G36*
G01X1268399D02*
G02Y1626882I0J1502D01*
G01X1271799D01*
G02Y1623878I0J-1502D01*
G01X1268399D01*
G37*
G36*
G01X1280459D02*
G02Y1626882I0J1502D01*
G01X1283859D01*
G02Y1623878I0J-1502D01*
G01X1280459D01*
G37*
G36*
G01X1292519D02*
G02Y1626882I0J1502D01*
G01X1295919D01*
G02Y1623878I0J-1502D01*
G01X1292519D01*
G37*
G36*
G01X1304579D02*
G02Y1626882I0J1502D01*
G01X1307979D01*
G02Y1623878I0J-1502D01*
G01X1304579D01*
G37*
G36*
G01X1316639D02*
G02Y1626882I0J1502D01*
G01X1320039D01*
G02Y1623878I0J-1502D01*
G01X1316639D01*
G37*
G36*
G01X1328699D02*
G02Y1626882I0J1502D01*
G01X1332099D01*
G02Y1623878I0J-1502D01*
G01X1328699D01*
G37*
G36*
G01X1340759D02*
G02Y1626882I0J1502D01*
G01X1344159D01*
G02Y1623878I0J-1502D01*
G01X1340759D01*
G37*
G36*
G01X1352819D02*
G02Y1626882I0J1502D01*
G01X1356219D01*
G02Y1623878I0J-1502D01*
G01X1352819D01*
G37*
G36*
G01X1364879D02*
G02Y1626882I0J1502D01*
G01X1368279D01*
G02Y1623878I0J-1502D01*
G01X1364879D01*
G37*
G36*
G01X1376939D02*
G02Y1626882I0J1502D01*
G01X1380339D01*
G02Y1623878I0J-1502D01*
G01X1376939D01*
G37*
G36*
G01X1460213D02*
G02Y1626882I0J1502D01*
G01X1463613D01*
G02Y1623878I0J-1502D01*
G01X1460213D01*
G37*
G36*
G01X1472273D02*
G02Y1626882I0J1502D01*
G01X1475673D01*
G02Y1623878I0J-1502D01*
G01X1472273D01*
G37*
G36*
G01X1484333D02*
G02Y1626882I0J1502D01*
G01X1487733D01*
G02Y1623878I0J-1502D01*
G01X1484333D01*
G37*
G36*
G01X1496393D02*
G02Y1626882I0J1502D01*
G01X1499793D01*
G02Y1623878I0J-1502D01*
G01X1496393D01*
G37*
G36*
G01X1508453D02*
G02Y1626882I0J1502D01*
G01X1511853D01*
G02Y1623878I0J-1502D01*
G01X1508453D01*
G37*
G36*
G01X1520513D02*
G02Y1626882I0J1502D01*
G01X1523913D01*
G02Y1623878I0J-1502D01*
G01X1520513D01*
G37*
G36*
G01X1532573D02*
G02Y1626882I0J1502D01*
G01X1535973D01*
G02Y1623878I0J-1502D01*
G01X1532573D01*
G37*
G36*
G01X1544633D02*
G02Y1626882I0J1502D01*
G01X1548033D01*
G02Y1623878I0J-1502D01*
G01X1544633D01*
G37*
G36*
G01X1556693D02*
G02Y1626882I0J1502D01*
G01X1560093D01*
G02Y1623878I0J-1502D01*
G01X1556693D01*
G37*
G36*
G01X1568753D02*
G02Y1626882I0J1502D01*
G01X1572153D01*
G02Y1623878I0J-1502D01*
G01X1568753D01*
G37*
G36*
G01X1580813D02*
G02Y1626882I0J1502D01*
G01X1584213D01*
G02Y1623878I0J-1502D01*
G01X1580813D01*
G37*
G36*
G01X1592873D02*
G02Y1626882I0J1502D01*
G01X1596273D01*
G02Y1623878I0J-1502D01*
G01X1592873D01*
G37*
G36*
G01X1604933D02*
G02Y1626882I0J1502D01*
G01X1608333D01*
G02Y1623878I0J-1502D01*
G01X1604933D01*
G37*
G36*
G01X1616993D02*
G02Y1626882I0J1502D01*
G01X1620393D01*
G02Y1623878I0J-1502D01*
G01X1616993D01*
G37*
G36*
G01X1629053D02*
G02Y1626882I0J1502D01*
G01X1632453D01*
G02Y1623878I0J-1502D01*
G01X1629053D01*
G37*
G36*
G01X1641113D02*
G02Y1626882I0J1502D01*
G01X1644513D01*
G02Y1623878I0J-1502D01*
G01X1641113D01*
G37*
G36*
G01X417365Y1626192D02*
G02Y1629198I0J1503D01*
G01X420765D01*
G02Y1626192I0J-1503D01*
G01X417365D01*
G37*
G36*
G01X1202069Y1633878D02*
G02Y1636882I0J1502D01*
G01X1205469D01*
G02Y1633878I0J-1502D01*
G01X1202069D01*
G37*
G36*
G01X1214129D02*
G02Y1636882I0J1502D01*
G01X1217529D01*
G02Y1633878I0J-1502D01*
G01X1214129D01*
G37*
G36*
G01X1226189D02*
G02Y1636882I0J1502D01*
G01X1229589D01*
G02Y1633878I0J-1502D01*
G01X1226189D01*
G37*
G36*
G01X1238249D02*
G02Y1636882I0J1502D01*
G01X1241649D01*
G02Y1633878I0J-1502D01*
G01X1238249D01*
G37*
G36*
G01X1250309D02*
G02Y1636882I0J1502D01*
G01X1253709D01*
G02Y1633878I0J-1502D01*
G01X1250309D01*
G37*
G36*
G01X1262369D02*
G02Y1636882I0J1502D01*
G01X1265769D01*
G02Y1633878I0J-1502D01*
G01X1262369D01*
G37*
G36*
G01X1274429D02*
G02Y1636882I0J1502D01*
G01X1277829D01*
G02Y1633878I0J-1502D01*
G01X1274429D01*
G37*
G36*
G01X1286489D02*
G02Y1636882I0J1502D01*
G01X1289889D01*
G02Y1633878I0J-1502D01*
G01X1286489D01*
G37*
G36*
G01X1298549D02*
G02Y1636882I0J1502D01*
G01X1301949D01*
G02Y1633878I0J-1502D01*
G01X1298549D01*
G37*
G36*
G01X1310609D02*
G02Y1636882I0J1502D01*
G01X1314009D01*
G02Y1633878I0J-1502D01*
G01X1310609D01*
G37*
G36*
G01X1322669D02*
G02Y1636882I0J1502D01*
G01X1326069D01*
G02Y1633878I0J-1502D01*
G01X1322669D01*
G37*
G36*
G01X1334729D02*
G02Y1636882I0J1502D01*
G01X1338129D01*
G02Y1633878I0J-1502D01*
G01X1334729D01*
G37*
G36*
G01X1346789D02*
G02Y1636882I0J1502D01*
G01X1350189D01*
G02Y1633878I0J-1502D01*
G01X1346789D01*
G37*
G36*
G01X1358849D02*
G02Y1636882I0J1502D01*
G01X1362249D01*
G02Y1633878I0J-1502D01*
G01X1358849D01*
G37*
G36*
G01X1370909D02*
G02Y1636882I0J1502D01*
G01X1374309D01*
G02Y1633878I0J-1502D01*
G01X1370909D01*
G37*
G36*
G01X1382969D02*
G02Y1636882I0J1502D01*
G01X1386369D01*
G02Y1633878I0J-1502D01*
G01X1382969D01*
G37*
G36*
G01X1466243D02*
G02Y1636882I0J1502D01*
G01X1469643D01*
G02Y1633878I0J-1502D01*
G01X1466243D01*
G37*
G36*
G01X1478303D02*
G02Y1636882I0J1502D01*
G01X1481703D01*
G02Y1633878I0J-1502D01*
G01X1478303D01*
G37*
G36*
G01X1490363D02*
G02Y1636882I0J1502D01*
G01X1493763D01*
G02Y1633878I0J-1502D01*
G01X1490363D01*
G37*
G36*
G01X1502423D02*
G02Y1636882I0J1502D01*
G01X1505823D01*
G02Y1633878I0J-1502D01*
G01X1502423D01*
G37*
G36*
G01X1514483D02*
G02Y1636882I0J1502D01*
G01X1517883D01*
G02Y1633878I0J-1502D01*
G01X1514483D01*
G37*
G36*
G01X1526543D02*
G02Y1636882I0J1502D01*
G01X1529943D01*
G02Y1633878I0J-1502D01*
G01X1526543D01*
G37*
G36*
G01X1538603D02*
G02Y1636882I0J1502D01*
G01X1542003D01*
G02Y1633878I0J-1502D01*
G01X1538603D01*
G37*
G36*
G01X1550663D02*
G02Y1636882I0J1502D01*
G01X1554063D01*
G02Y1633878I0J-1502D01*
G01X1550663D01*
G37*
G36*
G01X1562723D02*
G02Y1636882I0J1502D01*
G01X1566123D01*
G02Y1633878I0J-1502D01*
G01X1562723D01*
G37*
G36*
G01X1574783D02*
G02Y1636882I0J1502D01*
G01X1578183D01*
G02Y1633878I0J-1502D01*
G01X1574783D01*
G37*
G36*
G01X1586843D02*
G02Y1636882I0J1502D01*
G01X1590243D01*
G02Y1633878I0J-1502D01*
G01X1586843D01*
G37*
G36*
G01X1598903D02*
G02Y1636882I0J1502D01*
G01X1602303D01*
G02Y1633878I0J-1502D01*
G01X1598903D01*
G37*
G36*
G01X1610963D02*
G02Y1636882I0J1502D01*
G01X1614363D01*
G02Y1633878I0J-1502D01*
G01X1610963D01*
G37*
G36*
G01X1623023D02*
G02Y1636882I0J1502D01*
G01X1626423D01*
G02Y1633878I0J-1502D01*
G01X1623023D01*
G37*
G36*
G01X1635083D02*
G02Y1636882I0J1502D01*
G01X1638483D01*
G02Y1633878I0J-1502D01*
G01X1635083D01*
G37*
G36*
G01X1647143D02*
G02Y1636882I0J1502D01*
G01X1650543D01*
G02Y1633878I0J-1502D01*
G01X1647143D01*
G37*
G36*
G01X1202069Y1645790D02*
G02Y1648794I0J1502D01*
G01X1205469D01*
G02Y1645790I0J-1502D01*
G01X1202069D01*
G37*
G36*
G01X1214129D02*
G02Y1648794I0J1502D01*
G01X1217529D01*
G02Y1645790I0J-1502D01*
G01X1214129D01*
G37*
G36*
G01X1226189D02*
G02Y1648794I0J1502D01*
G01X1229589D01*
G02Y1645790I0J-1502D01*
G01X1226189D01*
G37*
G36*
G01X1238249D02*
G02Y1648794I0J1502D01*
G01X1241649D01*
G02Y1645790I0J-1502D01*
G01X1238249D01*
G37*
G36*
G01X1250309D02*
G02Y1648794I0J1502D01*
G01X1253709D01*
G02Y1645790I0J-1502D01*
G01X1250309D01*
G37*
G36*
G01X1262369D02*
G02Y1648794I0J1502D01*
G01X1265769D01*
G02Y1645790I0J-1502D01*
G01X1262369D01*
G37*
G36*
G01X1274429D02*
G02Y1648794I0J1502D01*
G01X1277829D01*
G02Y1645790I0J-1502D01*
G01X1274429D01*
G37*
G36*
G01X1286489D02*
G02Y1648794I0J1502D01*
G01X1289889D01*
G02Y1645790I0J-1502D01*
G01X1286489D01*
G37*
G36*
G01X1298549D02*
G02Y1648794I0J1502D01*
G01X1301949D01*
G02Y1645790I0J-1502D01*
G01X1298549D01*
G37*
G36*
G01X1310609D02*
G02Y1648794I0J1502D01*
G01X1314009D01*
G02Y1645790I0J-1502D01*
G01X1310609D01*
G37*
G36*
G01X1322669D02*
G02Y1648794I0J1502D01*
G01X1326069D01*
G02Y1645790I0J-1502D01*
G01X1322669D01*
G37*
G36*
G01X1334729D02*
G02Y1648794I0J1502D01*
G01X1338129D01*
G02Y1645790I0J-1502D01*
G01X1334729D01*
G37*
G36*
G01X1346789D02*
G02Y1648794I0J1502D01*
G01X1350189D01*
G02Y1645790I0J-1502D01*
G01X1346789D01*
G37*
G36*
G01X1358849D02*
G02Y1648794I0J1502D01*
G01X1362249D01*
G02Y1645790I0J-1502D01*
G01X1358849D01*
G37*
G36*
G01X1370909D02*
G02Y1648794I0J1502D01*
G01X1374309D01*
G02Y1645790I0J-1502D01*
G01X1370909D01*
G37*
G36*
G01X1382969D02*
G02Y1648794I0J1502D01*
G01X1386369D01*
G02Y1645790I0J-1502D01*
G01X1382969D01*
G37*
G36*
G01X1466243D02*
G02Y1648794I0J1502D01*
G01X1469643D01*
G02Y1645790I0J-1502D01*
G01X1466243D01*
G37*
G36*
G01X1478303D02*
G02Y1648794I0J1502D01*
G01X1481703D01*
G02Y1645790I0J-1502D01*
G01X1478303D01*
G37*
G36*
G01X1490363D02*
G02Y1648794I0J1502D01*
G01X1493763D01*
G02Y1645790I0J-1502D01*
G01X1490363D01*
G37*
G36*
G01X1502423D02*
G02Y1648794I0J1502D01*
G01X1505823D01*
G02Y1645790I0J-1502D01*
G01X1502423D01*
G37*
G36*
G01X1514483D02*
G02Y1648794I0J1502D01*
G01X1517883D01*
G02Y1645790I0J-1502D01*
G01X1514483D01*
G37*
G36*
G01X1526543D02*
G02Y1648794I0J1502D01*
G01X1529943D01*
G02Y1645790I0J-1502D01*
G01X1526543D01*
G37*
G36*
G01X1538603D02*
G02Y1648794I0J1502D01*
G01X1542003D01*
G02Y1645790I0J-1502D01*
G01X1538603D01*
G37*
G36*
G01X1550663D02*
G02Y1648794I0J1502D01*
G01X1554063D01*
G02Y1645790I0J-1502D01*
G01X1550663D01*
G37*
G36*
G01X1562723D02*
G02Y1648794I0J1502D01*
G01X1566123D01*
G02Y1645790I0J-1502D01*
G01X1562723D01*
G37*
G36*
G01X1574783D02*
G02Y1648794I0J1502D01*
G01X1578183D01*
G02Y1645790I0J-1502D01*
G01X1574783D01*
G37*
G36*
G01X1586843D02*
G02Y1648794I0J1502D01*
G01X1590243D01*
G02Y1645790I0J-1502D01*
G01X1586843D01*
G37*
G36*
G01X1598903D02*
G02Y1648794I0J1502D01*
G01X1602303D01*
G02Y1645790I0J-1502D01*
G01X1598903D01*
G37*
G36*
G01X1610963D02*
G02Y1648794I0J1502D01*
G01X1614363D01*
G02Y1645790I0J-1502D01*
G01X1610963D01*
G37*
G36*
G01X1623023D02*
G02Y1648794I0J1502D01*
G01X1626423D01*
G02Y1645790I0J-1502D01*
G01X1623023D01*
G37*
G36*
G01X1635083D02*
G02Y1648794I0J1502D01*
G01X1638483D01*
G02Y1645790I0J-1502D01*
G01X1635083D01*
G37*
G36*
G01X1647143D02*
G02Y1648794I0J1502D01*
G01X1650543D01*
G02Y1645790I0J-1502D01*
G01X1647143D01*
G37*
G36*
G01X228902Y1656537D02*
G02X229205Y1656840I303J0D01*
G01X232905D01*
G02X233208Y1656537I0J-303D01*
G01Y1646531D01*
G02X232905Y1646228I-303J0D01*
G01X229205D01*
G02X228902Y1646531I0J303D01*
G01Y1656537D01*
G37*
G36*
G01X276146D02*
G02X276449Y1656840I303J0D01*
G01X280149D01*
G02X280452Y1656537I0J-303D01*
G01Y1646531D01*
G02X280149Y1646228I-303J0D01*
G01X276449D01*
G02X276146Y1646531I0J303D01*
G01Y1656537D01*
G37*
G36*
G01X382478Y1657961D02*
G02X382681Y1658164I203J0D01*
G01X401967D01*
G02X402170Y1657961I0J-203D01*
G01Y1631213D01*
G02X401967Y1631010I-203J0D01*
G01X382681D01*
G02X382478Y1631213I0J203D01*
G01Y1657961D01*
G37*
G36*
G01X1196039Y1655790D02*
G02Y1658794I0J1502D01*
G01X1199439D01*
G02Y1655790I0J-1502D01*
G01X1196039D01*
G37*
G36*
G01X1208099D02*
G02Y1658794I0J1502D01*
G01X1211499D01*
G02Y1655790I0J-1502D01*
G01X1208099D01*
G37*
G36*
G01X1220159D02*
G02Y1658794I0J1502D01*
G01X1223559D01*
G02Y1655790I0J-1502D01*
G01X1220159D01*
G37*
G36*
G01X1232219D02*
G02Y1658794I0J1502D01*
G01X1235619D01*
G02Y1655790I0J-1502D01*
G01X1232219D01*
G37*
G36*
G01X1244279D02*
G02Y1658794I0J1502D01*
G01X1247679D01*
G02Y1655790I0J-1502D01*
G01X1244279D01*
G37*
G36*
G01X1256339D02*
G02Y1658794I0J1502D01*
G01X1259739D01*
G02Y1655790I0J-1502D01*
G01X1256339D01*
G37*
G36*
G01X1268399D02*
G02Y1658794I0J1502D01*
G01X1271799D01*
G02Y1655790I0J-1502D01*
G01X1268399D01*
G37*
G36*
G01X1280459D02*
G02Y1658794I0J1502D01*
G01X1283859D01*
G02Y1655790I0J-1502D01*
G01X1280459D01*
G37*
G36*
G01X1292519D02*
G02Y1658794I0J1502D01*
G01X1295919D01*
G02Y1655790I0J-1502D01*
G01X1292519D01*
G37*
G36*
G01X1304579D02*
G02Y1658794I0J1502D01*
G01X1307979D01*
G02Y1655790I0J-1502D01*
G01X1304579D01*
G37*
G36*
G01X1316639D02*
G02Y1658794I0J1502D01*
G01X1320039D01*
G02Y1655790I0J-1502D01*
G01X1316639D01*
G37*
G36*
G01X1328699D02*
G02Y1658794I0J1502D01*
G01X1332099D01*
G02Y1655790I0J-1502D01*
G01X1328699D01*
G37*
G36*
G01X1340759D02*
G02Y1658794I0J1502D01*
G01X1344159D01*
G02Y1655790I0J-1502D01*
G01X1340759D01*
G37*
G36*
G01X1352819D02*
G02Y1658794I0J1502D01*
G01X1356219D01*
G02Y1655790I0J-1502D01*
G01X1352819D01*
G37*
G36*
G01X1364879D02*
G02Y1658794I0J1502D01*
G01X1368279D01*
G02Y1655790I0J-1502D01*
G01X1364879D01*
G37*
G36*
G01X1376939D02*
G02Y1658794I0J1502D01*
G01X1380339D01*
G02Y1655790I0J-1502D01*
G01X1376939D01*
G37*
G36*
G01X1460213D02*
G02Y1658794I0J1502D01*
G01X1463613D01*
G02Y1655790I0J-1502D01*
G01X1460213D01*
G37*
G36*
G01X1472273D02*
G02Y1658794I0J1502D01*
G01X1475673D01*
G02Y1655790I0J-1502D01*
G01X1472273D01*
G37*
G36*
G01X1484333D02*
G02Y1658794I0J1502D01*
G01X1487733D01*
G02Y1655790I0J-1502D01*
G01X1484333D01*
G37*
G36*
G01X1496393D02*
G02Y1658794I0J1502D01*
G01X1499793D01*
G02Y1655790I0J-1502D01*
G01X1496393D01*
G37*
G36*
G01X1508453D02*
G02Y1658794I0J1502D01*
G01X1511853D01*
G02Y1655790I0J-1502D01*
G01X1508453D01*
G37*
G36*
G01X1520513D02*
G02Y1658794I0J1502D01*
G01X1523913D01*
G02Y1655790I0J-1502D01*
G01X1520513D01*
G37*
G36*
G01X1532573D02*
G02Y1658794I0J1502D01*
G01X1535973D01*
G02Y1655790I0J-1502D01*
G01X1532573D01*
G37*
G36*
G01X1544633D02*
G02Y1658794I0J1502D01*
G01X1548033D01*
G02Y1655790I0J-1502D01*
G01X1544633D01*
G37*
G36*
G01X1556693D02*
G02Y1658794I0J1502D01*
G01X1560093D01*
G02Y1655790I0J-1502D01*
G01X1556693D01*
G37*
G36*
G01X1568753D02*
G02Y1658794I0J1502D01*
G01X1572153D01*
G02Y1655790I0J-1502D01*
G01X1568753D01*
G37*
G36*
G01X1580813D02*
G02Y1658794I0J1502D01*
G01X1584213D01*
G02Y1655790I0J-1502D01*
G01X1580813D01*
G37*
G36*
G01X1592873D02*
G02Y1658794I0J1502D01*
G01X1596273D01*
G02Y1655790I0J-1502D01*
G01X1592873D01*
G37*
G36*
G01X1604933D02*
G02Y1658794I0J1502D01*
G01X1608333D01*
G02Y1655790I0J-1502D01*
G01X1604933D01*
G37*
G36*
G01X1616993D02*
G02Y1658794I0J1502D01*
G01X1620393D01*
G02Y1655790I0J-1502D01*
G01X1616993D01*
G37*
G36*
G01X1629053D02*
G02Y1658794I0J1502D01*
G01X1632453D01*
G02Y1655790I0J-1502D01*
G01X1629053D01*
G37*
G36*
G01X1641113D02*
G02Y1658794I0J1502D01*
G01X1644513D01*
G02Y1655790I0J-1502D01*
G01X1641113D01*
G37*
G36*
G01X236776Y1660474D02*
G02X237079Y1660776I303J-1D01*
G01X240781D01*
G02X241082Y1660474I-1J-302D01*
G01Y1650468D01*
G02X240779Y1650166I-303J1D01*
G01X237077D01*
G02X236776Y1650468I1J302D01*
G01Y1660474D01*
G37*
G36*
G01X268272D02*
G02X268575Y1660776I303J-1D01*
G01X272277D01*
G02X272578Y1660474I-1J-302D01*
G01Y1650468D01*
G02X272275Y1650166I-303J1D01*
G01X268573D01*
G02X268272Y1650468I1J302D01*
G01Y1660474D01*
G37*
G36*
G01X284020D02*
G02X284323Y1660776I303J-1D01*
G01X288025D01*
G02X288326Y1660474I-1J-302D01*
G01Y1650468D01*
G02X288023Y1650166I-303J1D01*
G01X284321D01*
G02X284020Y1650468I1J302D01*
G01Y1660474D01*
G37*
G36*
G01X109073Y1658732D02*
G02Y1661738I0J1503D01*
G01X112473D01*
G02Y1658732I0J-1503D01*
G01X109073D01*
G37*
G36*
G01X1125784Y1661202D02*
G02Y1664208I0J1503D01*
G01X1129184D01*
G02Y1661202I0J-1503D01*
G01X1125784D01*
G37*
G36*
G01X1438232Y1664144D02*
G02X1438436Y1664348I204J0D01*
G01X1457722D01*
G02X1457926Y1664144I0J-204D01*
G01Y1658186D01*
X1457330D01*
G03X1457154Y1658002I23J-199D01*
G01Y1656638D01*
G03X1457330Y1656454I199J15D01*
G01X1457926D01*
Y1637396D01*
G02X1457722Y1637192I-204J0D01*
G01X1438436D01*
G02X1438232Y1637396I0J204D01*
G01Y1664144D01*
G37*
G36*
G01X154111Y1662430D02*
G02Y1665436I0J1503D01*
G01X157511D01*
G02Y1662430I0J-1503D01*
G01X154111D01*
G37*
G36*
G01X228902Y1670711D02*
G02X229205Y1671014I303J0D01*
G01X232905D01*
G02X233208Y1670711I0J-303D01*
G01Y1660705D01*
G02X232905Y1660402I-303J0D01*
G01X229205D01*
G02X228902Y1660705I0J303D01*
G01Y1670711D01*
G37*
G36*
G01X244650D02*
G02X244953Y1671014I303J0D01*
G01X248653D01*
G02X248956Y1670711I0J-303D01*
G01Y1660705D01*
G02X248653Y1660402I-303J0D01*
G01X244953D01*
G02X244650Y1660705I0J303D01*
G01Y1670711D01*
G37*
G36*
G01X276146D02*
G02X276449Y1671014I303J0D01*
G01X280149D01*
G02X280452Y1670711I0J-303D01*
G01Y1660705D01*
G02X280149Y1660402I-303J0D01*
G01X276449D01*
G02X276146Y1660705I0J303D01*
G01Y1670711D01*
G37*
G36*
G01X252524Y1674648D02*
G02X252827Y1674950I303J-1D01*
G01X256529D01*
G02X256830Y1674648I-1J-302D01*
G01Y1664642D01*
G02X256527Y1664340I-303J1D01*
G01X252825D01*
G02X252524Y1664642I1J302D01*
G01Y1674648D01*
G37*
G36*
G01X268272D02*
G02X268575Y1674950I303J-1D01*
G01X272277D01*
G02X272578Y1674648I-1J-302D01*
G01Y1664642D01*
G02X272275Y1664340I-303J1D01*
G01X268573D01*
G02X268272Y1664642I1J302D01*
G01Y1674648D01*
G37*
G36*
G01X284020D02*
G02X284323Y1674950I303J-1D01*
G01X288025D01*
G02X288326Y1674648I-1J-302D01*
G01Y1664642D01*
G02X288023Y1664340I-303J1D01*
G01X284321D01*
G02X284020Y1664642I1J302D01*
G01Y1674648D01*
G37*
G36*
G01X154010Y1675308D02*
G02Y1678314I0J1503D01*
G01X157410D01*
G02Y1675308I0J-1503D01*
G01X154010D01*
G37*
G36*
G01X228902Y1684884D02*
G02X229205Y1685186I303J-1D01*
G01X232907D01*
G02X233208Y1684884I-1J-302D01*
G01Y1674878D01*
G02X232905Y1674576I-303J1D01*
G01X229203D01*
G02X228902Y1674878I1J302D01*
G01Y1684884D01*
G37*
G36*
G01X244650D02*
G02X244953Y1685186I303J-1D01*
G01X248655D01*
G02X248956Y1684884I-1J-302D01*
G01Y1674878D01*
G02X248653Y1674576I-303J1D01*
G01X244951D01*
G02X244650Y1674878I1J302D01*
G01Y1684884D01*
G37*
G36*
G01X260398D02*
G02X260701Y1685186I303J-1D01*
G01X264403D01*
G02X264704Y1684884I-1J-302D01*
G01Y1674878D01*
G02X264401Y1674576I-303J1D01*
G01X260699D01*
G02X260398Y1674878I1J302D01*
G01Y1684884D01*
G37*
G36*
G01X276146D02*
G02X276449Y1685186I303J-1D01*
G01X280151D01*
G02X280452Y1684884I-1J-302D01*
G01Y1674878D01*
G02X280149Y1674576I-303J1D01*
G01X276447D01*
G02X276146Y1674878I1J302D01*
G01Y1684884D01*
G37*
G36*
G01X295832D02*
G02X296134Y1685186I302J0D01*
G01X299834D01*
G02X300136Y1684884I0J-302D01*
G01Y1674878D01*
G02X299834Y1674576I-302J0D01*
G01X296134D01*
G02X295832Y1674878I0J302D01*
G01Y1684884D01*
G37*
G36*
G01X311580D02*
G02X311882Y1685186I302J0D01*
G01X315582D01*
G02X315884Y1684884I0J-302D01*
G01Y1674878D01*
G02X315582Y1674576I-302J0D01*
G01X311882D01*
G02X311580Y1674878I0J302D01*
G01Y1684884D01*
G37*
G36*
G01X327328D02*
G02X327630Y1685186I302J0D01*
G01X331330D01*
G02X331632Y1684884I0J-302D01*
G01Y1674878D01*
G02X331330Y1674576I-302J0D01*
G01X327630D01*
G02X327328Y1674878I0J302D01*
G01Y1684884D01*
G37*
G36*
G01X343076D02*
G02X343378Y1685186I302J0D01*
G01X347078D01*
G02X347380Y1684884I0J-302D01*
G01Y1674878D01*
G02X347078Y1674576I-302J0D01*
G01X343378D01*
G02X343076Y1674878I0J302D01*
G01Y1684884D01*
G37*
G36*
G01X493076D02*
G02X493378Y1685186I302J0D01*
G01X497078D01*
G02X497380Y1684884I0J-302D01*
G01Y1674878D01*
G02X497078Y1674576I-302J0D01*
G01X493378D01*
G02X493076Y1674878I0J302D01*
G01Y1684884D01*
G37*
G36*
G01X508824D02*
G02X509126Y1685186I302J0D01*
G01X512826D01*
G02X513128Y1684884I0J-302D01*
G01Y1674878D01*
G02X512826Y1674576I-302J0D01*
G01X509126D01*
G02X508824Y1674878I0J302D01*
G01Y1684884D01*
G37*
G36*
G01X524572D02*
G02X524874Y1685186I302J0D01*
G01X528574D01*
G02X528876Y1684884I0J-302D01*
G01Y1674878D01*
G02X528574Y1674576I-302J0D01*
G01X524874D01*
G02X524572Y1674878I0J302D01*
G01Y1684884D01*
G37*
G36*
G01X540320D02*
G02X540622Y1685186I302J0D01*
G01X544322D01*
G02X544624Y1684884I0J-302D01*
G01Y1674878D01*
G02X544322Y1674576I-302J0D01*
G01X540622D01*
G02X540320Y1674878I0J302D01*
G01Y1684884D01*
G37*
G36*
G01X560004D02*
G02X560307Y1685186I303J-1D01*
G01X564009D01*
G02X564310Y1684884I-1J-302D01*
G01Y1674878D01*
G02X564007Y1674576I-303J1D01*
G01X560305D01*
G02X560004Y1674878I1J302D01*
G01Y1684884D01*
G37*
G36*
G01X575752D02*
G02X576055Y1685186I303J-1D01*
G01X579757D01*
G02X580058Y1684884I-1J-302D01*
G01Y1674878D01*
G02X579755Y1674576I-303J1D01*
G01X576053D01*
G02X575752Y1674878I1J302D01*
G01Y1684884D01*
G37*
G36*
G01X591500D02*
G02X591803Y1685186I303J-1D01*
G01X595505D01*
G02X595806Y1684884I-1J-302D01*
G01Y1674878D01*
G02X595503Y1674576I-303J1D01*
G01X591801D01*
G02X591500Y1674878I1J302D01*
G01Y1684884D01*
G37*
G36*
G01X607248D02*
G02X607551Y1685186I303J-1D01*
G01X611253D01*
G02X611554Y1684884I-1J-302D01*
G01Y1674878D01*
G02X611251Y1674576I-303J1D01*
G01X607549D01*
G02X607248Y1674878I1J302D01*
G01Y1684884D01*
G37*
G36*
G01X1236776D02*
G02X1237079Y1685186I303J-1D01*
G01X1240781D01*
G02X1241082Y1684884I-1J-302D01*
G01Y1674878D01*
G02X1240779Y1674576I-303J1D01*
G01X1237077D01*
G02X1236776Y1674878I1J302D01*
G01Y1684884D01*
G37*
G36*
G01X1252524D02*
G02X1252827Y1685186I303J-1D01*
G01X1256529D01*
G02X1256830Y1684884I-1J-302D01*
G01Y1674878D01*
G02X1256527Y1674576I-303J1D01*
G01X1252825D01*
G02X1252524Y1674878I1J302D01*
G01Y1684884D01*
G37*
G36*
G01X1268272D02*
G02X1268575Y1685186I303J-1D01*
G01X1272277D01*
G02X1272578Y1684884I-1J-302D01*
G01Y1674878D01*
G02X1272275Y1674576I-303J1D01*
G01X1268573D01*
G02X1268272Y1674878I1J302D01*
G01Y1684884D01*
G37*
G36*
G01X1284020D02*
G02X1284323Y1685186I303J-1D01*
G01X1288025D01*
G02X1288326Y1684884I-1J-302D01*
G01Y1674878D01*
G02X1288023Y1674576I-303J1D01*
G01X1284321D01*
G02X1284020Y1674878I1J302D01*
G01Y1684884D01*
G37*
G36*
G01X1303706D02*
G02X1304008Y1685186I302J0D01*
G01X1307708D01*
G02X1308010Y1684884I0J-302D01*
G01Y1674878D01*
G02X1307708Y1674576I-302J0D01*
G01X1304008D01*
G02X1303706Y1674878I0J302D01*
G01Y1684884D01*
G37*
G36*
G01X1319454D02*
G02X1319756Y1685186I302J0D01*
G01X1323456D01*
G02X1323758Y1684884I0J-302D01*
G01Y1674878D01*
G02X1323456Y1674576I-302J0D01*
G01X1319756D01*
G02X1319454Y1674878I0J302D01*
G01Y1684884D01*
G37*
G36*
G01X1335202D02*
G02X1335504Y1685186I302J0D01*
G01X1339204D01*
G02X1339506Y1684884I0J-302D01*
G01Y1674878D01*
G02X1339204Y1674576I-302J0D01*
G01X1335504D01*
G02X1335202Y1674878I0J302D01*
G01Y1684884D01*
G37*
G36*
G01X1350950D02*
G02X1351252Y1685186I302J0D01*
G01X1354952D01*
G02X1355254Y1684884I0J-302D01*
G01Y1674878D01*
G02X1354952Y1674576I-302J0D01*
G01X1351252D01*
G02X1350950Y1674878I0J302D01*
G01Y1684884D01*
G37*
G36*
G01X1500950D02*
G02X1501252Y1685186I302J0D01*
G01X1504952D01*
G02X1505254Y1684884I0J-302D01*
G01Y1674878D01*
G02X1504952Y1674576I-302J0D01*
G01X1501252D01*
G02X1500950Y1674878I0J302D01*
G01Y1684884D01*
G37*
G36*
G01X1516698D02*
G02X1517000Y1685186I302J0D01*
G01X1520700D01*
G02X1521002Y1684884I0J-302D01*
G01Y1674878D01*
G02X1520700Y1674576I-302J0D01*
G01X1517000D01*
G02X1516698Y1674878I0J302D01*
G01Y1684884D01*
G37*
G36*
G01X1532446D02*
G02X1532748Y1685186I302J0D01*
G01X1536448D01*
G02X1536750Y1684884I0J-302D01*
G01Y1674878D01*
G02X1536448Y1674576I-302J0D01*
G01X1532748D01*
G02X1532446Y1674878I0J302D01*
G01Y1684884D01*
G37*
G36*
G01X1548194D02*
G02X1548496Y1685186I302J0D01*
G01X1552196D01*
G02X1552498Y1684884I0J-302D01*
G01Y1674878D01*
G02X1552196Y1674576I-302J0D01*
G01X1548496D01*
G02X1548194Y1674878I0J302D01*
G01Y1684884D01*
G37*
G36*
G01X1567878D02*
G02X1568181Y1685186I303J-1D01*
G01X1571883D01*
G02X1572184Y1684884I-1J-302D01*
G01Y1674878D01*
G02X1571881Y1674576I-303J1D01*
G01X1568179D01*
G02X1567878Y1674878I1J302D01*
G01Y1684884D01*
G37*
G36*
G01X1583626D02*
G02X1583929Y1685186I303J-1D01*
G01X1587631D01*
G02X1587932Y1684884I-1J-302D01*
G01Y1674878D01*
G02X1587629Y1674576I-303J1D01*
G01X1583927D01*
G02X1583626Y1674878I1J302D01*
G01Y1684884D01*
G37*
G36*
G01X1599374D02*
G02X1599677Y1685186I303J-1D01*
G01X1603379D01*
G02X1603680Y1684884I-1J-302D01*
G01Y1674878D01*
G02X1603377Y1674576I-303J1D01*
G01X1599675D01*
G02X1599374Y1674878I1J302D01*
G01Y1684884D01*
G37*
G36*
G01X1615122D02*
G02X1615425Y1685186I303J-1D01*
G01X1619127D01*
G02X1619428Y1684884I-1J-302D01*
G01Y1674878D01*
G02X1619125Y1674576I-303J1D01*
G01X1615423D01*
G02X1615122Y1674878I1J302D01*
G01Y1684884D01*
G37*
G36*
G01X107569Y1684260D02*
G02Y1687266I0J1503D01*
G01X110969D01*
G02Y1684260I0J-1503D01*
G01X107569D01*
G37*
G36*
G01X236776Y1688821D02*
G02X237079Y1689124I303J0D01*
G01X240779D01*
G02X241082Y1688821I0J-303D01*
G01Y1678815D01*
G02X240779Y1678512I-303J0D01*
G01X237079D01*
G02X236776Y1678815I0J303D01*
G01Y1688821D01*
G37*
G36*
G01X252524D02*
G02X252827Y1689124I303J0D01*
G01X256527D01*
G02X256830Y1688821I0J-303D01*
G01Y1678815D01*
G02X256527Y1678512I-303J0D01*
G01X252827D01*
G02X252524Y1678815I0J303D01*
G01Y1688821D01*
G37*
G36*
G01X268272D02*
G02X268575Y1689124I303J0D01*
G01X272275D01*
G02X272578Y1688821I0J-303D01*
G01Y1678815D01*
G02X272275Y1678512I-303J0D01*
G01X268575D01*
G02X268272Y1678815I0J303D01*
G01Y1688821D01*
G37*
G36*
G01X284020D02*
G02X284323Y1689124I303J0D01*
G01X288023D01*
G02X288326Y1688821I0J-303D01*
G01Y1678815D01*
G02X288023Y1678512I-303J0D01*
G01X284323D01*
G02X284020Y1678815I0J303D01*
G01Y1688821D01*
G37*
G36*
G01X303706D02*
G02X304008Y1689124I302J1D01*
G01X307708D01*
G02X308010Y1688821I-1J-303D01*
G01Y1678815D01*
G02X307708Y1678512I-302J-1D01*
G01X304008D01*
G02X303706Y1678815I1J303D01*
G01Y1688821D01*
G37*
G36*
G01X319454D02*
G02X319756Y1689124I302J1D01*
G01X323456D01*
G02X323758Y1688821I-1J-303D01*
G01Y1678815D01*
G02X323456Y1678512I-302J-1D01*
G01X319756D01*
G02X319454Y1678815I1J303D01*
G01Y1688821D01*
G37*
G36*
G01X335202D02*
G02X335504Y1689124I302J1D01*
G01X339204D01*
G02X339506Y1688821I-1J-303D01*
G01Y1678815D01*
G02X339204Y1678512I-302J-1D01*
G01X335504D01*
G02X335202Y1678815I1J303D01*
G01Y1688821D01*
G37*
G36*
G01X350950D02*
G02X351252Y1689124I302J1D01*
G01X354952D01*
G02X355254Y1688821I-1J-303D01*
G01Y1678815D01*
G02X354952Y1678512I-302J-1D01*
G01X351252D01*
G02X350950Y1678815I1J303D01*
G01Y1688821D01*
G37*
G36*
G01X500950D02*
G02X501252Y1689124I302J1D01*
G01X504952D01*
G02X505254Y1688821I-1J-303D01*
G01Y1678815D01*
G02X504952Y1678512I-302J-1D01*
G01X501252D01*
G02X500950Y1678815I1J303D01*
G01Y1688821D01*
G37*
G36*
G01X516698D02*
G02X517000Y1689124I302J1D01*
G01X520700D01*
G02X521002Y1688821I-1J-303D01*
G01Y1678815D01*
G02X520700Y1678512I-302J-1D01*
G01X517000D01*
G02X516698Y1678815I1J303D01*
G01Y1688821D01*
G37*
G36*
G01X532446D02*
G02X532748Y1689124I302J1D01*
G01X536448D01*
G02X536750Y1688821I-1J-303D01*
G01Y1678815D01*
G02X536448Y1678512I-302J-1D01*
G01X532748D01*
G02X532446Y1678815I1J303D01*
G01Y1688821D01*
G37*
G36*
G01X548194D02*
G02X548496Y1689124I302J1D01*
G01X552196D01*
G02X552498Y1688821I-1J-303D01*
G01Y1678815D01*
G02X552196Y1678512I-302J-1D01*
G01X548496D01*
G02X548194Y1678815I1J303D01*
G01Y1688821D01*
G37*
G36*
G01X567878D02*
G02X568181Y1689124I303J0D01*
G01X571881D01*
G02X572184Y1688821I0J-303D01*
G01Y1678815D01*
G02X571881Y1678512I-303J0D01*
G01X568181D01*
G02X567878Y1678815I0J303D01*
G01Y1688821D01*
G37*
G36*
G01X583626D02*
G02X583929Y1689124I303J0D01*
G01X587629D01*
G02X587932Y1688821I0J-303D01*
G01Y1678815D01*
G02X587629Y1678512I-303J0D01*
G01X583929D01*
G02X583626Y1678815I0J303D01*
G01Y1688821D01*
G37*
G36*
G01X599374D02*
G02X599677Y1689124I303J0D01*
G01X603377D01*
G02X603680Y1688821I0J-303D01*
G01Y1678815D01*
G02X603377Y1678512I-303J0D01*
G01X599677D01*
G02X599374Y1678815I0J303D01*
G01Y1688821D01*
G37*
G36*
G01X615122D02*
G02X615425Y1689124I303J0D01*
G01X619125D01*
G02X619428Y1688821I0J-303D01*
G01Y1678815D01*
G02X619125Y1678512I-303J0D01*
G01X615425D01*
G02X615122Y1678815I0J303D01*
G01Y1688821D01*
G37*
G36*
G01X1244650D02*
G02X1244953Y1689124I303J0D01*
G01X1248653D01*
G02X1248956Y1688821I0J-303D01*
G01Y1678815D01*
G02X1248653Y1678512I-303J0D01*
G01X1244953D01*
G02X1244650Y1678815I0J303D01*
G01Y1688821D01*
G37*
G36*
G01X1260398D02*
G02X1260701Y1689124I303J0D01*
G01X1264401D01*
G02X1264704Y1688821I0J-303D01*
G01Y1678815D01*
G02X1264401Y1678512I-303J0D01*
G01X1260701D01*
G02X1260398Y1678815I0J303D01*
G01Y1688821D01*
G37*
G36*
G01X1276146D02*
G02X1276449Y1689124I303J0D01*
G01X1280149D01*
G02X1280452Y1688821I0J-303D01*
G01Y1678815D01*
G02X1280149Y1678512I-303J0D01*
G01X1276449D01*
G02X1276146Y1678815I0J303D01*
G01Y1688821D01*
G37*
G36*
G01X1291894D02*
G02X1292197Y1689124I303J0D01*
G01X1295897D01*
G02X1296200Y1688821I0J-303D01*
G01Y1678815D01*
G02X1295897Y1678512I-303J0D01*
G01X1292197D01*
G02X1291894Y1678815I0J303D01*
G01Y1688821D01*
G37*
G36*
G01X1311580D02*
G02X1311882Y1689124I302J1D01*
G01X1315582D01*
G02X1315884Y1688821I-1J-303D01*
G01Y1678815D01*
G02X1315582Y1678512I-302J-1D01*
G01X1311882D01*
G02X1311580Y1678815I1J303D01*
G01Y1688821D01*
G37*
G36*
G01X1327328D02*
G02X1327630Y1689124I302J1D01*
G01X1331330D01*
G02X1331632Y1688821I-1J-303D01*
G01Y1678815D01*
G02X1331330Y1678512I-302J-1D01*
G01X1327630D01*
G02X1327328Y1678815I1J303D01*
G01Y1688821D01*
G37*
G36*
G01X1343076D02*
G02X1343378Y1689124I302J1D01*
G01X1347078D01*
G02X1347380Y1688821I-1J-303D01*
G01Y1678815D01*
G02X1347078Y1678512I-302J-1D01*
G01X1343378D01*
G02X1343076Y1678815I1J303D01*
G01Y1688821D01*
G37*
G36*
G01X1358824D02*
G02X1359126Y1689124I302J1D01*
G01X1362826D01*
G02X1363128Y1688821I-1J-303D01*
G01Y1678815D01*
G02X1362826Y1678512I-302J-1D01*
G01X1359126D01*
G02X1358824Y1678815I1J303D01*
G01Y1688821D01*
G37*
G36*
G01X1508824D02*
G02X1509126Y1689124I302J1D01*
G01X1512826D01*
G02X1513128Y1688821I-1J-303D01*
G01Y1678815D01*
G02X1512826Y1678512I-302J-1D01*
G01X1509126D01*
G02X1508824Y1678815I1J303D01*
G01Y1688821D01*
G37*
G36*
G01X1524572D02*
G02X1524874Y1689124I302J1D01*
G01X1528574D01*
G02X1528876Y1688821I-1J-303D01*
G01Y1678815D01*
G02X1528574Y1678512I-302J-1D01*
G01X1524874D01*
G02X1524572Y1678815I1J303D01*
G01Y1688821D01*
G37*
G36*
G01X1540320D02*
G02X1540622Y1689124I302J1D01*
G01X1544322D01*
G02X1544624Y1688821I-1J-303D01*
G01Y1678815D01*
G02X1544322Y1678512I-302J-1D01*
G01X1540622D01*
G02X1540320Y1678815I1J303D01*
G01Y1688821D01*
G37*
G36*
G01X1556068D02*
G02X1556370Y1689124I302J1D01*
G01X1560070D01*
G02X1560372Y1688821I-1J-303D01*
G01Y1678815D01*
G02X1560070Y1678512I-302J-1D01*
G01X1556370D01*
G02X1556068Y1678815I1J303D01*
G01Y1688821D01*
G37*
G36*
G01X1575752D02*
G02X1576055Y1689124I303J0D01*
G01X1579755D01*
G02X1580058Y1688821I0J-303D01*
G01Y1678815D01*
G02X1579755Y1678512I-303J0D01*
G01X1576055D01*
G02X1575752Y1678815I0J303D01*
G01Y1688821D01*
G37*
G36*
G01X1591500D02*
G02X1591803Y1689124I303J0D01*
G01X1595503D01*
G02X1595806Y1688821I0J-303D01*
G01Y1678815D01*
G02X1595503Y1678512I-303J0D01*
G01X1591803D01*
G02X1591500Y1678815I0J303D01*
G01Y1688821D01*
G37*
G36*
G01X1607248D02*
G02X1607551Y1689124I303J0D01*
G01X1611251D01*
G02X1611554Y1688821I0J-303D01*
G01Y1678815D01*
G02X1611251Y1678512I-303J0D01*
G01X1607551D01*
G02X1607248Y1678815I0J303D01*
G01Y1688821D01*
G37*
G36*
G01X1622996D02*
G02X1623299Y1689124I303J0D01*
G01X1626999D01*
G02X1627302Y1688821I0J-303D01*
G01Y1678815D01*
G02X1626999Y1678512I-303J0D01*
G01X1623299D01*
G02X1622996Y1678815I0J303D01*
G01Y1688821D01*
G37*
G36*
G01X228902Y1699057D02*
G02X229205Y1699360I303J0D01*
G01X232905D01*
G02X233208Y1699057I0J-303D01*
G01Y1689051D01*
G02X232905Y1688748I-303J0D01*
G01X229205D01*
G02X228902Y1689051I0J303D01*
G01Y1691915D01*
G02X228934Y1692048I302J-2D01*
G01Y1692050D01*
X229853Y1693924D01*
G03Y1694186I-267J131D01*
G01X228934Y1696060D01*
Y1696062D01*
G02X228902Y1696195I270J135D01*
G01Y1699057D01*
G37*
G36*
G01X244650D02*
G02X244953Y1699360I303J0D01*
G01X248653D01*
G02X248956Y1699057I0J-303D01*
G01Y1689051D01*
G02X248653Y1688748I-303J0D01*
G01X244953D01*
G02X244650Y1689051I0J303D01*
G01Y1691915D01*
G02X244682Y1692048I302J-2D01*
G01Y1692050D01*
X245601Y1693924D01*
G03Y1694186I-267J131D01*
G01X244682Y1696060D01*
Y1696062D01*
G02X244650Y1696195I270J135D01*
G01Y1699057D01*
G37*
G36*
G01X260398D02*
G02X260701Y1699360I303J0D01*
G01X264401D01*
G02X264704Y1699057I0J-303D01*
G01Y1689051D01*
G02X264401Y1688748I-303J0D01*
G01X260701D01*
G02X260398Y1689051I0J303D01*
G01Y1691915D01*
G02X260430Y1692048I302J-2D01*
G01Y1692050D01*
X261349Y1693924D01*
G03Y1694186I-267J131D01*
G01X260430Y1696060D01*
Y1696062D01*
G02X260398Y1696195I270J135D01*
G01Y1699057D01*
G37*
G36*
G01X276146D02*
G02X276449Y1699360I303J0D01*
G01X280149D01*
G02X280452Y1699057I0J-303D01*
G01Y1689051D01*
G02X280149Y1688748I-303J0D01*
G01X276449D01*
G02X276146Y1689051I0J303D01*
G01Y1691915D01*
G02X276178Y1692048I302J-2D01*
G01Y1692050D01*
X277097Y1693924D01*
G03Y1694186I-267J131D01*
G01X276178Y1696060D01*
Y1696062D01*
G02X276146Y1696195I270J135D01*
G01Y1699057D01*
G37*
G36*
G01X295832D02*
G02X296134Y1699360I302J1D01*
G01X299834D01*
G02X300136Y1699057I-1J-303D01*
G01Y1689051D01*
G02X299834Y1688748I-302J-1D01*
G01X296134D01*
G02X295832Y1689051I1J303D01*
G01Y1691916D01*
G02X295863Y1692049I302J0D01*
G01X296782Y1693924D01*
G03Y1694186I-267J131D01*
G01X295863Y1696061D01*
G02X295832Y1696194I271J133D01*
G01Y1699057D01*
G37*
G36*
G01X311580D02*
G02X311882Y1699360I302J1D01*
G01X315582D01*
G02X315884Y1699057I-1J-303D01*
G01Y1689051D01*
G02X315582Y1688748I-302J-1D01*
G01X311882D01*
G02X311580Y1689051I1J303D01*
G01Y1691916D01*
G02X311611Y1692049I302J0D01*
G01X312530Y1693924D01*
G03Y1694186I-267J131D01*
G01X311611Y1696061D01*
G02X311580Y1696194I271J133D01*
G01Y1699057D01*
G37*
G36*
G01X327328D02*
G02X327630Y1699360I302J1D01*
G01X331330D01*
G02X331632Y1699057I-1J-303D01*
G01Y1689051D01*
G02X331330Y1688748I-302J-1D01*
G01X327630D01*
G02X327328Y1689051I1J303D01*
G01Y1691916D01*
G02X327359Y1692049I302J0D01*
G01X328278Y1693924D01*
G03Y1694186I-267J131D01*
G01X327359Y1696061D01*
G02X327328Y1696194I271J133D01*
G01Y1699057D01*
G37*
G36*
G01X343076D02*
G02X343378Y1699360I302J1D01*
G01X347078D01*
G02X347380Y1699057I-1J-303D01*
G01Y1689051D01*
G02X347078Y1688748I-302J-1D01*
G01X343378D01*
G02X343076Y1689051I1J303D01*
G01Y1691916D01*
G02X343107Y1692049I302J0D01*
G01X344026Y1693924D01*
G03Y1694186I-267J131D01*
G01X343107Y1696061D01*
G02X343076Y1696194I271J133D01*
G01Y1699057D01*
G37*
G36*
G01X493076D02*
G02X493378Y1699360I302J1D01*
G01X497078D01*
G02X497380Y1699057I-1J-303D01*
G01Y1689051D01*
G02X497078Y1688748I-302J-1D01*
G01X493378D01*
G02X493076Y1689051I1J303D01*
G01Y1691916D01*
G02X493107Y1692049I302J0D01*
G01X494026Y1693924D01*
G03Y1694186I-267J131D01*
G01X493107Y1696061D01*
G02X493076Y1696194I271J133D01*
G01Y1699057D01*
G37*
G36*
G01X508824D02*
G02X509126Y1699360I302J1D01*
G01X512826D01*
G02X513128Y1699057I-1J-303D01*
G01Y1689051D01*
G02X512826Y1688748I-302J-1D01*
G01X509126D01*
G02X508824Y1689051I1J303D01*
G01Y1691916D01*
G02X508855Y1692049I302J0D01*
G01X509774Y1693924D01*
G03Y1694186I-267J131D01*
G01X508855Y1696061D01*
G02X508824Y1696194I271J133D01*
G01Y1699057D01*
G37*
G36*
G01X524572D02*
G02X524874Y1699360I302J1D01*
G01X528574D01*
G02X528876Y1699057I-1J-303D01*
G01Y1689051D01*
G02X528574Y1688748I-302J-1D01*
G01X524874D01*
G02X524572Y1689051I1J303D01*
G01Y1691916D01*
G02X524603Y1692049I302J0D01*
G01X525522Y1693924D01*
G03Y1694186I-267J131D01*
G01X524603Y1696061D01*
G02X524572Y1696194I271J133D01*
G01Y1699057D01*
G37*
G36*
G01X540320D02*
G02X540622Y1699360I302J1D01*
G01X544322D01*
G02X544624Y1699057I-1J-303D01*
G01Y1689051D01*
G02X544322Y1688748I-302J-1D01*
G01X540622D01*
G02X540320Y1689051I1J303D01*
G01Y1691916D01*
G02X540351Y1692049I302J0D01*
G01X541270Y1693924D01*
G03Y1694186I-267J131D01*
G01X540351Y1696061D01*
G02X540320Y1696194I271J133D01*
G01Y1699057D01*
G37*
G36*
G01X560006D02*
G02X560308Y1699360I302J1D01*
G01X564008D01*
G02X564310Y1699057I-1J-303D01*
G01Y1689051D01*
G02X564008Y1688748I-302J-1D01*
G01X560308D01*
G02X560006Y1689051I1J303D01*
G01Y1691916D01*
G02X560037Y1692049I302J0D01*
G01X560956Y1693924D01*
G03Y1694186I-267J131D01*
G01X560037Y1696061D01*
G02X560006Y1696194I271J133D01*
G01Y1699057D01*
G37*
G36*
G01X575754D02*
G02X576056Y1699360I302J1D01*
G01X579756D01*
G02X580058Y1699057I-1J-303D01*
G01Y1689051D01*
G02X579756Y1688748I-302J-1D01*
G01X576056D01*
G02X575754Y1689051I1J303D01*
G01Y1691916D01*
G02X575785Y1692049I302J0D01*
G01X576704Y1693924D01*
G03Y1694186I-267J131D01*
G01X575785Y1696061D01*
G02X575754Y1696194I271J133D01*
G01Y1699057D01*
G37*
G36*
G01X591502D02*
G02X591804Y1699360I302J1D01*
G01X595504D01*
G02X595806Y1699057I-1J-303D01*
G01Y1689051D01*
G02X595504Y1688748I-302J-1D01*
G01X591804D01*
G02X591502Y1689051I1J303D01*
G01Y1691916D01*
G02X591533Y1692049I302J0D01*
G01X592452Y1693924D01*
G03Y1694186I-267J131D01*
G01X591533Y1696061D01*
G02X591502Y1696194I271J133D01*
G01Y1699057D01*
G37*
G36*
G01X607250D02*
G02X607552Y1699360I302J1D01*
G01X611252D01*
G02X611554Y1699057I-1J-303D01*
G01Y1689051D01*
G02X611252Y1688748I-302J-1D01*
G01X607552D01*
G02X607250Y1689051I1J303D01*
G01Y1691916D01*
G02X607281Y1692049I302J0D01*
G01X608200Y1693924D01*
G03Y1694186I-267J131D01*
G01X607281Y1696061D01*
G02X607250Y1696194I271J133D01*
G01Y1699057D01*
G37*
G36*
G01X1236776D02*
G02X1237078Y1699360I302J1D01*
G01X1240778D01*
G02X1241080Y1699057I-1J-303D01*
G01Y1689051D01*
G02X1240778Y1688748I-302J-1D01*
G01X1237078D01*
G02X1236776Y1689051I1J303D01*
G01Y1691916D01*
G02X1236807Y1692049I302J0D01*
G01X1237726Y1693924D01*
G03Y1694186I-267J131D01*
G01X1236807Y1696061D01*
G02X1236776Y1696194I271J133D01*
G01Y1699057D01*
G37*
G36*
G01X1252524D02*
G02X1252826Y1699360I302J1D01*
G01X1256526D01*
G02X1256828Y1699057I-1J-303D01*
G01Y1689051D01*
G02X1256526Y1688748I-302J-1D01*
G01X1252826D01*
G02X1252524Y1689051I1J303D01*
G01Y1691916D01*
G02X1252555Y1692049I302J0D01*
G01X1253474Y1693924D01*
G03Y1694186I-267J131D01*
G01X1252555Y1696061D01*
G02X1252524Y1696194I271J133D01*
G01Y1699057D01*
G37*
G36*
G01X1268272D02*
G02X1268574Y1699360I302J1D01*
G01X1272274D01*
G02X1272576Y1699057I-1J-303D01*
G01Y1689051D01*
G02X1272274Y1688748I-302J-1D01*
G01X1268574D01*
G02X1268272Y1689051I1J303D01*
G01Y1691916D01*
G02X1268303Y1692049I302J0D01*
G01X1269222Y1693924D01*
G03Y1694186I-267J131D01*
G01X1268303Y1696061D01*
G02X1268272Y1696194I271J133D01*
G01Y1699057D01*
G37*
G36*
G01X1284020D02*
G02X1284322Y1699360I302J1D01*
G01X1288022D01*
G02X1288324Y1699057I-1J-303D01*
G01Y1689051D01*
G02X1288022Y1688748I-302J-1D01*
G01X1284322D01*
G02X1284020Y1689051I1J303D01*
G01Y1691916D01*
G02X1284051Y1692049I302J0D01*
G01X1284970Y1693924D01*
G03Y1694186I-267J131D01*
G01X1284051Y1696061D01*
G02X1284020Y1696194I271J133D01*
G01Y1699057D01*
G37*
G36*
G01X1303706D02*
G02X1304008Y1699360I302J1D01*
G01X1307708D01*
G02X1308010Y1699057I-1J-303D01*
G01Y1689051D01*
G02X1307708Y1688748I-302J-1D01*
G01X1304008D01*
G02X1303706Y1689051I1J303D01*
G01Y1691916D01*
G02X1303737Y1692049I302J0D01*
G01X1304656Y1693924D01*
G03Y1694186I-267J131D01*
G01X1303737Y1696061D01*
G02X1303706Y1696194I271J133D01*
G01Y1699057D01*
G37*
G36*
G01X1319454D02*
G02X1319756Y1699360I302J1D01*
G01X1323456D01*
G02X1323758Y1699057I-1J-303D01*
G01Y1689051D01*
G02X1323456Y1688748I-302J-1D01*
G01X1319756D01*
G02X1319454Y1689051I1J303D01*
G01Y1691916D01*
G02X1319485Y1692049I302J0D01*
G01X1320404Y1693924D01*
G03Y1694186I-267J131D01*
G01X1319485Y1696061D01*
G02X1319454Y1696194I271J133D01*
G01Y1699057D01*
G37*
G36*
G01X1335202D02*
G02X1335504Y1699360I302J1D01*
G01X1339204D01*
G02X1339506Y1699057I-1J-303D01*
G01Y1689051D01*
G02X1339204Y1688748I-302J-1D01*
G01X1335504D01*
G02X1335202Y1689051I1J303D01*
G01Y1691916D01*
G02X1335233Y1692049I302J0D01*
G01X1336152Y1693924D01*
G03Y1694186I-267J131D01*
G01X1335233Y1696061D01*
G02X1335202Y1696194I271J133D01*
G01Y1699057D01*
G37*
G36*
G01X1350950D02*
G02X1351252Y1699360I302J1D01*
G01X1354952D01*
G02X1355254Y1699057I-1J-303D01*
G01Y1689051D01*
G02X1354952Y1688748I-302J-1D01*
G01X1351252D01*
G02X1350950Y1689051I1J303D01*
G01Y1691916D01*
G02X1350981Y1692049I302J0D01*
G01X1351900Y1693924D01*
G03Y1694186I-267J131D01*
G01X1350981Y1696061D01*
G02X1350950Y1696194I271J133D01*
G01Y1699057D01*
G37*
G36*
G01X1500950D02*
G02X1501252Y1699360I302J1D01*
G01X1504952D01*
G02X1505254Y1699057I-1J-303D01*
G01Y1689051D01*
G02X1504952Y1688748I-302J-1D01*
G01X1501252D01*
G02X1500950Y1689051I1J303D01*
G01Y1691916D01*
G02X1500981Y1692049I302J0D01*
G01X1501900Y1693924D01*
G03Y1694186I-267J131D01*
G01X1500981Y1696061D01*
G02X1500950Y1696194I271J133D01*
G01Y1699057D01*
G37*
G36*
G01X1516698D02*
G02X1517000Y1699360I302J1D01*
G01X1520700D01*
G02X1521002Y1699057I-1J-303D01*
G01Y1689051D01*
G02X1520700Y1688748I-302J-1D01*
G01X1517000D01*
G02X1516698Y1689051I1J303D01*
G01Y1691916D01*
G02X1516729Y1692049I302J0D01*
G01X1517648Y1693924D01*
G03Y1694186I-267J131D01*
G01X1516729Y1696061D01*
G02X1516698Y1696194I271J133D01*
G01Y1699057D01*
G37*
G36*
G01X1532446D02*
G02X1532748Y1699360I302J1D01*
G01X1536448D01*
G02X1536750Y1699057I-1J-303D01*
G01Y1689051D01*
G02X1536448Y1688748I-302J-1D01*
G01X1532748D01*
G02X1532446Y1689051I1J303D01*
G01Y1691916D01*
G02X1532477Y1692049I302J0D01*
G01X1533396Y1693924D01*
G03Y1694186I-267J131D01*
G01X1532477Y1696061D01*
G02X1532446Y1696194I271J133D01*
G01Y1699057D01*
G37*
G36*
G01X1548194D02*
G02X1548496Y1699360I302J1D01*
G01X1552196D01*
G02X1552498Y1699057I-1J-303D01*
G01Y1689051D01*
G02X1552196Y1688748I-302J-1D01*
G01X1548496D01*
G02X1548194Y1689051I1J303D01*
G01Y1691916D01*
G02X1548225Y1692049I302J0D01*
G01X1549144Y1693924D01*
G03Y1694186I-267J131D01*
G01X1548225Y1696061D01*
G02X1548194Y1696194I271J133D01*
G01Y1699057D01*
G37*
G36*
G01X1567880D02*
G02X1568182Y1699360I302J1D01*
G01X1571882D01*
G02X1572184Y1699057I-1J-303D01*
G01Y1689051D01*
G02X1571882Y1688748I-302J-1D01*
G01X1568182D01*
G02X1567880Y1689051I1J303D01*
G01Y1691916D01*
G02X1567911Y1692049I302J0D01*
G01X1568830Y1693924D01*
G03Y1694186I-267J131D01*
G01X1567911Y1696061D01*
G02X1567880Y1696194I271J133D01*
G01Y1699057D01*
G37*
G36*
G01X1583628D02*
G02X1583930Y1699360I302J1D01*
G01X1587630D01*
G02X1587932Y1699057I-1J-303D01*
G01Y1689051D01*
G02X1587630Y1688748I-302J-1D01*
G01X1583930D01*
G02X1583628Y1689051I1J303D01*
G01Y1691916D01*
G02X1583659Y1692049I302J0D01*
G01X1584578Y1693924D01*
G03Y1694186I-267J131D01*
G01X1583659Y1696061D01*
G02X1583628Y1696194I271J133D01*
G01Y1699057D01*
G37*
G36*
G01X1599376D02*
G02X1599678Y1699360I302J1D01*
G01X1603378D01*
G02X1603680Y1699057I-1J-303D01*
G01Y1689051D01*
G02X1603378Y1688748I-302J-1D01*
G01X1599678D01*
G02X1599376Y1689051I1J303D01*
G01Y1691916D01*
G02X1599407Y1692049I302J0D01*
G01X1600326Y1693924D01*
G03Y1694186I-267J131D01*
G01X1599407Y1696061D01*
G02X1599376Y1696194I271J133D01*
G01Y1699057D01*
G37*
G36*
G01X1615124D02*
G02X1615426Y1699360I302J1D01*
G01X1619126D01*
G02X1619428Y1699057I-1J-303D01*
G01Y1689051D01*
G02X1619126Y1688748I-302J-1D01*
G01X1615426D01*
G02X1615124Y1689051I1J303D01*
G01Y1691916D01*
G02X1615155Y1692049I302J0D01*
G01X1616074Y1693924D01*
G03Y1694186I-267J131D01*
G01X1615155Y1696061D01*
G02X1615124Y1696194I271J133D01*
G01Y1699057D01*
G37*
G36*
G01X236776Y1702994D02*
G02X237079Y1703296I303J-1D01*
G01X240781D01*
G02X241082Y1702994I-1J-302D01*
G01Y1692988D01*
G02X240779Y1692686I-303J1D01*
G01X237077D01*
G02X236776Y1692988I1J302D01*
G01Y1695852D01*
G02X236808Y1695985I302J-2D01*
G01Y1695987D01*
X237727Y1697861D01*
G03Y1698123I-267J131D01*
G01X236808Y1699997D01*
Y1699999D01*
G02X236776Y1700132I270J135D01*
G01Y1702994D01*
G37*
G36*
G01X252524D02*
G02X252827Y1703296I303J-1D01*
G01X256529D01*
G02X256830Y1702994I-1J-302D01*
G01Y1692988D01*
G02X256527Y1692686I-303J1D01*
G01X252825D01*
G02X252524Y1692988I1J302D01*
G01Y1695852D01*
G02X252556Y1695985I302J-2D01*
G01Y1695987D01*
X253475Y1697861D01*
G03Y1698123I-267J131D01*
G01X252556Y1699997D01*
Y1699999D01*
G02X252524Y1700132I270J135D01*
G01Y1702994D01*
G37*
G36*
G01X268272D02*
G02X268575Y1703296I303J-1D01*
G01X272277D01*
G02X272578Y1702994I-1J-302D01*
G01Y1692988D01*
G02X272275Y1692686I-303J1D01*
G01X268573D01*
G02X268272Y1692988I1J302D01*
G01Y1695852D01*
G02X268304Y1695985I302J-2D01*
G01Y1695987D01*
X269223Y1697861D01*
G03Y1698123I-267J131D01*
G01X268304Y1699997D01*
Y1699999D01*
G02X268272Y1700132I270J135D01*
G01Y1702994D01*
G37*
G36*
G01X284020D02*
G02X284323Y1703296I303J-1D01*
G01X288025D01*
G02X288326Y1702994I-1J-302D01*
G01Y1692988D01*
G02X288023Y1692686I-303J1D01*
G01X284321D01*
G02X284020Y1692988I1J302D01*
G01Y1695852D01*
G02X284052Y1695985I302J-2D01*
G01Y1695987D01*
X284971Y1697861D01*
G03Y1698123I-267J131D01*
G01X284052Y1699997D01*
Y1699999D01*
G02X284020Y1700132I270J135D01*
G01Y1702994D01*
G37*
G36*
G01X303706D02*
G02X304008Y1703296I302J0D01*
G01X307708D01*
G02X308010Y1702994I0J-302D01*
G01Y1692988D01*
G02X307708Y1692686I-302J0D01*
G01X304008D01*
G02X303706Y1692988I0J302D01*
G01Y1695853D01*
G02X303737Y1695986I302J0D01*
G01X304656Y1697861D01*
G03Y1698123I-267J131D01*
G01X303737Y1699998D01*
G02X303706Y1700131I271J133D01*
G01Y1702994D01*
G37*
G36*
G01X319454D02*
G02X319756Y1703296I302J0D01*
G01X323456D01*
G02X323758Y1702994I0J-302D01*
G01Y1692988D01*
G02X323456Y1692686I-302J0D01*
G01X319756D01*
G02X319454Y1692988I0J302D01*
G01Y1695853D01*
G02X319485Y1695986I302J0D01*
G01X320404Y1697861D01*
G03Y1698123I-267J131D01*
G01X319485Y1699998D01*
G02X319454Y1700131I271J133D01*
G01Y1702994D01*
G37*
G36*
G01X335202D02*
G02X335504Y1703296I302J0D01*
G01X339204D01*
G02X339506Y1702994I0J-302D01*
G01Y1692988D01*
G02X339204Y1692686I-302J0D01*
G01X335504D01*
G02X335202Y1692988I0J302D01*
G01Y1695853D01*
G02X335233Y1695986I302J0D01*
G01X336152Y1697861D01*
G03Y1698123I-267J131D01*
G01X335233Y1699998D01*
G02X335202Y1700131I271J133D01*
G01Y1702994D01*
G37*
G36*
G01X350950D02*
G02X351252Y1703296I302J0D01*
G01X354952D01*
G02X355254Y1702994I0J-302D01*
G01Y1692988D01*
G02X354952Y1692686I-302J0D01*
G01X351252D01*
G02X350950Y1692988I0J302D01*
G01Y1695853D01*
G02X350981Y1695986I302J0D01*
G01X351900Y1697861D01*
G03Y1698123I-267J131D01*
G01X350981Y1699998D01*
G02X350950Y1700131I271J133D01*
G01Y1702994D01*
G37*
G36*
G01X500950D02*
G02X501252Y1703296I302J0D01*
G01X504952D01*
G02X505254Y1702994I0J-302D01*
G01Y1692988D01*
G02X504952Y1692686I-302J0D01*
G01X501252D01*
G02X500950Y1692988I0J302D01*
G01Y1695853D01*
G02X500981Y1695986I302J0D01*
G01X501900Y1697861D01*
G03Y1698123I-267J131D01*
G01X500981Y1699998D01*
G02X500950Y1700131I271J133D01*
G01Y1702994D01*
G37*
G36*
G01X516698D02*
G02X517000Y1703296I302J0D01*
G01X520700D01*
G02X521002Y1702994I0J-302D01*
G01Y1692988D01*
G02X520700Y1692686I-302J0D01*
G01X517000D01*
G02X516698Y1692988I0J302D01*
G01Y1695853D01*
G02X516729Y1695986I302J0D01*
G01X517648Y1697861D01*
G03Y1698123I-267J131D01*
G01X516729Y1699998D01*
G02X516698Y1700131I271J133D01*
G01Y1702994D01*
G37*
G36*
G01X532446D02*
G02X532748Y1703296I302J0D01*
G01X536448D01*
G02X536750Y1702994I0J-302D01*
G01Y1692988D01*
G02X536448Y1692686I-302J0D01*
G01X532748D01*
G02X532446Y1692988I0J302D01*
G01Y1695853D01*
G02X532477Y1695986I302J0D01*
G01X533396Y1697861D01*
G03Y1698123I-267J131D01*
G01X532477Y1699998D01*
G02X532446Y1700131I271J133D01*
G01Y1702994D01*
G37*
G36*
G01X548194D02*
G02X548496Y1703296I302J0D01*
G01X552196D01*
G02X552498Y1702994I0J-302D01*
G01Y1692988D01*
G02X552196Y1692686I-302J0D01*
G01X548496D01*
G02X548194Y1692988I0J302D01*
G01Y1695853D01*
G02X548225Y1695986I302J0D01*
G01X549144Y1697861D01*
G03Y1698123I-267J131D01*
G01X548225Y1699998D01*
G02X548194Y1700131I271J133D01*
G01Y1702994D01*
G37*
G36*
G01X567880D02*
G02X568182Y1703296I302J0D01*
G01X571882D01*
G02X572184Y1702994I0J-302D01*
G01Y1692988D01*
G02X571882Y1692686I-302J0D01*
G01X568182D01*
G02X567880Y1692988I0J302D01*
G01Y1695853D01*
G02X567911Y1695986I302J0D01*
G01X568830Y1697861D01*
G03Y1698123I-267J131D01*
G01X567911Y1699998D01*
G02X567880Y1700131I271J133D01*
G01Y1702994D01*
G37*
G36*
G01X583628D02*
G02X583930Y1703296I302J0D01*
G01X587630D01*
G02X587932Y1702994I0J-302D01*
G01Y1692988D01*
G02X587630Y1692686I-302J0D01*
G01X583930D01*
G02X583628Y1692988I0J302D01*
G01Y1695853D01*
G02X583659Y1695986I302J0D01*
G01X584578Y1697861D01*
G03Y1698123I-267J131D01*
G01X583659Y1699998D01*
G02X583628Y1700131I271J133D01*
G01Y1702994D01*
G37*
G36*
G01X599376D02*
G02X599678Y1703296I302J0D01*
G01X603378D01*
G02X603680Y1702994I0J-302D01*
G01Y1692988D01*
G02X603378Y1692686I-302J0D01*
G01X599678D01*
G02X599376Y1692988I0J302D01*
G01Y1695853D01*
G02X599407Y1695986I302J0D01*
G01X600326Y1697861D01*
G03Y1698123I-267J131D01*
G01X599407Y1699998D01*
G02X599376Y1700131I271J133D01*
G01Y1702994D01*
G37*
G36*
G01X615124D02*
G02X615426Y1703296I302J0D01*
G01X619126D01*
G02X619428Y1702994I0J-302D01*
G01Y1692988D01*
G02X619126Y1692686I-302J0D01*
G01X615426D01*
G02X615124Y1692988I0J302D01*
G01Y1695853D01*
G02X615155Y1695986I302J0D01*
G01X616074Y1697861D01*
G03Y1698123I-267J131D01*
G01X615155Y1699998D01*
G02X615124Y1700131I271J133D01*
G01Y1702994D01*
G37*
G36*
G01X1244650D02*
G02X1244952Y1703296I302J0D01*
G01X1248652D01*
G02X1248954Y1702994I0J-302D01*
G01Y1692988D01*
G02X1248652Y1692686I-302J0D01*
G01X1244952D01*
G02X1244650Y1692988I0J302D01*
G01Y1695853D01*
G02X1244681Y1695986I302J0D01*
G01X1245600Y1697861D01*
G03Y1698123I-267J131D01*
G01X1244681Y1699998D01*
G02X1244650Y1700131I271J133D01*
G01Y1702994D01*
G37*
G36*
G01X1260398D02*
G02X1260700Y1703296I302J0D01*
G01X1264400D01*
G02X1264702Y1702994I0J-302D01*
G01Y1692988D01*
G02X1264400Y1692686I-302J0D01*
G01X1260700D01*
G02X1260398Y1692988I0J302D01*
G01Y1695853D01*
G02X1260429Y1695986I302J0D01*
G01X1261348Y1697861D01*
G03Y1698123I-267J131D01*
G01X1260429Y1699998D01*
G02X1260398Y1700131I271J133D01*
G01Y1702994D01*
G37*
G36*
G01X1276146D02*
G02X1276448Y1703296I302J0D01*
G01X1280148D01*
G02X1280450Y1702994I0J-302D01*
G01Y1692988D01*
G02X1280148Y1692686I-302J0D01*
G01X1276448D01*
G02X1276146Y1692988I0J302D01*
G01Y1695853D01*
G02X1276177Y1695986I302J0D01*
G01X1277096Y1697861D01*
G03Y1698123I-267J131D01*
G01X1276177Y1699998D01*
G02X1276146Y1700131I271J133D01*
G01Y1702994D01*
G37*
G36*
G01X1291894D02*
G02X1292196Y1703296I302J0D01*
G01X1295896D01*
G02X1296198Y1702994I0J-302D01*
G01Y1692988D01*
G02X1295896Y1692686I-302J0D01*
G01X1292196D01*
G02X1291894Y1692988I0J302D01*
G01Y1695853D01*
G02X1291925Y1695986I302J0D01*
G01X1292844Y1697861D01*
G03Y1698123I-267J131D01*
G01X1291925Y1699998D01*
G02X1291894Y1700131I271J133D01*
G01Y1702994D01*
G37*
G36*
G01X1311580D02*
G02X1311882Y1703296I302J0D01*
G01X1315582D01*
G02X1315884Y1702994I0J-302D01*
G01Y1692988D01*
G02X1315582Y1692686I-302J0D01*
G01X1311882D01*
G02X1311580Y1692988I0J302D01*
G01Y1695853D01*
G02X1311611Y1695986I302J0D01*
G01X1312530Y1697861D01*
G03Y1698123I-267J131D01*
G01X1311611Y1699998D01*
G02X1311580Y1700131I271J133D01*
G01Y1702994D01*
G37*
G36*
G01X1327328D02*
G02X1327630Y1703296I302J0D01*
G01X1331330D01*
G02X1331632Y1702994I0J-302D01*
G01Y1692988D01*
G02X1331330Y1692686I-302J0D01*
G01X1327630D01*
G02X1327328Y1692988I0J302D01*
G01Y1695853D01*
G02X1327359Y1695986I302J0D01*
G01X1328278Y1697861D01*
G03Y1698123I-267J131D01*
G01X1327359Y1699998D01*
G02X1327328Y1700131I271J133D01*
G01Y1702994D01*
G37*
G36*
G01X1343076D02*
G02X1343378Y1703296I302J0D01*
G01X1347078D01*
G02X1347380Y1702994I0J-302D01*
G01Y1692988D01*
G02X1347078Y1692686I-302J0D01*
G01X1343378D01*
G02X1343076Y1692988I0J302D01*
G01Y1695853D01*
G02X1343107Y1695986I302J0D01*
G01X1344026Y1697861D01*
G03Y1698123I-267J131D01*
G01X1343107Y1699998D01*
G02X1343076Y1700131I271J133D01*
G01Y1702994D01*
G37*
G36*
G01X1358824D02*
G02X1359126Y1703296I302J0D01*
G01X1362826D01*
G02X1363128Y1702994I0J-302D01*
G01Y1692988D01*
G02X1362826Y1692686I-302J0D01*
G01X1359126D01*
G02X1358824Y1692988I0J302D01*
G01Y1695853D01*
G02X1358855Y1695986I302J0D01*
G01X1359774Y1697861D01*
G03Y1698123I-267J131D01*
G01X1358855Y1699998D01*
G02X1358824Y1700131I271J133D01*
G01Y1702994D01*
G37*
G36*
G01X1508824D02*
G02X1509126Y1703296I302J0D01*
G01X1512826D01*
G02X1513128Y1702994I0J-302D01*
G01Y1692988D01*
G02X1512826Y1692686I-302J0D01*
G01X1509126D01*
G02X1508824Y1692988I0J302D01*
G01Y1695853D01*
G02X1508855Y1695986I302J0D01*
G01X1509774Y1697861D01*
G03Y1698123I-267J131D01*
G01X1508855Y1699998D01*
G02X1508824Y1700131I271J133D01*
G01Y1702994D01*
G37*
G36*
G01X1524572D02*
G02X1524874Y1703296I302J0D01*
G01X1528574D01*
G02X1528876Y1702994I0J-302D01*
G01Y1692988D01*
G02X1528574Y1692686I-302J0D01*
G01X1524874D01*
G02X1524572Y1692988I0J302D01*
G01Y1695853D01*
G02X1524603Y1695986I302J0D01*
G01X1525522Y1697861D01*
G03Y1698123I-267J131D01*
G01X1524603Y1699998D01*
G02X1524572Y1700131I271J133D01*
G01Y1702994D01*
G37*
G36*
G01X1540320D02*
G02X1540622Y1703296I302J0D01*
G01X1544322D01*
G02X1544624Y1702994I0J-302D01*
G01Y1692988D01*
G02X1544322Y1692686I-302J0D01*
G01X1540622D01*
G02X1540320Y1692988I0J302D01*
G01Y1695853D01*
G02X1540351Y1695986I302J0D01*
G01X1541270Y1697861D01*
G03Y1698123I-267J131D01*
G01X1540351Y1699998D01*
G02X1540320Y1700131I271J133D01*
G01Y1702994D01*
G37*
G36*
G01X1556068D02*
G02X1556370Y1703296I302J0D01*
G01X1560070D01*
G02X1560372Y1702994I0J-302D01*
G01Y1692988D01*
G02X1560070Y1692686I-302J0D01*
G01X1556370D01*
G02X1556068Y1692988I0J302D01*
G01Y1695853D01*
G02X1556099Y1695986I302J0D01*
G01X1557018Y1697861D01*
G03Y1698123I-267J131D01*
G01X1556099Y1699998D01*
G02X1556068Y1700131I271J133D01*
G01Y1702994D01*
G37*
G36*
G01X1575754D02*
G02X1576056Y1703296I302J0D01*
G01X1579756D01*
G02X1580058Y1702994I0J-302D01*
G01Y1692988D01*
G02X1579756Y1692686I-302J0D01*
G01X1576056D01*
G02X1575754Y1692988I0J302D01*
G01Y1695853D01*
G02X1575785Y1695986I302J0D01*
G01X1576704Y1697861D01*
G03Y1698123I-267J131D01*
G01X1575785Y1699998D01*
G02X1575754Y1700131I271J133D01*
G01Y1702994D01*
G37*
G36*
G01X1591502D02*
G02X1591804Y1703296I302J0D01*
G01X1595504D01*
G02X1595806Y1702994I0J-302D01*
G01Y1692988D01*
G02X1595504Y1692686I-302J0D01*
G01X1591804D01*
G02X1591502Y1692988I0J302D01*
G01Y1695853D01*
G02X1591533Y1695986I302J0D01*
G01X1592452Y1697861D01*
G03Y1698123I-267J131D01*
G01X1591533Y1699998D01*
G02X1591502Y1700131I271J133D01*
G01Y1702994D01*
G37*
G36*
G01X1607250D02*
G02X1607552Y1703296I302J0D01*
G01X1611252D01*
G02X1611554Y1702994I0J-302D01*
G01Y1692988D01*
G02X1611252Y1692686I-302J0D01*
G01X1607552D01*
G02X1607250Y1692988I0J302D01*
G01Y1695853D01*
G02X1607281Y1695986I302J0D01*
G01X1608200Y1697861D01*
G03Y1698123I-267J131D01*
G01X1607281Y1699998D01*
G02X1607250Y1700131I271J133D01*
G01Y1702994D01*
G37*
G36*
G01X1622998D02*
G02X1623300Y1703296I302J0D01*
G01X1627000D01*
G02X1627302Y1702994I0J-302D01*
G01Y1692988D01*
G02X1627000Y1692686I-302J0D01*
G01X1623300D01*
G02X1622998Y1692988I0J302D01*
G01Y1695853D01*
G02X1623029Y1695986I302J0D01*
G01X1623948Y1697861D01*
G03Y1698123I-267J131D01*
G01X1623029Y1699998D01*
G02X1622998Y1700131I271J133D01*
G01Y1702994D01*
G37*
G36*
G01X228902Y1713230D02*
G02X229205Y1713532I303J-1D01*
G01X232907D01*
G02X233208Y1713230I-1J-302D01*
G01Y1703224D01*
G02X232905Y1702922I-303J1D01*
G01X229203D01*
G02X228902Y1703224I1J302D01*
G01Y1713230D01*
G37*
G36*
G01X244650D02*
G02X244953Y1713532I303J-1D01*
G01X248655D01*
G02X248956Y1713230I-1J-302D01*
G01Y1703224D01*
G02X248653Y1702922I-303J1D01*
G01X244951D01*
G02X244650Y1703224I1J302D01*
G01Y1713230D01*
G37*
G36*
G01X260398D02*
G02X260701Y1713532I303J-1D01*
G01X264403D01*
G02X264704Y1713230I-1J-302D01*
G01Y1703224D01*
G02X264401Y1702922I-303J1D01*
G01X260699D01*
G02X260398Y1703224I1J302D01*
G01Y1713230D01*
G37*
G36*
G01X276146D02*
G02X276449Y1713532I303J-1D01*
G01X280151D01*
G02X280452Y1713230I-1J-302D01*
G01Y1703224D01*
G02X280149Y1702922I-303J1D01*
G01X276447D01*
G02X276146Y1703224I1J302D01*
G01Y1713230D01*
G37*
G36*
G01X295832D02*
G02X296134Y1713532I302J0D01*
G01X299834D01*
G02X300136Y1713230I0J-302D01*
G01Y1703224D01*
G02X299834Y1702922I-302J0D01*
G01X296134D01*
G02X295832Y1703224I0J302D01*
G01Y1713230D01*
G37*
G36*
G01X311580D02*
G02X311882Y1713532I302J0D01*
G01X315582D01*
G02X315884Y1713230I0J-302D01*
G01Y1703224D01*
G02X315582Y1702922I-302J0D01*
G01X311882D01*
G02X311580Y1703224I0J302D01*
G01Y1713230D01*
G37*
G36*
G01X327328D02*
G02X327630Y1713532I302J0D01*
G01X331330D01*
G02X331632Y1713230I0J-302D01*
G01Y1703224D01*
G02X331330Y1702922I-302J0D01*
G01X327630D01*
G02X327328Y1703224I0J302D01*
G01Y1713230D01*
G37*
G36*
G01X343076D02*
G02X343378Y1713532I302J0D01*
G01X347078D01*
G02X347380Y1713230I0J-302D01*
G01Y1703224D01*
G02X347078Y1702922I-302J0D01*
G01X343378D01*
G02X343076Y1703224I0J302D01*
G01Y1713230D01*
G37*
G36*
G01X493074Y1713231D02*
G02X493377Y1713534I303J0D01*
G01X497077D01*
G02X497380Y1713231I0J-303D01*
G01Y1703225D01*
G02X497077Y1702922I-303J0D01*
G01X493377D01*
G02X493074Y1703225I0J303D01*
G01Y1713231D01*
G37*
G36*
G01X508822D02*
G02X509125Y1713534I303J0D01*
G01X512825D01*
G02X513128Y1713231I0J-303D01*
G01Y1703225D01*
G02X512825Y1702922I-303J0D01*
G01X509125D01*
G02X508822Y1703225I0J303D01*
G01Y1713231D01*
G37*
G36*
G01X524570D02*
G02X524873Y1713534I303J0D01*
G01X528573D01*
G02X528876Y1713231I0J-303D01*
G01Y1703225D01*
G02X528573Y1702922I-303J0D01*
G01X524873D01*
G02X524570Y1703225I0J303D01*
G01Y1713231D01*
G37*
G36*
G01X540318D02*
G02X540621Y1713534I303J0D01*
G01X544321D01*
G02X544624Y1713231I0J-303D01*
G01Y1703225D01*
G02X544321Y1702922I-303J0D01*
G01X540621D01*
G02X540318Y1703225I0J303D01*
G01Y1713231D01*
G37*
G36*
G01X560004D02*
G02X560307Y1713534I303J0D01*
G01X564007D01*
G02X564310Y1713231I0J-303D01*
G01Y1703225D01*
G02X564007Y1702922I-303J0D01*
G01X560307D01*
G02X560004Y1703225I0J303D01*
G01Y1713231D01*
G37*
G36*
G01X575752D02*
G02X576055Y1713534I303J0D01*
G01X579755D01*
G02X580058Y1713231I0J-303D01*
G01Y1703225D01*
G02X579755Y1702922I-303J0D01*
G01X576055D01*
G02X575752Y1703225I0J303D01*
G01Y1713231D01*
G37*
G36*
G01X591500D02*
G02X591803Y1713534I303J0D01*
G01X595503D01*
G02X595806Y1713231I0J-303D01*
G01Y1703225D01*
G02X595503Y1702922I-303J0D01*
G01X591803D01*
G02X591500Y1703225I0J303D01*
G01Y1713231D01*
G37*
G36*
G01X607248D02*
G02X607551Y1713534I303J0D01*
G01X611251D01*
G02X611554Y1713231I0J-303D01*
G01Y1703225D01*
G02X611251Y1702922I-303J0D01*
G01X607551D01*
G02X607248Y1703225I0J303D01*
G01Y1713231D01*
G37*
G36*
G01X1236774D02*
G02X1237077Y1713534I303J0D01*
G01X1240777D01*
G02X1241080Y1713231I0J-303D01*
G01Y1703225D01*
G02X1240777Y1702922I-303J0D01*
G01X1237077D01*
G02X1236774Y1703225I0J303D01*
G01Y1713231D01*
G37*
G36*
G01X1252522D02*
G02X1252825Y1713534I303J0D01*
G01X1256525D01*
G02X1256828Y1713231I0J-303D01*
G01Y1703225D01*
G02X1256525Y1702922I-303J0D01*
G01X1252825D01*
G02X1252522Y1703225I0J303D01*
G01Y1713231D01*
G37*
G36*
G01X1268270D02*
G02X1268573Y1713534I303J0D01*
G01X1272273D01*
G02X1272576Y1713231I0J-303D01*
G01Y1703225D01*
G02X1272273Y1702922I-303J0D01*
G01X1268573D01*
G02X1268270Y1703225I0J303D01*
G01Y1713231D01*
G37*
G36*
G01X1284018D02*
G02X1284321Y1713534I303J0D01*
G01X1288021D01*
G02X1288324Y1713231I0J-303D01*
G01Y1703225D01*
G02X1288021Y1702922I-303J0D01*
G01X1284321D01*
G02X1284018Y1703225I0J303D01*
G01Y1713231D01*
G37*
G36*
G01X1303704D02*
G02X1304007Y1713534I303J0D01*
G01X1307707D01*
G02X1308010Y1713231I0J-303D01*
G01Y1703225D01*
G02X1307707Y1702922I-303J0D01*
G01X1304007D01*
G02X1303704Y1703225I0J303D01*
G01Y1713231D01*
G37*
G36*
G01X1319452D02*
G02X1319755Y1713534I303J0D01*
G01X1323455D01*
G02X1323758Y1713231I0J-303D01*
G01Y1703225D01*
G02X1323455Y1702922I-303J0D01*
G01X1319755D01*
G02X1319452Y1703225I0J303D01*
G01Y1713231D01*
G37*
G36*
G01X1335200D02*
G02X1335503Y1713534I303J0D01*
G01X1339203D01*
G02X1339506Y1713231I0J-303D01*
G01Y1703225D01*
G02X1339203Y1702922I-303J0D01*
G01X1335503D01*
G02X1335200Y1703225I0J303D01*
G01Y1713231D01*
G37*
G36*
G01X1350948D02*
G02X1351251Y1713534I303J0D01*
G01X1354951D01*
G02X1355254Y1713231I0J-303D01*
G01Y1703225D01*
G02X1354951Y1702922I-303J0D01*
G01X1351251D01*
G02X1350948Y1703225I0J303D01*
G01Y1713231D01*
G37*
G36*
G01X1500948D02*
G02X1501251Y1713534I303J0D01*
G01X1504951D01*
G02X1505254Y1713231I0J-303D01*
G01Y1703225D01*
G02X1504951Y1702922I-303J0D01*
G01X1501251D01*
G02X1500948Y1703225I0J303D01*
G01Y1713231D01*
G37*
G36*
G01X1516696D02*
G02X1516999Y1713534I303J0D01*
G01X1520699D01*
G02X1521002Y1713231I0J-303D01*
G01Y1703225D01*
G02X1520699Y1702922I-303J0D01*
G01X1516999D01*
G02X1516696Y1703225I0J303D01*
G01Y1713231D01*
G37*
G36*
G01X1532444D02*
G02X1532747Y1713534I303J0D01*
G01X1536447D01*
G02X1536750Y1713231I0J-303D01*
G01Y1703225D01*
G02X1536447Y1702922I-303J0D01*
G01X1532747D01*
G02X1532444Y1703225I0J303D01*
G01Y1713231D01*
G37*
G36*
G01X1548192D02*
G02X1548495Y1713534I303J0D01*
G01X1552195D01*
G02X1552498Y1713231I0J-303D01*
G01Y1703225D01*
G02X1552195Y1702922I-303J0D01*
G01X1548495D01*
G02X1548192Y1703225I0J303D01*
G01Y1713231D01*
G37*
G36*
G01X1567878D02*
G02X1568181Y1713534I303J0D01*
G01X1571881D01*
G02X1572184Y1713231I0J-303D01*
G01Y1703225D01*
G02X1571881Y1702922I-303J0D01*
G01X1568181D01*
G02X1567878Y1703225I0J303D01*
G01Y1713231D01*
G37*
G36*
G01X1583626D02*
G02X1583929Y1713534I303J0D01*
G01X1587629D01*
G02X1587932Y1713231I0J-303D01*
G01Y1703225D01*
G02X1587629Y1702922I-303J0D01*
G01X1583929D01*
G02X1583626Y1703225I0J303D01*
G01Y1713231D01*
G37*
G36*
G01X1599374D02*
G02X1599677Y1713534I303J0D01*
G01X1603377D01*
G02X1603680Y1713231I0J-303D01*
G01Y1703225D01*
G02X1603377Y1702922I-303J0D01*
G01X1599677D01*
G02X1599374Y1703225I0J303D01*
G01Y1713231D01*
G37*
G36*
G01X1615122D02*
G02X1615425Y1713534I303J0D01*
G01X1619125D01*
G02X1619428Y1713231I0J-303D01*
G01Y1703225D01*
G02X1619125Y1702922I-303J0D01*
G01X1615425D01*
G02X1615122Y1703225I0J303D01*
G01Y1713231D01*
G37*
G36*
G01X236776Y1717167D02*
G02X237079Y1717470I303J0D01*
G01X240779D01*
G02X241082Y1717167I0J-303D01*
G01Y1707161D01*
G02X240779Y1706858I-303J0D01*
G01X237079D01*
G02X236776Y1707161I0J303D01*
G01Y1717167D01*
G37*
G36*
G01X252524D02*
G02X252827Y1717470I303J0D01*
G01X256527D01*
G02X256830Y1717167I0J-303D01*
G01Y1707161D01*
G02X256527Y1706858I-303J0D01*
G01X252827D01*
G02X252524Y1707161I0J303D01*
G01Y1717167D01*
G37*
G36*
G01X268272D02*
G02X268575Y1717470I303J0D01*
G01X272275D01*
G02X272578Y1717167I0J-303D01*
G01Y1707161D01*
G02X272275Y1706858I-303J0D01*
G01X268575D01*
G02X268272Y1707161I0J303D01*
G01Y1717167D01*
G37*
G36*
G01X284020D02*
G02X284323Y1717470I303J0D01*
G01X288023D01*
G02X288326Y1717167I0J-303D01*
G01Y1707161D01*
G02X288023Y1706858I-303J0D01*
G01X284323D01*
G02X284020Y1707161I0J303D01*
G01Y1717167D01*
G37*
G36*
G01X303706D02*
G02X304008Y1717470I302J1D01*
G01X307708D01*
G02X308010Y1717167I-1J-303D01*
G01Y1707161D01*
G02X307708Y1706858I-302J-1D01*
G01X304008D01*
G02X303706Y1707161I1J303D01*
G01Y1717167D01*
G37*
G36*
G01X319454D02*
G02X319756Y1717470I302J1D01*
G01X323456D01*
G02X323758Y1717167I-1J-303D01*
G01Y1707161D01*
G02X323456Y1706858I-302J-1D01*
G01X319756D01*
G02X319454Y1707161I1J303D01*
G01Y1717167D01*
G37*
G36*
G01X335202D02*
G02X335504Y1717470I302J1D01*
G01X339204D01*
G02X339506Y1717167I-1J-303D01*
G01Y1707161D01*
G02X339204Y1706858I-302J-1D01*
G01X335504D01*
G02X335202Y1707161I1J303D01*
G01Y1717167D01*
G37*
G36*
G01X350950D02*
G02X351252Y1717470I302J1D01*
G01X354952D01*
G02X355254Y1717167I-1J-303D01*
G01Y1707161D01*
G02X354952Y1706858I-302J-1D01*
G01X351252D01*
G02X350950Y1707161I1J303D01*
G01Y1717167D01*
G37*
G36*
G01X500948Y1717168D02*
G02X501251Y1717470I303J-1D01*
G01X504953D01*
G02X505254Y1717168I-1J-302D01*
G01Y1707162D01*
G02X504951Y1706860I-303J1D01*
G01X501249D01*
G02X500948Y1707162I1J302D01*
G01Y1717168D01*
G37*
G36*
G01X516696D02*
G02X516999Y1717470I303J-1D01*
G01X520701D01*
G02X521002Y1717168I-1J-302D01*
G01Y1707162D01*
G02X520699Y1706860I-303J1D01*
G01X516997D01*
G02X516696Y1707162I1J302D01*
G01Y1717168D01*
G37*
G36*
G01X532444D02*
G02X532747Y1717470I303J-1D01*
G01X536449D01*
G02X536750Y1717168I-1J-302D01*
G01Y1707162D01*
G02X536447Y1706860I-303J1D01*
G01X532745D01*
G02X532444Y1707162I1J302D01*
G01Y1717168D01*
G37*
G36*
G01X548192D02*
G02X548495Y1717470I303J-1D01*
G01X552197D01*
G02X552498Y1717168I-1J-302D01*
G01Y1707162D01*
G02X552195Y1706860I-303J1D01*
G01X548493D01*
G02X548192Y1707162I1J302D01*
G01Y1717168D01*
G37*
G36*
G01X567878D02*
G02X568181Y1717470I303J-1D01*
G01X571883D01*
G02X572184Y1717168I-1J-302D01*
G01Y1707162D01*
G02X571881Y1706860I-303J1D01*
G01X568179D01*
G02X567878Y1707162I1J302D01*
G01Y1717168D01*
G37*
G36*
G01X583626D02*
G02X583929Y1717470I303J-1D01*
G01X587631D01*
G02X587932Y1717168I-1J-302D01*
G01Y1707162D01*
G02X587629Y1706860I-303J1D01*
G01X583927D01*
G02X583626Y1707162I1J302D01*
G01Y1717168D01*
G37*
G36*
G01X599374D02*
G02X599677Y1717470I303J-1D01*
G01X603379D01*
G02X603680Y1717168I-1J-302D01*
G01Y1707162D01*
G02X603377Y1706860I-303J1D01*
G01X599675D01*
G02X599374Y1707162I1J302D01*
G01Y1717168D01*
G37*
G36*
G01X615122D02*
G02X615425Y1717470I303J-1D01*
G01X619127D01*
G02X619428Y1717168I-1J-302D01*
G01Y1707162D01*
G02X619125Y1706860I-303J1D01*
G01X615423D01*
G02X615122Y1707162I1J302D01*
G01Y1717168D01*
G37*
G36*
G01X1244648D02*
G02X1244951Y1717470I303J-1D01*
G01X1248653D01*
G02X1248954Y1717168I-1J-302D01*
G01Y1707162D01*
G02X1248651Y1706860I-303J1D01*
G01X1244949D01*
G02X1244648Y1707162I1J302D01*
G01Y1717168D01*
G37*
G36*
G01X1260396D02*
G02X1260699Y1717470I303J-1D01*
G01X1264401D01*
G02X1264702Y1717168I-1J-302D01*
G01Y1707162D01*
G02X1264399Y1706860I-303J1D01*
G01X1260697D01*
G02X1260396Y1707162I1J302D01*
G01Y1717168D01*
G37*
G36*
G01X1276144D02*
G02X1276447Y1717470I303J-1D01*
G01X1280149D01*
G02X1280450Y1717168I-1J-302D01*
G01Y1707162D01*
G02X1280147Y1706860I-303J1D01*
G01X1276445D01*
G02X1276144Y1707162I1J302D01*
G01Y1717168D01*
G37*
G36*
G01X1291892D02*
G02X1292195Y1717470I303J-1D01*
G01X1295897D01*
G02X1296198Y1717168I-1J-302D01*
G01Y1707162D01*
G02X1295895Y1706860I-303J1D01*
G01X1292193D01*
G02X1291892Y1707162I1J302D01*
G01Y1717168D01*
G37*
G36*
G01X1311578D02*
G02X1311881Y1717470I303J-1D01*
G01X1315583D01*
G02X1315884Y1717168I-1J-302D01*
G01Y1707162D01*
G02X1315581Y1706860I-303J1D01*
G01X1311879D01*
G02X1311578Y1707162I1J302D01*
G01Y1717168D01*
G37*
G36*
G01X1327326D02*
G02X1327629Y1717470I303J-1D01*
G01X1331331D01*
G02X1331632Y1717168I-1J-302D01*
G01Y1707162D01*
G02X1331329Y1706860I-303J1D01*
G01X1327627D01*
G02X1327326Y1707162I1J302D01*
G01Y1717168D01*
G37*
G36*
G01X1343074D02*
G02X1343377Y1717470I303J-1D01*
G01X1347079D01*
G02X1347380Y1717168I-1J-302D01*
G01Y1707162D01*
G02X1347077Y1706860I-303J1D01*
G01X1343375D01*
G02X1343074Y1707162I1J302D01*
G01Y1717168D01*
G37*
G36*
G01X1358822D02*
G02X1359125Y1717470I303J-1D01*
G01X1362827D01*
G02X1363128Y1717168I-1J-302D01*
G01Y1707162D01*
G02X1362825Y1706860I-303J1D01*
G01X1359123D01*
G02X1358822Y1707162I1J302D01*
G01Y1717168D01*
G37*
G36*
G01X1508822D02*
G02X1509125Y1717470I303J-1D01*
G01X1512827D01*
G02X1513128Y1717168I-1J-302D01*
G01Y1707162D01*
G02X1512825Y1706860I-303J1D01*
G01X1509123D01*
G02X1508822Y1707162I1J302D01*
G01Y1717168D01*
G37*
G36*
G01X1524570D02*
G02X1524873Y1717470I303J-1D01*
G01X1528575D01*
G02X1528876Y1717168I-1J-302D01*
G01Y1707162D01*
G02X1528573Y1706860I-303J1D01*
G01X1524871D01*
G02X1524570Y1707162I1J302D01*
G01Y1717168D01*
G37*
G36*
G01X1540318D02*
G02X1540621Y1717470I303J-1D01*
G01X1544323D01*
G02X1544624Y1717168I-1J-302D01*
G01Y1707162D01*
G02X1544321Y1706860I-303J1D01*
G01X1540619D01*
G02X1540318Y1707162I1J302D01*
G01Y1717168D01*
G37*
G36*
G01X1556066D02*
G02X1556369Y1717470I303J-1D01*
G01X1560071D01*
G02X1560372Y1717168I-1J-302D01*
G01Y1707162D01*
G02X1560069Y1706860I-303J1D01*
G01X1556367D01*
G02X1556066Y1707162I1J302D01*
G01Y1717168D01*
G37*
G36*
G01X1575752D02*
G02X1576055Y1717470I303J-1D01*
G01X1579757D01*
G02X1580058Y1717168I-1J-302D01*
G01Y1707162D01*
G02X1579755Y1706860I-303J1D01*
G01X1576053D01*
G02X1575752Y1707162I1J302D01*
G01Y1717168D01*
G37*
G36*
G01X1591500D02*
G02X1591803Y1717470I303J-1D01*
G01X1595505D01*
G02X1595806Y1717168I-1J-302D01*
G01Y1707162D01*
G02X1595503Y1706860I-303J1D01*
G01X1591801D01*
G02X1591500Y1707162I1J302D01*
G01Y1717168D01*
G37*
G36*
G01X1607248D02*
G02X1607551Y1717470I303J-1D01*
G01X1611253D01*
G02X1611554Y1717168I-1J-302D01*
G01Y1707162D01*
G02X1611251Y1706860I-303J1D01*
G01X1607549D01*
G02X1607248Y1707162I1J302D01*
G01Y1717168D01*
G37*
G36*
G01X1622996D02*
G02X1623299Y1717470I303J-1D01*
G01X1627001D01*
G02X1627302Y1717168I-1J-302D01*
G01Y1707162D01*
G02X1626999Y1706860I-303J1D01*
G01X1623297D01*
G02X1622996Y1707162I1J302D01*
G01Y1717168D01*
G37*
G36*
G01X815268Y1720554D02*
G02X816152Y1720920I884J-885D01*
G01X901868D01*
G02X902752Y1720554I0J-1251D01*
G01X906384Y1716922D01*
G02X906750Y1716038I-885J-884D01*
G01Y1662730D01*
G03X906809Y1662588I200J0D01*
G01X925253Y1644144D01*
G03X925395Y1644085I142J141D01*
G01X1071615D01*
G02X1072499Y1643719I0J-1251D01*
G01X1104694Y1611524D01*
G02X1105060Y1610640I-885J-884D01*
G01Y1554972D01*
G02X1104267Y1553063I-2700J2D01*
G01X1102758Y1551554D01*
G02X1102734Y1551530I-1921J1897D01*
G01X1102705Y1551502D01*
X1102674Y1551429D01*
X1102672Y1551104D01*
G03X1102731Y1550962I200J0D01*
G01X1105128Y1548565D01*
G02X1105494Y1547681I-885J-884D01*
G01Y1546325D01*
G03X1105553Y1546183I200J0D01*
G01X1106834Y1544902D01*
G02X1107200Y1544018I-885J-884D01*
G01Y1528083D01*
X1107264Y1527984D01*
X1107318Y1527960D01*
G02Y1525222I-618J-1369D01*
G01X1107264Y1525198D01*
X1107200Y1525099D01*
Y1512882D01*
G02X1106834Y1511998I-1251J0D01*
G01X1104042Y1509206D01*
G02X1103158Y1508840I-884J885D01*
G01X1082180D01*
G02X1081296Y1509206I0J1251D01*
G01X1079878Y1510624D01*
G03X1079731Y1510683I-142J-141D01*
G01X1079401Y1510675D01*
X1079326Y1510640D01*
X1079299Y1510610D01*
G02X1079205Y1510512I-1995J1819D01*
G01X1078341Y1509648D01*
G03X1078339Y1509646I140J-142D01*
G01X1078143Y1509442D01*
G02X1077714Y1509153I-898J870D01*
G01X1077169Y1508932D01*
G02X1076699Y1508840I-471J1158D01*
G01X943079D01*
G02X941170Y1509633I2J2700D01*
G01X939306Y1511497D01*
G03X939304Y1511499I-142J-140D01*
G01X939100Y1511695D01*
G02X938811Y1512124I870J898D01*
G01X938590Y1512669D01*
G02X938498Y1513139I1158J471D01*
G01Y1547259D01*
G02X939291Y1549168I2700J-2D01*
G01X939871Y1549749D01*
G03Y1550031I-142J141D01*
G01X939599Y1550303D01*
G02X939233Y1551187I885J884D01*
G01Y1595231D01*
G03X939033Y1595431I-200J0D01*
G01X923917D01*
G03X923775Y1595372I0J-200D01*
G01X921862Y1593459D01*
G03X921803Y1593317I141J-142D01*
G01Y1590235D01*
G02X921437Y1589351I-1251J0D01*
G01X920893Y1588807D01*
G03X920834Y1588665I141J-142D01*
G01Y1575212D01*
G02X920468Y1574328I-1251J0D01*
G01X919595Y1573455D01*
G02X918711Y1573089I-884J885D01*
G01X904513D01*
G02X903629Y1573455I0J1251D01*
G01X902723Y1574361D01*
G02X902357Y1575245I885J884D01*
G01Y1588311D01*
G03X902298Y1588453I-200J0D01*
G01X901997Y1588754D01*
G02X901631Y1589638I885J884D01*
G01Y1598584D01*
G03X901572Y1598726I-200J0D01*
G01X894103Y1606195D01*
G03X893961Y1606254I-142J-141D01*
G01X887750D01*
G03X887562Y1606122I0J-200D01*
G02X886150Y1605131I-1412J510D01*
G02X885513Y1605273I0J1502D01*
G01X885456Y1605300D01*
X885332Y1605279D01*
X879652Y1599599D01*
G03X879593Y1599457I141J-142D01*
G01Y1589767D01*
G02X879227Y1588883I-1251J0D01*
G01X878892Y1588548D01*
G03X878833Y1588406I141J-142D01*
G01Y1575147D01*
G02X878467Y1574263I-1251J0D01*
G01X877692Y1573488D01*
G02X876808Y1573122I-884J885D01*
G01X862383D01*
G02X861499Y1573488I0J1251D01*
G01X860690Y1574297D01*
G02X860324Y1575181I885J884D01*
G01Y1588310D01*
G03X860265Y1588452I-200J0D01*
G01X860012Y1588705D01*
G02X859646Y1589589I885J884D01*
G01Y1598680D01*
G03X859587Y1598822I-200J0D01*
G01X852067Y1606342D01*
G03X851925Y1606401I-142J-141D01*
G01X845728D01*
X845620Y1606318D01*
X845603Y1606252D01*
G02X844150Y1605131I-1453J381D01*
G01X844149D01*
G02X843483Y1605287I1J1502D01*
G03X843252Y1605249I-89J-179D01*
G01X837586Y1599583D01*
G03X837527Y1599441I141J-142D01*
G01Y1589622D01*
G02X837161Y1588738I-1251J0D01*
G01X837069Y1588646D01*
G03X837010Y1588504I141J-142D01*
G01Y1575374D01*
G02X836644Y1574490I-1251J0D01*
G01X835416Y1573262D01*
G02X834532Y1572896I-884J885D01*
G01X820575D01*
G02X819691Y1573262I0J1251D01*
G01X818721Y1574232D01*
G02X818355Y1575116I885J884D01*
G01Y1588116D01*
G03X818296Y1588258I-200J0D01*
G01X817979Y1588575D01*
G02X817613Y1589459I885J884D01*
G01Y1598907D01*
G03X817554Y1599049I-200J0D01*
G01X810360Y1606243D01*
G03X810218Y1606302I-142J-141D01*
G01X803767D01*
G03X803577Y1606164I0J-200D01*
G02X802150Y1605131I-1427J469D01*
G02X801147Y1605516I1J1501D01*
G03X801012Y1605567I-134J-149D01*
G01X800892Y1605566D01*
G03X800752Y1605508I1J-200D01*
G01X795843Y1600599D01*
G03X795784Y1600457I141J-142D01*
G01Y1589718D01*
G02X795418Y1588834I-1251J0D01*
G01X795004Y1588420D01*
G03X794945Y1588278I141J-142D01*
G01Y1575245D01*
G02X794579Y1574361I-1251J0D01*
G01X793554Y1573336D01*
G02X792670Y1572970I-884J885D01*
G01X778599D01*
G02X777715Y1573336I0J1251D01*
G01X776721Y1574330D01*
G02X776355Y1575214I885J884D01*
G01Y1588309D01*
G03X776296Y1588451I-200J0D01*
G01X768907Y1595840D01*
G03X768765Y1595899I-142J-141D01*
G01X752860D01*
G03X752718Y1595840I0J-200D01*
G01X742663Y1585785D01*
G03X742604Y1585643I141J-142D01*
G01Y1575099D01*
G02X742238Y1574215I-1251J0D01*
G01X741510Y1573487D01*
G02X740626Y1573121I-884J885D01*
G01X726236D01*
G02X725352Y1573487I0J1251D01*
G01X724543Y1574296D01*
G02X724177Y1575180I885J884D01*
G01Y1616962D01*
G02X724543Y1617846I1251J0D01*
G01X726716Y1620019D01*
G02X727600Y1620385I884J-885D01*
G01X739420D01*
G03X739562Y1620444I0J200D01*
G01X742109Y1622991D01*
G02X742993Y1623357I884J-885D01*
G01X768182D01*
G03X768324Y1623416I0J200D01*
G01X772047Y1627139D01*
G03X772106Y1627281I-141J142D01*
G01Y1660280D01*
G02X772472Y1661164I1251J0D01*
G01X808681Y1697373D01*
G03X808740Y1697515I-141J142D01*
G01Y1713508D01*
G02X809106Y1714392I1251J0D01*
G01X815268Y1720554D01*
G37*
G36*
G01X435748Y1712135D02*
G02X446338I5295J6330D01*
G01X446297Y1712101D01*
X446260Y1712004D01*
X446322Y1711612D01*
G03X446443Y1711458I198J31D01*
G02X455296Y1698268I-5399J-13190D01*
G02X426790I-14253J0D01*
G02X435643Y1711458I14252J0D01*
G01X435692Y1711478D01*
X435756Y1711560D01*
X435826Y1712004D01*
X435789Y1712101D01*
X435748Y1712135D01*
G37*
G36*
G01X1411142D02*
G02X1421732I5295J6330D01*
G01X1421691Y1712101D01*
X1421654Y1712004D01*
X1421716Y1711612D01*
G03X1421837Y1711458I198J31D01*
G02X1430690Y1698268I-5399J-13190D01*
G02X1402184I-14253J0D01*
G02X1402186Y1698468I14253J-43D01*
G01X1402185D01*
G02X1411037Y1711458I14252J-201D01*
G01X1411086Y1711478D01*
X1411150Y1711560D01*
X1411219Y1712004D01*
X1411182Y1712102D01*
X1411142Y1712135D01*
G37*
G36*
G01X228902Y1727404D02*
G02X229205Y1727706I303J-1D01*
G01X232907D01*
G02X233208Y1727404I-1J-302D01*
G01Y1717398D01*
G02X232905Y1717096I-303J1D01*
G01X229203D01*
G02X228902Y1717398I1J302D01*
G01Y1727404D01*
G37*
G36*
G01X244650D02*
G02X244953Y1727706I303J-1D01*
G01X248655D01*
G02X248956Y1727404I-1J-302D01*
G01Y1717398D01*
G02X248653Y1717096I-303J1D01*
G01X244951D01*
G02X244650Y1717398I1J302D01*
G01Y1727404D01*
G37*
G36*
G01X260398D02*
G02X260701Y1727706I303J-1D01*
G01X264403D01*
G02X264704Y1727404I-1J-302D01*
G01Y1717398D01*
G02X264401Y1717096I-303J1D01*
G01X260699D01*
G02X260398Y1717398I1J302D01*
G01Y1727404D01*
G37*
G36*
G01X276146D02*
G02X276449Y1727706I303J-1D01*
G01X280151D01*
G02X280452Y1727404I-1J-302D01*
G01Y1717398D01*
G02X280149Y1717096I-303J1D01*
G01X276447D01*
G02X276146Y1717398I1J302D01*
G01Y1727404D01*
G37*
G36*
G01X295832D02*
G02X296134Y1727706I302J0D01*
G01X299834D01*
G02X300136Y1727404I0J-302D01*
G01Y1717398D01*
G02X299834Y1717096I-302J0D01*
G01X296134D01*
G02X295832Y1717398I0J302D01*
G01Y1727404D01*
G37*
G36*
G01X311580D02*
G02X311882Y1727706I302J0D01*
G01X315582D01*
G02X315884Y1727404I0J-302D01*
G01Y1717398D01*
G02X315582Y1717096I-302J0D01*
G01X311882D01*
G02X311580Y1717398I0J302D01*
G01Y1727404D01*
G37*
G36*
G01X327328D02*
G02X327630Y1727706I302J0D01*
G01X331330D01*
G02X331632Y1727404I0J-302D01*
G01Y1717398D01*
G02X331330Y1717096I-302J0D01*
G01X327630D01*
G02X327328Y1717398I0J302D01*
G01Y1727404D01*
G37*
G36*
G01X343076D02*
G02X343378Y1727706I302J0D01*
G01X347078D01*
G02X347380Y1727404I0J-302D01*
G01Y1717398D01*
G02X347078Y1717096I-302J0D01*
G01X343378D01*
G02X343076Y1717398I0J302D01*
G01Y1727404D01*
G37*
G36*
G01X493076D02*
G02X493378Y1727706I302J0D01*
G01X497078D01*
G02X497380Y1727404I0J-302D01*
G01Y1717398D01*
G02X497078Y1717096I-302J0D01*
G01X493378D01*
G02X493076Y1717398I0J302D01*
G01Y1727404D01*
G37*
G36*
G01X508824D02*
G02X509126Y1727706I302J0D01*
G01X512826D01*
G02X513128Y1727404I0J-302D01*
G01Y1717398D01*
G02X512826Y1717096I-302J0D01*
G01X509126D01*
G02X508824Y1717398I0J302D01*
G01Y1727404D01*
G37*
G36*
G01X524572D02*
G02X524874Y1727706I302J0D01*
G01X528574D01*
G02X528876Y1727404I0J-302D01*
G01Y1717398D01*
G02X528574Y1717096I-302J0D01*
G01X524874D01*
G02X524572Y1717398I0J302D01*
G01Y1727404D01*
G37*
G36*
G01X540320D02*
G02X540622Y1727706I302J0D01*
G01X544322D01*
G02X544624Y1727404I0J-302D01*
G01Y1717398D01*
G02X544322Y1717096I-302J0D01*
G01X540622D01*
G02X540320Y1717398I0J302D01*
G01Y1727404D01*
G37*
G36*
G01X560004D02*
G02X560307Y1727706I303J-1D01*
G01X564009D01*
G02X564310Y1727404I-1J-302D01*
G01Y1717398D01*
G02X564007Y1717096I-303J1D01*
G01X560305D01*
G02X560004Y1717398I1J302D01*
G01Y1727404D01*
G37*
G36*
G01X575752D02*
G02X576055Y1727706I303J-1D01*
G01X579757D01*
G02X580058Y1727404I-1J-302D01*
G01Y1717398D01*
G02X579755Y1717096I-303J1D01*
G01X576053D01*
G02X575752Y1717398I1J302D01*
G01Y1727404D01*
G37*
G36*
G01X591500D02*
G02X591803Y1727706I303J-1D01*
G01X595505D01*
G02X595806Y1727404I-1J-302D01*
G01Y1717398D01*
G02X595503Y1717096I-303J1D01*
G01X591801D01*
G02X591500Y1717398I1J302D01*
G01Y1727404D01*
G37*
G36*
G01X607248D02*
G02X607551Y1727706I303J-1D01*
G01X611253D01*
G02X611554Y1727404I-1J-302D01*
G01Y1717398D01*
G02X611251Y1717096I-303J1D01*
G01X607549D01*
G02X607248Y1717398I1J302D01*
G01Y1727404D01*
G37*
G36*
G01X1236776D02*
G02X1237079Y1727706I303J-1D01*
G01X1240781D01*
G02X1241082Y1727404I-1J-302D01*
G01Y1717398D01*
G02X1240779Y1717096I-303J1D01*
G01X1237077D01*
G02X1236776Y1717398I1J302D01*
G01Y1727404D01*
G37*
G36*
G01X1252524D02*
G02X1252827Y1727706I303J-1D01*
G01X1256529D01*
G02X1256830Y1727404I-1J-302D01*
G01Y1717398D01*
G02X1256527Y1717096I-303J1D01*
G01X1252825D01*
G02X1252524Y1717398I1J302D01*
G01Y1727404D01*
G37*
G36*
G01X1268272D02*
G02X1268575Y1727706I303J-1D01*
G01X1272277D01*
G02X1272578Y1727404I-1J-302D01*
G01Y1717398D01*
G02X1272275Y1717096I-303J1D01*
G01X1268573D01*
G02X1268272Y1717398I1J302D01*
G01Y1727404D01*
G37*
G36*
G01X1284020D02*
G02X1284323Y1727706I303J-1D01*
G01X1288025D01*
G02X1288326Y1727404I-1J-302D01*
G01Y1717398D01*
G02X1288023Y1717096I-303J1D01*
G01X1284321D01*
G02X1284020Y1717398I1J302D01*
G01Y1727404D01*
G37*
G36*
G01X1303706D02*
G02X1304008Y1727706I302J0D01*
G01X1307708D01*
G02X1308010Y1727404I0J-302D01*
G01Y1717398D01*
G02X1307708Y1717096I-302J0D01*
G01X1304008D01*
G02X1303706Y1717398I0J302D01*
G01Y1727404D01*
G37*
G36*
G01X1319454D02*
G02X1319756Y1727706I302J0D01*
G01X1323456D01*
G02X1323758Y1727404I0J-302D01*
G01Y1717398D01*
G02X1323456Y1717096I-302J0D01*
G01X1319756D01*
G02X1319454Y1717398I0J302D01*
G01Y1727404D01*
G37*
G36*
G01X1335202D02*
G02X1335504Y1727706I302J0D01*
G01X1339204D01*
G02X1339506Y1727404I0J-302D01*
G01Y1717398D01*
G02X1339204Y1717096I-302J0D01*
G01X1335504D01*
G02X1335202Y1717398I0J302D01*
G01Y1727404D01*
G37*
G36*
G01X1350950D02*
G02X1351252Y1727706I302J0D01*
G01X1354952D01*
G02X1355254Y1727404I0J-302D01*
G01Y1717398D01*
G02X1354952Y1717096I-302J0D01*
G01X1351252D01*
G02X1350950Y1717398I0J302D01*
G01Y1727404D01*
G37*
G36*
G01X1500950D02*
G02X1501252Y1727706I302J0D01*
G01X1504952D01*
G02X1505254Y1727404I0J-302D01*
G01Y1717398D01*
G02X1504952Y1717096I-302J0D01*
G01X1501252D01*
G02X1500950Y1717398I0J302D01*
G01Y1727404D01*
G37*
G36*
G01X1516698D02*
G02X1517000Y1727706I302J0D01*
G01X1520700D01*
G02X1521002Y1727404I0J-302D01*
G01Y1717398D01*
G02X1520700Y1717096I-302J0D01*
G01X1517000D01*
G02X1516698Y1717398I0J302D01*
G01Y1727404D01*
G37*
G36*
G01X1532446D02*
G02X1532748Y1727706I302J0D01*
G01X1536448D01*
G02X1536750Y1727404I0J-302D01*
G01Y1717398D01*
G02X1536448Y1717096I-302J0D01*
G01X1532748D01*
G02X1532446Y1717398I0J302D01*
G01Y1727404D01*
G37*
G36*
G01X1548194D02*
G02X1548496Y1727706I302J0D01*
G01X1552196D01*
G02X1552498Y1727404I0J-302D01*
G01Y1717398D01*
G02X1552196Y1717096I-302J0D01*
G01X1548496D01*
G02X1548194Y1717398I0J302D01*
G01Y1727404D01*
G37*
G36*
G01X1567878D02*
G02X1568181Y1727706I303J-1D01*
G01X1571883D01*
G02X1572184Y1727404I-1J-302D01*
G01Y1717398D01*
G02X1571881Y1717096I-303J1D01*
G01X1568179D01*
G02X1567878Y1717398I1J302D01*
G01Y1727404D01*
G37*
G36*
G01X1583626D02*
G02X1583929Y1727706I303J-1D01*
G01X1587631D01*
G02X1587932Y1727404I-1J-302D01*
G01Y1717398D01*
G02X1587629Y1717096I-303J1D01*
G01X1583927D01*
G02X1583626Y1717398I1J302D01*
G01Y1727404D01*
G37*
G36*
G01X1599374D02*
G02X1599677Y1727706I303J-1D01*
G01X1603379D01*
G02X1603680Y1727404I-1J-302D01*
G01Y1717398D01*
G02X1603377Y1717096I-303J1D01*
G01X1599675D01*
G02X1599374Y1717398I1J302D01*
G01Y1727404D01*
G37*
G36*
G01X1615122D02*
G02X1615425Y1727706I303J-1D01*
G01X1619127D01*
G02X1619428Y1727404I-1J-302D01*
G01Y1717398D01*
G02X1619125Y1717096I-303J1D01*
G01X1615423D01*
G02X1615122Y1717398I1J302D01*
G01Y1727404D01*
G37*
G36*
G01X236776Y1731341D02*
G02X237079Y1731644I303J0D01*
G01X240779D01*
G02X241082Y1731341I0J-303D01*
G01Y1721335D01*
G02X240779Y1721032I-303J0D01*
G01X237079D01*
G02X236776Y1721335I0J303D01*
G01Y1731341D01*
G37*
G36*
G01X252524D02*
G02X252827Y1731644I303J0D01*
G01X256527D01*
G02X256830Y1731341I0J-303D01*
G01Y1721335D01*
G02X256527Y1721032I-303J0D01*
G01X252827D01*
G02X252524Y1721335I0J303D01*
G01Y1731341D01*
G37*
G36*
G01X268272D02*
G02X268575Y1731644I303J0D01*
G01X272275D01*
G02X272578Y1731341I0J-303D01*
G01Y1721335D01*
G02X272275Y1721032I-303J0D01*
G01X268575D01*
G02X268272Y1721335I0J303D01*
G01Y1731341D01*
G37*
G36*
G01X284020D02*
G02X284323Y1731644I303J0D01*
G01X288023D01*
G02X288326Y1731341I0J-303D01*
G01Y1721335D01*
G02X288023Y1721032I-303J0D01*
G01X284323D01*
G02X284020Y1721335I0J303D01*
G01Y1731341D01*
G37*
G36*
G01X303706D02*
G02X304008Y1731644I302J1D01*
G01X307708D01*
G02X308010Y1731341I-1J-303D01*
G01Y1721335D01*
G02X307708Y1721032I-302J-1D01*
G01X304008D01*
G02X303706Y1721335I1J303D01*
G01Y1731341D01*
G37*
G36*
G01X319454D02*
G02X319756Y1731644I302J1D01*
G01X323456D01*
G02X323758Y1731341I-1J-303D01*
G01Y1721335D01*
G02X323456Y1721032I-302J-1D01*
G01X319756D01*
G02X319454Y1721335I1J303D01*
G01Y1731341D01*
G37*
G36*
G01X335202D02*
G02X335504Y1731644I302J1D01*
G01X339204D01*
G02X339506Y1731341I-1J-303D01*
G01Y1721335D01*
G02X339204Y1721032I-302J-1D01*
G01X335504D01*
G02X335202Y1721335I1J303D01*
G01Y1731341D01*
G37*
G36*
G01X350950D02*
G02X351252Y1731644I302J1D01*
G01X354952D01*
G02X355254Y1731341I-1J-303D01*
G01Y1721335D01*
G02X354952Y1721032I-302J-1D01*
G01X351252D01*
G02X350950Y1721335I1J303D01*
G01Y1731341D01*
G37*
G36*
G01X500950D02*
G02X501252Y1731644I302J1D01*
G01X504952D01*
G02X505254Y1731341I-1J-303D01*
G01Y1721335D01*
G02X504952Y1721032I-302J-1D01*
G01X501252D01*
G02X500950Y1721335I1J303D01*
G01Y1731341D01*
G37*
G36*
G01X516698D02*
G02X517000Y1731644I302J1D01*
G01X520700D01*
G02X521002Y1731341I-1J-303D01*
G01Y1721335D01*
G02X520700Y1721032I-302J-1D01*
G01X517000D01*
G02X516698Y1721335I1J303D01*
G01Y1731341D01*
G37*
G36*
G01X532446D02*
G02X532748Y1731644I302J1D01*
G01X536448D01*
G02X536750Y1731341I-1J-303D01*
G01Y1721335D01*
G02X536448Y1721032I-302J-1D01*
G01X532748D01*
G02X532446Y1721335I1J303D01*
G01Y1731341D01*
G37*
G36*
G01X548194D02*
G02X548496Y1731644I302J1D01*
G01X552196D01*
G02X552498Y1731341I-1J-303D01*
G01Y1721335D01*
G02X552196Y1721032I-302J-1D01*
G01X548496D01*
G02X548194Y1721335I1J303D01*
G01Y1731341D01*
G37*
G36*
G01X567878D02*
G02X568181Y1731644I303J0D01*
G01X571881D01*
G02X572184Y1731341I0J-303D01*
G01Y1721335D01*
G02X571881Y1721032I-303J0D01*
G01X568181D01*
G02X567878Y1721335I0J303D01*
G01Y1731341D01*
G37*
G36*
G01X583626D02*
G02X583929Y1731644I303J0D01*
G01X587629D01*
G02X587932Y1731341I0J-303D01*
G01Y1721335D01*
G02X587629Y1721032I-303J0D01*
G01X583929D01*
G02X583626Y1721335I0J303D01*
G01Y1731341D01*
G37*
G36*
G01X599374D02*
G02X599677Y1731644I303J0D01*
G01X603377D01*
G02X603680Y1731341I0J-303D01*
G01Y1721335D01*
G02X603377Y1721032I-303J0D01*
G01X599677D01*
G02X599374Y1721335I0J303D01*
G01Y1731341D01*
G37*
G36*
G01X615122D02*
G02X615425Y1731644I303J0D01*
G01X619125D01*
G02X619428Y1731341I0J-303D01*
G01Y1721335D01*
G02X619125Y1721032I-303J0D01*
G01X615425D01*
G02X615122Y1721335I0J303D01*
G01Y1731341D01*
G37*
G36*
G01X1244650D02*
G02X1244953Y1731644I303J0D01*
G01X1248653D01*
G02X1248956Y1731341I0J-303D01*
G01Y1721335D01*
G02X1248653Y1721032I-303J0D01*
G01X1244953D01*
G02X1244650Y1721335I0J303D01*
G01Y1731341D01*
G37*
G36*
G01X1260398D02*
G02X1260701Y1731644I303J0D01*
G01X1264401D01*
G02X1264704Y1731341I0J-303D01*
G01Y1721335D01*
G02X1264401Y1721032I-303J0D01*
G01X1260701D01*
G02X1260398Y1721335I0J303D01*
G01Y1731341D01*
G37*
G36*
G01X1276146D02*
G02X1276449Y1731644I303J0D01*
G01X1280149D01*
G02X1280452Y1731341I0J-303D01*
G01Y1721335D01*
G02X1280149Y1721032I-303J0D01*
G01X1276449D01*
G02X1276146Y1721335I0J303D01*
G01Y1731341D01*
G37*
G36*
G01X1291894D02*
G02X1292197Y1731644I303J0D01*
G01X1295897D01*
G02X1296200Y1731341I0J-303D01*
G01Y1721335D01*
G02X1295897Y1721032I-303J0D01*
G01X1292197D01*
G02X1291894Y1721335I0J303D01*
G01Y1731341D01*
G37*
G36*
G01X1311580D02*
G02X1311882Y1731644I302J1D01*
G01X1315582D01*
G02X1315884Y1731341I-1J-303D01*
G01Y1721335D01*
G02X1315582Y1721032I-302J-1D01*
G01X1311882D01*
G02X1311580Y1721335I1J303D01*
G01Y1731341D01*
G37*
G36*
G01X1327328D02*
G02X1327630Y1731644I302J1D01*
G01X1331330D01*
G02X1331632Y1731341I-1J-303D01*
G01Y1721335D01*
G02X1331330Y1721032I-302J-1D01*
G01X1327630D01*
G02X1327328Y1721335I1J303D01*
G01Y1731341D01*
G37*
G36*
G01X1343076D02*
G02X1343378Y1731644I302J1D01*
G01X1347078D01*
G02X1347380Y1731341I-1J-303D01*
G01Y1721335D01*
G02X1347078Y1721032I-302J-1D01*
G01X1343378D01*
G02X1343076Y1721335I1J303D01*
G01Y1731341D01*
G37*
G36*
G01X1358824D02*
G02X1359126Y1731644I302J1D01*
G01X1362826D01*
G02X1363128Y1731341I-1J-303D01*
G01Y1721335D01*
G02X1362826Y1721032I-302J-1D01*
G01X1359126D01*
G02X1358824Y1721335I1J303D01*
G01Y1731341D01*
G37*
G36*
G01X1508824D02*
G02X1509126Y1731644I302J1D01*
G01X1512826D01*
G02X1513128Y1731341I-1J-303D01*
G01Y1721335D01*
G02X1512826Y1721032I-302J-1D01*
G01X1509126D01*
G02X1508824Y1721335I1J303D01*
G01Y1731341D01*
G37*
G36*
G01X1524572D02*
G02X1524874Y1731644I302J1D01*
G01X1528574D01*
G02X1528876Y1731341I-1J-303D01*
G01Y1721335D01*
G02X1528574Y1721032I-302J-1D01*
G01X1524874D01*
G02X1524572Y1721335I1J303D01*
G01Y1731341D01*
G37*
G36*
G01X1540320D02*
G02X1540622Y1731644I302J1D01*
G01X1544322D01*
G02X1544624Y1731341I-1J-303D01*
G01Y1721335D01*
G02X1544322Y1721032I-302J-1D01*
G01X1540622D01*
G02X1540320Y1721335I1J303D01*
G01Y1731341D01*
G37*
G36*
G01X1556068D02*
G02X1556370Y1731644I302J1D01*
G01X1560070D01*
G02X1560372Y1731341I-1J-303D01*
G01Y1721335D01*
G02X1560070Y1721032I-302J-1D01*
G01X1556370D01*
G02X1556068Y1721335I1J303D01*
G01Y1731341D01*
G37*
G36*
G01X1575752D02*
G02X1576055Y1731644I303J0D01*
G01X1579755D01*
G02X1580058Y1731341I0J-303D01*
G01Y1721335D01*
G02X1579755Y1721032I-303J0D01*
G01X1576055D01*
G02X1575752Y1721335I0J303D01*
G01Y1731341D01*
G37*
G36*
G01X1591500D02*
G02X1591803Y1731644I303J0D01*
G01X1595503D01*
G02X1595806Y1731341I0J-303D01*
G01Y1721335D01*
G02X1595503Y1721032I-303J0D01*
G01X1591803D01*
G02X1591500Y1721335I0J303D01*
G01Y1731341D01*
G37*
G36*
G01X1607248D02*
G02X1607551Y1731644I303J0D01*
G01X1611251D01*
G02X1611554Y1731341I0J-303D01*
G01Y1721335D01*
G02X1611251Y1721032I-303J0D01*
G01X1607551D01*
G02X1607248Y1721335I0J303D01*
G01Y1731341D01*
G37*
G36*
G01X1622996D02*
G02X1623299Y1731644I303J0D01*
G01X1626999D01*
G02X1627302Y1731341I0J-303D01*
G01Y1721335D01*
G02X1626999Y1721032I-303J0D01*
G01X1623299D01*
G02X1622996Y1721335I0J303D01*
G01Y1731341D01*
G37*
G54D88*
X1461791Y1095024D03*
X1472893D03*
X1461791Y1075890D03*
Y1082268D03*
Y1088646D03*
X1472893D03*
Y1082268D03*
Y1075890D03*
X1461791Y1063134D03*
Y1069512D03*
X1472893D03*
Y1063134D03*
X1450688Y1095024D03*
Y1088646D03*
Y1082268D03*
Y1075890D03*
Y1069512D03*
Y1063134D03*
X1439586Y1095024D03*
Y1101402D03*
Y1075890D03*
Y1082268D03*
Y1088646D03*
Y1063134D03*
Y1069512D03*
X1430334Y1091835D03*
Y1098213D03*
Y1085457D03*
Y1079079D03*
Y1072701D03*
Y1066323D03*
Y1059945D03*
X1408154Y1091835D03*
Y1098213D03*
Y1079079D03*
Y1085457D03*
Y1066323D03*
Y1072701D03*
Y1059945D03*
X1387800Y1095024D03*
X1398902D03*
Y1101402D03*
X1387800Y1075890D03*
Y1082268D03*
Y1088646D03*
X1398902Y1075890D03*
Y1082268D03*
Y1088646D03*
X1387800Y1063134D03*
Y1069512D03*
X1398902Y1063134D03*
Y1069512D03*
X1376697Y1095024D03*
Y1075890D03*
Y1082268D03*
Y1088646D03*
Y1063134D03*
Y1069512D03*
X1365595Y1095024D03*
Y1088646D03*
Y1082268D03*
Y1075890D03*
Y1069512D03*
Y1063134D03*
X463444Y1101403D03*
X454192Y1098214D03*
Y1091836D03*
Y1079080D03*
Y1085458D03*
Y1066324D03*
Y1072702D03*
Y1059946D03*
X474546Y1095025D03*
Y1075891D03*
Y1082269D03*
Y1088647D03*
Y1063135D03*
Y1069513D03*
X463444Y1095025D03*
Y1088647D03*
Y1082269D03*
Y1075891D03*
Y1069513D03*
Y1063135D03*
X496751Y1095025D03*
Y1075891D03*
Y1082269D03*
Y1088647D03*
Y1063135D03*
Y1069513D03*
X485649Y1095025D03*
Y1088647D03*
Y1082269D03*
Y1075891D03*
Y1069513D03*
Y1063135D03*
X432012Y1098214D03*
X422760Y1101403D03*
X432012Y1091836D03*
Y1085458D03*
Y1079080D03*
Y1072702D03*
Y1066324D03*
Y1059946D03*
X422760Y1095025D03*
Y1088647D03*
Y1082269D03*
Y1075891D03*
Y1069513D03*
Y1063135D03*
X411658Y1095025D03*
Y1088647D03*
Y1082269D03*
Y1075891D03*
Y1069513D03*
Y1063135D03*
X400555Y1095025D03*
Y1088647D03*
Y1082269D03*
Y1075891D03*
Y1069513D03*
Y1063135D03*
X389453D03*
Y1069513D03*
Y1075891D03*
Y1082269D03*
Y1088647D03*
Y1095025D03*
G54D89*
X1469192Y1095024D03*
Y1088646D03*
Y1082268D03*
Y1075890D03*
Y1069512D03*
Y1063134D03*
X1458090Y1095024D03*
X1446987D03*
X1458090Y1075890D03*
Y1082268D03*
Y1088646D03*
X1446987D03*
Y1082268D03*
Y1075890D03*
X1458090Y1063134D03*
Y1069512D03*
X1446987D03*
Y1063134D03*
X1435885Y1095024D03*
Y1101402D03*
Y1075890D03*
Y1082268D03*
Y1088646D03*
Y1063134D03*
Y1069512D03*
X1426633Y1091835D03*
Y1098213D03*
Y1085457D03*
Y1079079D03*
Y1072701D03*
Y1066323D03*
Y1059945D03*
X1404453Y1091835D03*
Y1098213D03*
Y1079079D03*
Y1085457D03*
Y1066323D03*
Y1072701D03*
Y1059945D03*
X1395201Y1095024D03*
Y1101402D03*
Y1075890D03*
Y1082268D03*
Y1088646D03*
Y1063134D03*
Y1069512D03*
X1372996Y1095024D03*
X1384099D03*
X1372996Y1075890D03*
Y1082268D03*
Y1088646D03*
X1384099Y1075890D03*
Y1082268D03*
Y1088646D03*
X1372996Y1063134D03*
Y1069512D03*
X1384099Y1063134D03*
Y1069512D03*
X1361894Y1095024D03*
Y1088646D03*
Y1082268D03*
Y1075890D03*
Y1069512D03*
Y1063134D03*
X459743Y1101403D03*
X450491Y1098214D03*
Y1091836D03*
Y1079080D03*
Y1085458D03*
Y1066324D03*
Y1072702D03*
Y1059946D03*
X470845Y1095025D03*
Y1075891D03*
Y1082269D03*
Y1088647D03*
Y1063135D03*
Y1069513D03*
X459743Y1095025D03*
Y1088647D03*
Y1082269D03*
Y1075891D03*
Y1069513D03*
Y1063135D03*
X493050Y1095025D03*
Y1075891D03*
Y1082269D03*
Y1088647D03*
Y1063135D03*
Y1069513D03*
X481948Y1095025D03*
Y1088647D03*
Y1082269D03*
Y1075891D03*
Y1069513D03*
Y1063135D03*
X428311Y1098214D03*
X419059Y1101403D03*
X428311Y1091836D03*
Y1085458D03*
Y1079080D03*
Y1072702D03*
Y1066324D03*
Y1059946D03*
X419059Y1095025D03*
Y1088647D03*
Y1082269D03*
Y1075891D03*
Y1069513D03*
Y1063135D03*
X407957Y1095025D03*
Y1088647D03*
Y1082269D03*
Y1075891D03*
Y1069513D03*
Y1063135D03*
X396854Y1095025D03*
Y1088647D03*
Y1082269D03*
Y1075891D03*
Y1069513D03*
Y1063135D03*
X385752D03*
Y1069513D03*
Y1075891D03*
Y1082269D03*
Y1088647D03*
Y1095025D03*
G54D108*
X766889Y1486756D03*
Y1530256D03*
G54D91*
X263316Y87665D03*
X712291Y106722D03*
X820901Y147112D03*
X1005307Y155043D03*
X101675Y160694D03*
X1571516Y319099D03*
X1290127Y410635D03*
X788710Y1488821D03*
G54D87*
X398673Y-18871D03*
Y-8871D03*
X373673D03*
Y-18871D03*
X398673Y-28871D03*
X373673D03*
X718093Y-8871D03*
Y-18871D03*
X743093D03*
Y-8871D03*
X718093Y-28871D03*
X743093D03*
X850152Y-5011D03*
X825152D03*
X850152Y-15011D03*
X825152D03*
X850152Y-35011D03*
Y-25011D03*
X825152D03*
Y-35011D03*
X850152Y4989D03*
X825152D03*
X850152Y14989D03*
X825152D03*
X850152Y24989D03*
X825152D03*
X1169572Y-5011D03*
X1194572D03*
X1169572Y-15011D03*
X1194572D03*
X1169572Y-25011D03*
Y-35011D03*
X1194572D03*
Y-25011D03*
X1169572Y4989D03*
X1194572D03*
X1169572Y14989D03*
X1194572D03*
X1169572Y24989D03*
X1194572D03*
X1253672Y-15011D03*
X1228672D03*
X1253672Y-35011D03*
Y-25011D03*
X1228672D03*
Y-35011D03*
X1253672Y-5011D03*
X1228672D03*
X1253672Y4989D03*
Y14989D03*
X1228672D03*
Y4989D03*
X1253672Y24989D03*
X1228672D03*
X1428431Y-15011D03*
X1453431D03*
X1428431Y-25011D03*
Y-35011D03*
X1453431D03*
Y-25011D03*
X1428431Y-5011D03*
X1453431D03*
X1428431Y14989D03*
Y4989D03*
X1453431D03*
Y14989D03*
X1428431Y24989D03*
X1453431D03*
X1546966Y-39212D03*
Y-29212D03*
X1521966D03*
Y-39212D03*
X1546966Y-19212D03*
X1521966D03*
X1721725Y-29212D03*
Y-39212D03*
X1746725D03*
Y-29212D03*
X1721725Y-19212D03*
X1746725D03*
G54D90*
X60303Y20354D03*
X1534712D03*
X312921Y24291D03*
X1787330D03*
X505185Y41141D03*
X929331Y160413D03*
X922441Y237697D03*
G54D98*
X676509Y224606D03*
G54D96*
Y145866D03*
G54D110*
X791280Y1704890D03*
X1066280D03*
G54D106*
X1340948Y1179681D03*
G54D101*
X433624Y594259D03*
X1415690Y601230D03*
X1487677Y640145D03*
X1524437Y640365D03*
X326731Y653394D03*
X363731D03*
X1291146Y1375715D03*
X1320516D03*
X1166535Y1412479D03*
X1700840Y1424519D03*
X754645Y1426892D03*
G54D92*
X526460Y99195D03*
X400426Y114515D03*
X553780Y122940D03*
X570860Y123010D03*
X417486Y125879D03*
X35852Y668745D03*
Y679710D03*
Y690616D03*
Y701522D03*
X372000Y833497D03*
Y844727D03*
X1342036Y1204729D03*
X313284Y1216822D03*
X390974Y1221149D03*
X388630Y1238447D03*
X814296Y1385745D03*
X50880Y1417263D03*
X558876Y1456605D03*
X1115098Y1470571D03*
X427286Y1481890D03*
X555348D03*
X544794Y1482382D03*
X672856D03*
X544794Y1495782D03*
X672856D03*
X427286Y1503690D03*
X555348D03*
X1170986Y1514890D03*
X1299048D03*
X1435160D03*
X1563222D03*
X1288494Y1515382D03*
X1416556D03*
X1552668D03*
X1680730D03*
X426704Y1525031D03*
X554766D03*
X1288494Y1528782D03*
X1416556D03*
X1552668D03*
X1680730D03*
X1170986Y1536690D03*
X1299048D03*
X1435160D03*
X1563222D03*
X188254Y1546697D03*
X192978D03*
X207152D03*
X211876D03*
X226050D03*
X230774D03*
X254396D03*
X259120D03*
X316316D03*
X321040D03*
X335214D03*
X339938D03*
X354112D03*
X358836D03*
X382458D03*
X387182D03*
X461876D03*
X466600D03*
X480774D03*
X485498D03*
X499672D03*
X504396D03*
X509120D03*
X513844D03*
X589938D03*
X594662D03*
X608836D03*
X613560D03*
X627734D03*
X632458D03*
X637182D03*
X641906D03*
X1170404Y1558031D03*
X1298466D03*
X1434578D03*
X1562640D03*
X1205576Y1579697D03*
X1210300D03*
X1224474D03*
X1229198D03*
X1243372D03*
X1248096D03*
X1252820D03*
X1257544D03*
X1333638D03*
X1338362D03*
X1352536D03*
X1357260D03*
X1371434D03*
X1376158D03*
X1380882D03*
X1385606D03*
X1469750D03*
X1474474D03*
X1488648D03*
X1493372D03*
X1507546D03*
X1512270D03*
X1516994D03*
X1521718D03*
X1597812D03*
X1602536D03*
X1616710D03*
X1621434D03*
X1635608D03*
X1640332D03*
X1645056D03*
X1649780D03*
X1131824Y1602293D03*
X436776Y1612094D03*
X142576Y1641863D03*
X1141084Y1644972D03*
X1090958Y1648228D03*
X40922Y1656569D03*
X85836Y1656843D03*
X165336Y1676777D03*
G54D109*
X138071Y1482244D03*
X698819D03*
X1145945Y1515236D03*
X1706693D03*
X163662Y1593661D03*
X673228D03*
X1171536Y1626654D03*
X1681102D03*
G54D93*
X559069Y103685D03*
X482255Y131522D03*
X704771Y169488D03*
X716699Y175387D03*
X704771Y181299D03*
X716699Y187387D03*
X704771Y193110D03*
X716699Y198887D03*
X704771Y204921D03*
X716699Y210721D03*
X704771Y216732D03*
X1007587Y763246D03*
Y774180D03*
Y785182D03*
Y796184D03*
Y807118D03*
X385001Y815227D03*
X1007587Y818052D03*
X371999Y821227D03*
X1007587Y829054D03*
Y840056D03*
X1315657Y1197832D03*
X1346063Y1216029D03*
X1370685Y1224732D03*
X58349Y1408031D03*
X653999Y1425057D03*
X546253Y1455807D03*
X163113Y1481890D03*
X291175D03*
X280621Y1482382D03*
X408683D03*
X280621Y1495782D03*
X408683D03*
X163113Y1503690D03*
X291175D03*
X162531Y1525031D03*
X290593D03*
X197703Y1546697D03*
X202427D03*
X216601D03*
X221325D03*
X235499D03*
X240223D03*
X244947D03*
X249671D03*
X325765D03*
X330489D03*
X344663D03*
X349387D03*
X363561D03*
X368285D03*
X373009D03*
X377733D03*
X452427D03*
X457151D03*
X471325D03*
X476049D03*
X490223D03*
X494947D03*
X518569D03*
X523293D03*
X580489D03*
X585213D03*
X599387D03*
X604111D03*
X618285D03*
X623009D03*
X646631D03*
X651355D03*
X1196127Y1579697D03*
X1200851D03*
X1215025D03*
X1219749D03*
X1233923D03*
X1238647D03*
X1262269D03*
X1266993D03*
X1324189D03*
X1328913D03*
X1343087D03*
X1347811D03*
X1361985D03*
X1366709D03*
X1390331D03*
X1395055D03*
X1460301D03*
X1465025D03*
X1479199D03*
X1483923D03*
X1498097D03*
X1502821D03*
X1526443D03*
X1531167D03*
X1588363D03*
X1593087D03*
X1607261D03*
X1611985D03*
X1626159D03*
X1630883D03*
X1654505D03*
X1659229D03*
X1142917Y1585014D03*
X1118133Y1589698D03*
X403837Y1610756D03*
X154945Y1626050D03*
X163735Y1633669D03*
X193679Y1641752D03*
X307255Y1645450D03*
X205479Y1650430D03*
X1146501Y1653908D03*
X297323Y1655472D03*
X99443Y1660231D03*
X165491Y1663882D03*
X87891Y1672821D03*
X41679Y1675023D03*
X100443Y1685763D03*
G54D111*
X1766929Y1714960D03*
G54D94*
X516020Y107320D03*
X535170Y113180D03*
X405606Y127765D03*
X80948Y523563D03*
X80318Y541363D03*
G54D102*
X117933Y605376D03*
X1094076Y605378D03*
X1739745Y605411D03*
X763602Y605413D03*
G54D85*
X1729562Y-24215D03*
Y-34215D03*
X1436268Y9986D03*
Y-14D03*
Y-20014D03*
Y-30014D03*
X725930Y-13874D03*
Y-23874D03*
X390846Y-13874D03*
Y-23874D03*
G54D84*
X1837795Y18819D03*
X19685Y-29134D03*
X1800449Y126194D03*
X44000Y154200D03*
X31818Y1424257D03*
X1804650Y1667292D03*
X441043Y1672205D03*
X1416437D03*
X1885039Y49021D03*
X2081889Y-29134D03*
X2081889Y1803261D03*
X1871260Y1291627D03*
G54D100*
X62813Y414050D03*
X47619Y417134D03*
X1025493Y763769D03*
G54D97*
X805690Y204724D03*
X1057659D03*
G54D95*
X1829921Y130314D03*
G54D86*
X1539139Y-24215D03*
Y-34215D03*
X1245845Y9986D03*
Y-14D03*
Y-20014D03*
Y-30014D03*
X1177409Y19986D03*
Y9986D03*
Y-10014D03*
Y-20014D03*
X842325Y19986D03*
Y9986D03*
Y-10014D03*
Y-20014D03*
G54D105*
X1582551Y1019213D03*
X1251055D03*
X606409Y1019214D03*
X274913D03*
G54D103*
X1296331Y838504D03*
X320189Y838505D03*
X1296331Y1199922D03*
X320189Y1199923D03*
G54D104*
X1537275Y838504D03*
X561133Y838505D03*
X1537275Y1199922D03*
X561133Y1199923D03*
G54D107*
X841240Y1420331D03*
X1016240D03*
G54D99*
X177413Y277208D03*
X1153555D03*
X704185Y277236D03*
X1680327D03*
%LPC*%
G75*
G36*
G01X386552Y1069513D02*
G02I-800J0D01*
G37*
G36*
G01Y1063135D02*
G02I-800J0D01*
G37*
G36*
G01X390253Y1069513D02*
G02I-800J0D01*
G37*
G36*
G01Y1063135D02*
G02I-800J0D01*
G37*
G36*
G01X386552Y1075891D02*
G02I-800J0D01*
G37*
G36*
G01X390253D02*
G02I-800J0D01*
G37*
G36*
G01X386552Y1088647D02*
G02I-800J0D01*
G37*
G36*
G01Y1082269D02*
G02I-800J0D01*
G37*
G36*
G01X390253Y1088647D02*
G02I-800J0D01*
G37*
G36*
G01Y1082269D02*
G02I-800J0D01*
G37*
G36*
G01X386552Y1095025D02*
G02I-800J0D01*
G37*
G36*
G01X390253D02*
G02I-800J0D01*
G37*
G36*
G01X397654Y1069513D02*
G02I-800J0D01*
G37*
G36*
G01Y1063135D02*
G02I-800J0D01*
G37*
G36*
G01X408757Y1069513D02*
G02I-800J0D01*
G37*
G36*
G01Y1063135D02*
G02I-800J0D01*
G37*
G36*
G01X401355Y1069513D02*
G02I-800J0D01*
G37*
G36*
G01Y1063135D02*
G02I-800J0D01*
G37*
G36*
G01X397654Y1075891D02*
G02I-800J0D01*
G37*
G36*
G01X408757D02*
G02I-800J0D01*
G37*
G36*
G01X401355D02*
G02I-800J0D01*
G37*
G36*
G01X397654Y1088647D02*
G02I-800J0D01*
G37*
G36*
G01Y1082269D02*
G02I-800J0D01*
G37*
G36*
G01X408757Y1088647D02*
G02I-800J0D01*
G37*
G36*
G01Y1082269D02*
G02I-800J0D01*
G37*
G36*
G01X401355Y1088647D02*
G02I-800J0D01*
G37*
G36*
G01Y1082269D02*
G02I-800J0D01*
G37*
G36*
G01X397654Y1095025D02*
G02I-800J0D01*
G37*
G36*
G01X408757D02*
G02I-800J0D01*
G37*
G36*
G01X401355D02*
G02I-800J0D01*
G37*
G36*
G01X419859Y1063135D02*
G02I-800J0D01*
G37*
G36*
G01Y1069513D02*
G02I-800J0D01*
G37*
G36*
G01X423560Y1063135D02*
G02I-800J0D01*
G37*
G36*
G01X412458Y1069513D02*
G02I-800J0D01*
G37*
G36*
G01Y1063135D02*
G02I-800J0D01*
G37*
G36*
G01X423560Y1069513D02*
G02I-800J0D01*
G37*
G36*
G01X419859Y1075891D02*
G02I-800J0D01*
G37*
G36*
G01X423560D02*
G02I-800J0D01*
G37*
G36*
G01X412458D02*
G02I-800J0D01*
G37*
G36*
G01X419859Y1082269D02*
G02I-800J0D01*
G37*
G36*
G01Y1088647D02*
G02I-800J0D01*
G37*
G36*
G01X423560Y1082269D02*
G02I-800J0D01*
G37*
G36*
G01X412458Y1088647D02*
G02I-800J0D01*
G37*
G36*
G01Y1082269D02*
G02I-800J0D01*
G37*
G36*
G01X423560Y1088647D02*
G02I-800J0D01*
G37*
G36*
G01X419859Y1095025D02*
G02I-800J0D01*
G37*
G36*
G01Y1101403D02*
G02I-800J0D01*
G37*
G36*
G01X423560Y1095025D02*
G02I-800J0D01*
G37*
G36*
G01Y1101403D02*
G02I-800J0D01*
G37*
G36*
G01X412458Y1095025D02*
G02I-800J0D01*
G37*
G36*
G01X429111Y1059946D02*
G02I-800J0D01*
G37*
G36*
G01X432812D02*
G02I-800J0D01*
G37*
G36*
G01X429111Y1072702D02*
G02I-800J0D01*
G37*
G36*
G01Y1066324D02*
G02I-800J0D01*
G37*
G36*
G01X432812Y1072702D02*
G02I-800J0D01*
G37*
G36*
G01Y1066324D02*
G02I-800J0D01*
G37*
G36*
G01X429111Y1079080D02*
G02I-800J0D01*
G37*
G36*
G01X432812D02*
G02I-800J0D01*
G37*
G36*
G01X429111Y1085458D02*
G02I-800J0D01*
G37*
G36*
G01X432812D02*
G02I-800J0D01*
G37*
G36*
G01X429111Y1098214D02*
G02I-800J0D01*
G37*
G36*
G01Y1091836D02*
G02I-800J0D01*
G37*
G36*
G01X432812Y1098214D02*
G02I-800J0D01*
G37*
G36*
G01Y1091836D02*
G02I-800J0D01*
G37*
G36*
G01X454992Y1059946D02*
G02I-800J0D01*
G37*
G36*
G01X451291D02*
G02I-800J0D01*
G37*
G36*
G01X454992Y1066324D02*
G02I-800J0D01*
G37*
G36*
G01Y1072702D02*
G02I-800J0D01*
G37*
G36*
G01X451291Y1066324D02*
G02I-800J0D01*
G37*
G36*
G01Y1072702D02*
G02I-800J0D01*
G37*
G36*
G01X454992Y1079080D02*
G02I-800J0D01*
G37*
G36*
G01X451291D02*
G02I-800J0D01*
G37*
G36*
G01X454992Y1085458D02*
G02I-800J0D01*
G37*
G36*
G01X451291D02*
G02I-800J0D01*
G37*
G36*
G01X454992Y1091836D02*
G02I-800J0D01*
G37*
G36*
G01Y1098214D02*
G02I-800J0D01*
G37*
G36*
G01X451291Y1091836D02*
G02I-800J0D01*
G37*
G36*
G01Y1098214D02*
G02I-800J0D01*
G37*
G36*
G01X464244Y1063135D02*
G02I-800J0D01*
G37*
G36*
G01Y1069513D02*
G02I-800J0D01*
G37*
G36*
G01X460543Y1063135D02*
G02I-800J0D01*
G37*
G36*
G01Y1069513D02*
G02I-800J0D01*
G37*
G36*
G01X464244Y1075891D02*
G02I-800J0D01*
G37*
G36*
G01X460543D02*
G02I-800J0D01*
G37*
G36*
G01X464244Y1082269D02*
G02I-800J0D01*
G37*
G36*
G01Y1088647D02*
G02I-800J0D01*
G37*
G36*
G01X460543Y1082269D02*
G02I-800J0D01*
G37*
G36*
G01Y1088647D02*
G02I-800J0D01*
G37*
G36*
G01X464244Y1101403D02*
G02I-800J0D01*
G37*
G36*
G01Y1095025D02*
G02I-800J0D01*
G37*
G36*
G01X460543Y1101403D02*
G02I-800J0D01*
G37*
G36*
G01Y1095025D02*
G02I-800J0D01*
G37*
G36*
G01X475346Y1063135D02*
G02I-800J0D01*
G37*
G36*
G01Y1069513D02*
G02I-800J0D01*
G37*
G36*
G01X482748Y1063135D02*
G02I-800J0D01*
G37*
G36*
G01Y1069513D02*
G02I-800J0D01*
G37*
G36*
G01X471645Y1063135D02*
G02I-800J0D01*
G37*
G36*
G01Y1069513D02*
G02I-800J0D01*
G37*
G36*
G01X475346Y1075891D02*
G02I-800J0D01*
G37*
G36*
G01X482748D02*
G02I-800J0D01*
G37*
G36*
G01X471645D02*
G02I-800J0D01*
G37*
G36*
G01X475346Y1082269D02*
G02I-800J0D01*
G37*
G36*
G01Y1088647D02*
G02I-800J0D01*
G37*
G36*
G01X482748Y1082269D02*
G02I-800J0D01*
G37*
G36*
G01Y1088647D02*
G02I-800J0D01*
G37*
G36*
G01X471645Y1082269D02*
G02I-800J0D01*
G37*
G36*
G01Y1088647D02*
G02I-800J0D01*
G37*
G36*
G01X475346Y1095025D02*
G02I-800J0D01*
G37*
G36*
G01X482748D02*
G02I-800J0D01*
G37*
G36*
G01X471645D02*
G02I-800J0D01*
G37*
G36*
G01X486449Y1063135D02*
G02I-800J0D01*
G37*
G36*
G01Y1069513D02*
G02I-800J0D01*
G37*
G36*
G01X497551Y1063135D02*
G02I-800J0D01*
G37*
G36*
G01Y1069513D02*
G02I-800J0D01*
G37*
G36*
G01X493850Y1063135D02*
G02I-800J0D01*
G37*
G36*
G01Y1069513D02*
G02I-800J0D01*
G37*
G36*
G01X486449Y1075891D02*
G02I-800J0D01*
G37*
G36*
G01X497551D02*
G02I-800J0D01*
G37*
G36*
G01X493850D02*
G02I-800J0D01*
G37*
G36*
G01X486449Y1082269D02*
G02I-800J0D01*
G37*
G36*
G01Y1088647D02*
G02I-800J0D01*
G37*
G36*
G01X497551Y1082269D02*
G02I-800J0D01*
G37*
G36*
G01Y1088647D02*
G02I-800J0D01*
G37*
G36*
G01X493850Y1082269D02*
G02I-800J0D01*
G37*
G36*
G01Y1088647D02*
G02I-800J0D01*
G37*
G36*
G01X486449Y1095025D02*
G02I-800J0D01*
G37*
G36*
G01X497551D02*
G02I-800J0D01*
G37*
G36*
G01X493850D02*
G02I-800J0D01*
G37*
G36*
G01X816753Y1718420D02*
X901267D01*
G02X901409Y1718361I0J-200D01*
G01X904191Y1715579D01*
G02X904250Y1715437I-141J-142D01*
G01Y1662129D01*
G03X904616Y1661245I1251J0D01*
G01X923910Y1641951D01*
G03X924794Y1641585I884J885D01*
G01X1071014D01*
G02X1071156Y1641526I0J-200D01*
G01X1102501Y1610181D01*
G02X1102560Y1610039I-141J-142D01*
G01Y1554974D01*
G02X1102501Y1554832I-200J0D01*
G03X1102500Y1554831I883J-884D01*
G01X1100990Y1553321D01*
G03X1100989Y1553320I883J-884D01*
G02X1100847Y1553261I-142J141D01*
G01X1094691D01*
G02X1094581Y1553294I0J200D01*
G03X1092934Y1553786I-1647J-2511D01*
G03X1091528Y1553436I1J-3002D01*
G02X1091340I-94J177D01*
G03X1089934Y1553786I-1407J-2652D01*
G03X1088287Y1553294I0J-3003D01*
G02X1088177Y1553261I-110J167D01*
G01X1059235D01*
G02X1059120Y1553297I0J200D01*
G03X1057396Y1553842I-1725J-2457D01*
G03X1055990Y1553492I1J-3002D01*
G02X1055802I-94J177D01*
G03X1054396Y1553842I-1407J-2652D01*
G03X1052672Y1553297I1J-3002D01*
G02X1052557Y1553261I-115J164D01*
G01X1027635D01*
G02X1027520Y1553297I0J200D01*
G03X1025796Y1553842I-1725J-2457D01*
G03X1024390Y1553492I1J-3002D01*
G02X1024202I-94J177D01*
G03X1022796Y1553842I-1407J-2652D01*
G03X1021072Y1553297I1J-3002D01*
G02X1020957Y1553261I-115J164D01*
G01X996035D01*
G02X995920Y1553297I0J200D01*
G03X994196Y1553842I-1725J-2457D01*
G03X992790Y1553492I1J-3002D01*
G02X992602I-94J177D01*
G03X991196Y1553842I-1407J-2652D01*
G03X989472Y1553297I1J-3002D01*
G02X989357Y1553261I-115J164D01*
G01X964400D01*
G02X964287Y1553296I0J200D01*
G03X962584Y1553826I-1703J-2471D01*
G03X961178Y1553476I1J-3002D01*
G02X960990I-94J177D01*
G03X959584Y1553826I-1407J-2652D01*
G03X957881Y1553296I0J-3001D01*
G02X957768Y1553261I-113J165D01*
G01X941933D01*
G02X941733Y1553461I0J200D01*
G01Y1596024D01*
G03X941367Y1596908I-1251J0D01*
G01X940710Y1597565D01*
G03X939826Y1597931I-884J-885D01*
G01X923316D01*
G03X922432Y1597565I0J-1251D01*
G01X919669Y1594802D01*
G03X919303Y1593918I885J-884D01*
G01Y1590836D01*
G02X919244Y1590694I-200J0D01*
G01X918700Y1590150D01*
G03X918334Y1589266I885J-884D01*
G01Y1575813D01*
G02X918275Y1575671I-200J0D01*
G01X918252Y1575648D01*
G02X918110Y1575589I-142J141D01*
G01X905114D01*
G02X904972Y1575648I0J200D01*
G01X904916Y1575704D01*
G02X904857Y1575846I141J142D01*
G01Y1588912D01*
G03X904491Y1589796I-1251J0D01*
G01X904190Y1590097D01*
G02X904131Y1590239I141J142D01*
G01Y1599185D01*
G03X903765Y1600069I-1251J0D01*
G01X895446Y1608388D01*
G03X894562Y1608754I-884J-885D01*
G01X888356D01*
G02X888218Y1608809I0J200D01*
G03X886150Y1609635I-2068J-2176D01*
G03X883149Y1606710I0J-3002D01*
G01X883148Y1606671D01*
X883118Y1606601D01*
X877459Y1600942D01*
G03X877093Y1600058I885J-884D01*
G01Y1590368D01*
G02X877034Y1590226I-200J0D01*
G01X876699Y1589891D01*
G03X876333Y1589007I885J-884D01*
G01Y1575708D01*
X876303Y1575635D01*
X876290Y1575622D01*
X862984D01*
G02X862842Y1575681I0J200D01*
G01X862824Y1575699D01*
Y1588911D01*
G03X862458Y1589795I-1251J0D01*
G01X862205Y1590048D01*
G02X862146Y1590190I141J142D01*
G01Y1599281D01*
G03X861780Y1600165I-1251J0D01*
G01X853410Y1608535D01*
G03X852526Y1608901I-884J-885D01*
G01X846190D01*
G02X846063Y1608947I1J200D01*
G03X844150Y1609635I-1912J-2314D01*
G03X841151Y1606758I0J-3002D01*
G01X841149Y1606720D01*
X841119Y1606652D01*
X835393Y1600926D01*
G03X835027Y1600042I885J-884D01*
G01Y1590223D01*
G02X834968Y1590081I-200J0D01*
G01X834876Y1589989D01*
G03X834510Y1589105I885J-884D01*
G01Y1575975D01*
G02X834451Y1575833I-200J0D01*
G01X834073Y1575455D01*
G02X833931Y1575396I-142J141D01*
G01X821176D01*
G02X821034Y1575455I0J200D01*
G01X820914Y1575575D01*
G02X820855Y1575717I141J142D01*
G01Y1588717D01*
G03X820489Y1589601I-1251J0D01*
G01X820172Y1589918D01*
G02X820113Y1590060I141J142D01*
G01Y1599508D01*
G03X819747Y1600392I-1251J0D01*
G01X811703Y1608436D01*
G03X810819Y1608802I-884J-885D01*
G01X804304D01*
G02X804170Y1608854I0J200D01*
G03X802150Y1609635I-2020J-2222D01*
G03X799323Y1607642I0J-3001D01*
G01X799307Y1607599D01*
X793650Y1601942D01*
G03X793284Y1601058I885J-884D01*
G01Y1590319D01*
G02X793225Y1590177I-200J0D01*
G01X792811Y1589763D01*
G03X792445Y1588879I885J-884D01*
G01Y1575846D01*
G02X792386Y1575704I-200J0D01*
G01X792211Y1575529D01*
G02X792069Y1575470I-142J141D01*
G01X779200D01*
G02X779058Y1575529I0J200D01*
G01X778914Y1575673D01*
G02X778855Y1575815I141J142D01*
G01Y1588910D01*
G03X778489Y1589794I-1251J0D01*
G01X770250Y1598033D01*
G03X769366Y1598399I-884J-885D01*
G01X752259D01*
G03X751375Y1598033I0J-1251D01*
G01X740470Y1587128D01*
G03X740104Y1586244I885J-884D01*
G01Y1575821D01*
G02X739904Y1575621I-200J0D01*
G01X726837D01*
G02X726695Y1575680I0J200D01*
G01X726677Y1575698D01*
Y1597760D01*
X726767Y1597870D01*
X726839Y1597884D01*
G03Y1600832I-289J1474D01*
G01X726767Y1600846D01*
X726677Y1600956D01*
Y1616361D01*
G02X726736Y1616503I200J0D01*
G01X728059Y1617826D01*
G02X728201Y1617885I142J-141D01*
G01X740021D01*
G03X740905Y1618251I0J1251D01*
G01X743452Y1620798D01*
G02X743594Y1620857I142J-141D01*
G01X768783D01*
G03X769667Y1621223I0J1251D01*
G01X774240Y1625796D01*
G03X774606Y1626680I-885J884D01*
G01Y1659679D01*
G02X774665Y1659821I200J0D01*
G01X810874Y1696030D01*
G03X811240Y1696914I-885J884D01*
G01Y1712907D01*
G02X811299Y1713049I200J0D01*
G01X816611Y1718361D01*
G02X816753Y1718420I142J-141D01*
G37*
G36*
G01X1075557Y1548281D02*
G03X1075558Y1548280I884J883D01*
G01X1077438Y1546400D01*
G03X1077439Y1546399I884J883D01*
G02X1077498Y1546257I-141J-142D01*
G01Y1512423D01*
G02X1077439Y1512281I-200J0D01*
G03X1077438Y1512280I883J-884D01*
G01X1076566Y1511408D01*
G02X1076564Y1511406I-142J140D01*
G03X1076557Y1511399I881J-887D01*
G02X1076415Y1511340I-142J141D01*
G01X943081D01*
G02X942939Y1511399I0J200D01*
G03X942938Y1511400I-884J-883D01*
G01X941065Y1513273D01*
X941064Y1513274D01*
G03X941057Y1513281I-887J-881D01*
G02X940998Y1513423I141J142D01*
G01Y1547257D01*
G02X941057Y1547399I200J0D01*
G03X941058Y1547400I-883J884D01*
G01X941938Y1548280D01*
G03X941939Y1548281I-883J884D01*
G02X942081Y1548340I142J-141D01*
G01X1075415D01*
G02X1075557Y1548281I0J-200D01*
G37*
G36*
G01X1081757Y1543874D02*
X1082064Y1544181D01*
G02X1082206Y1544240I142J-141D01*
G01X1099402D01*
G02X1099602Y1544040I0J-200D01*
G01Y1511540D01*
G02X1099402Y1511340I-200J0D01*
G01X1082781D01*
G02X1082639Y1511399I0J200D01*
G01X1081757Y1512281D01*
G02X1081698Y1512423I141J142D01*
G01Y1543732D01*
G02X1081757Y1543874I200J0D01*
G37*
G36*
G01X1362694Y1069512D02*
G02I-800J0D01*
G37*
G36*
G01Y1063134D02*
G02I-800J0D01*
G37*
G36*
G01Y1075890D02*
G02I-800J0D01*
G37*
G36*
G01Y1088646D02*
G02I-800J0D01*
G37*
G36*
G01Y1082268D02*
G02I-800J0D01*
G37*
G36*
G01Y1095024D02*
G02I-800J0D01*
G37*
G36*
G01X1373796Y1069512D02*
G02I-800J0D01*
G37*
G36*
G01Y1063134D02*
G02I-800J0D01*
G37*
G36*
G01X1366395Y1069512D02*
G02I-800J0D01*
G37*
G36*
G01Y1063134D02*
G02I-800J0D01*
G37*
G36*
G01X1377497Y1069512D02*
G02I-800J0D01*
G37*
G36*
G01Y1063134D02*
G02I-800J0D01*
G37*
G36*
G01X1373796Y1075890D02*
G02I-800J0D01*
G37*
G36*
G01X1366395D02*
G02I-800J0D01*
G37*
G36*
G01X1377497D02*
G02I-800J0D01*
G37*
G36*
G01X1373796Y1088646D02*
G02I-800J0D01*
G37*
G36*
G01Y1082268D02*
G02I-800J0D01*
G37*
G36*
G01X1366395Y1088646D02*
G02I-800J0D01*
G37*
G36*
G01Y1082268D02*
G02I-800J0D01*
G37*
G36*
G01X1377497Y1088646D02*
G02I-800J0D01*
G37*
G36*
G01Y1082268D02*
G02I-800J0D01*
G37*
G36*
G01X1373796Y1095024D02*
G02I-800J0D01*
G37*
G36*
G01X1366395D02*
G02I-800J0D01*
G37*
G36*
G01X1377497D02*
G02I-800J0D01*
G37*
G36*
G01X1384899Y1069512D02*
G02I-800J0D01*
G37*
G36*
G01Y1063134D02*
G02I-800J0D01*
G37*
G36*
G01X1388600Y1069512D02*
G02I-800J0D01*
G37*
G36*
G01Y1063134D02*
G02I-800J0D01*
G37*
G36*
G01X1384899Y1075890D02*
G02I-800J0D01*
G37*
G36*
G01X1388600D02*
G02I-800J0D01*
G37*
G36*
G01X1384899Y1088646D02*
G02I-800J0D01*
G37*
G36*
G01Y1082268D02*
G02I-800J0D01*
G37*
G36*
G01X1388600Y1088646D02*
G02I-800J0D01*
G37*
G36*
G01Y1082268D02*
G02I-800J0D01*
G37*
G36*
G01X1384899Y1095024D02*
G02I-800J0D01*
G37*
G36*
G01X1388600D02*
G02I-800J0D01*
G37*
G36*
G01X1405253Y1059945D02*
G02I-800J0D01*
G37*
G36*
G01X1408954D02*
G02I-800J0D01*
G37*
G36*
G01X1396001Y1063134D02*
G02I-800J0D01*
G37*
G36*
G01X1405253Y1072701D02*
G02I-800J0D01*
G37*
G36*
G01Y1066323D02*
G02I-800J0D01*
G37*
G36*
G01X1396001Y1069512D02*
G02I-800J0D01*
G37*
G36*
G01X1399702Y1063134D02*
G02I-800J0D01*
G37*
G36*
G01X1408954Y1072701D02*
G02I-800J0D01*
G37*
G36*
G01Y1066323D02*
G02I-800J0D01*
G37*
G36*
G01X1399702Y1069512D02*
G02I-800J0D01*
G37*
G36*
G01X1396001Y1075890D02*
G02I-800J0D01*
G37*
G36*
G01X1405253Y1079079D02*
G02I-800J0D01*
G37*
G36*
G01X1399702Y1075890D02*
G02I-800J0D01*
G37*
G36*
G01X1408954Y1079079D02*
G02I-800J0D01*
G37*
G36*
G01X1396001Y1082268D02*
G02I-800J0D01*
G37*
G36*
G01X1405253Y1085457D02*
G02I-800J0D01*
G37*
G36*
G01X1396001Y1088646D02*
G02I-800J0D01*
G37*
G36*
G01X1399702Y1082268D02*
G02I-800J0D01*
G37*
G36*
G01X1408954Y1085457D02*
G02I-800J0D01*
G37*
G36*
G01X1399702Y1088646D02*
G02I-800J0D01*
G37*
G36*
G01X1396001Y1095024D02*
G02I-800J0D01*
G37*
G36*
G01Y1101402D02*
G02I-800J0D01*
G37*
G36*
G01X1405253Y1098213D02*
G02I-800J0D01*
G37*
G36*
G01Y1091835D02*
G02I-800J0D01*
G37*
G36*
G01X1399702Y1095024D02*
G02I-800J0D01*
G37*
G36*
G01Y1101402D02*
G02I-800J0D01*
G37*
G36*
G01X1408954Y1098213D02*
G02I-800J0D01*
G37*
G36*
G01Y1091835D02*
G02I-800J0D01*
G37*
G36*
G01X1431134Y1059945D02*
G02I-800J0D01*
G37*
G36*
G01X1427433D02*
G02I-800J0D01*
G37*
G36*
G01X1431134Y1066323D02*
G02I-800J0D01*
G37*
G36*
G01Y1072701D02*
G02I-800J0D01*
G37*
G36*
G01X1427433Y1066323D02*
G02I-800J0D01*
G37*
G36*
G01Y1072701D02*
G02I-800J0D01*
G37*
G36*
G01X1436685Y1063134D02*
G02I-800J0D01*
G37*
G36*
G01Y1069512D02*
G02I-800J0D01*
G37*
G36*
G01X1431134Y1079079D02*
G02I-800J0D01*
G37*
G36*
G01X1427433D02*
G02I-800J0D01*
G37*
G36*
G01X1436685Y1075890D02*
G02I-800J0D01*
G37*
G36*
G01Y1088646D02*
G02I-800J0D01*
G37*
G36*
G01X1431134Y1085457D02*
G02I-800J0D01*
G37*
G36*
G01X1427433D02*
G02I-800J0D01*
G37*
G36*
G01X1436685Y1082268D02*
G02I-800J0D01*
G37*
G36*
G01Y1101402D02*
G02I-800J0D01*
G37*
G36*
G01Y1095024D02*
G02I-800J0D01*
G37*
G36*
G01X1431134Y1091835D02*
G02I-800J0D01*
G37*
G36*
G01Y1098213D02*
G02I-800J0D01*
G37*
G36*
G01X1427433Y1091835D02*
G02I-800J0D01*
G37*
G36*
G01Y1098213D02*
G02I-800J0D01*
G37*
G36*
G01X1440386Y1063134D02*
G02I-800J0D01*
G37*
G36*
G01Y1069512D02*
G02I-800J0D01*
G37*
G36*
G01X1451488Y1063134D02*
G02I-800J0D01*
G37*
G36*
G01Y1069512D02*
G02I-800J0D01*
G37*
G36*
G01X1447787Y1063134D02*
G02I-800J0D01*
G37*
G36*
G01Y1069512D02*
G02I-800J0D01*
G37*
G36*
G01X1440386Y1075890D02*
G02I-800J0D01*
G37*
G36*
G01X1451488D02*
G02I-800J0D01*
G37*
G36*
G01X1447787D02*
G02I-800J0D01*
G37*
G36*
G01X1440386Y1088646D02*
G02I-800J0D01*
G37*
G36*
G01X1451488Y1082268D02*
G02I-800J0D01*
G37*
G36*
G01X1447787D02*
G02I-800J0D01*
G37*
G36*
G01X1440386D02*
G02I-800J0D01*
G37*
G36*
G01X1451488Y1088646D02*
G02I-800J0D01*
G37*
G36*
G01X1447787D02*
G02I-800J0D01*
G37*
G36*
G01X1440386Y1101402D02*
G02I-800J0D01*
G37*
G36*
G01Y1095024D02*
G02I-800J0D01*
G37*
G36*
G01X1451488D02*
G02I-800J0D01*
G37*
G36*
G01X1447787D02*
G02I-800J0D01*
G37*
G36*
G01X1462591Y1063134D02*
G02I-800J0D01*
G37*
G36*
G01Y1069512D02*
G02I-800J0D01*
G37*
G36*
G01X1458890Y1063134D02*
G02I-800J0D01*
G37*
G36*
G01Y1069512D02*
G02I-800J0D01*
G37*
G36*
G01X1462591Y1075890D02*
G02I-800J0D01*
G37*
G36*
G01X1458890D02*
G02I-800J0D01*
G37*
G36*
G01X1462591Y1082268D02*
G02I-800J0D01*
G37*
G36*
G01Y1088646D02*
G02I-800J0D01*
G37*
G36*
G01X1458890Y1082268D02*
G02I-800J0D01*
G37*
G36*
G01Y1088646D02*
G02I-800J0D01*
G37*
G36*
G01X1462591Y1095024D02*
G02I-800J0D01*
G37*
G36*
G01X1458890D02*
G02I-800J0D01*
G37*
G36*
G01X1473693Y1063134D02*
G02I-800J0D01*
G37*
G36*
G01Y1069512D02*
G02I-800J0D01*
G37*
G36*
G01X1469992Y1063134D02*
G02I-800J0D01*
G37*
G36*
G01Y1069512D02*
G02I-800J0D01*
G37*
G36*
G01X1473693Y1075890D02*
G02I-800J0D01*
G37*
G36*
G01X1469992D02*
G02I-800J0D01*
G37*
G36*
G01X1473693Y1082268D02*
G02I-800J0D01*
G37*
G36*
G01Y1088646D02*
G02I-800J0D01*
G37*
G36*
G01X1469992Y1082268D02*
G02I-800J0D01*
G37*
G36*
G01Y1088646D02*
G02I-800J0D01*
G37*
G36*
G01X1473693Y1095024D02*
G02I-800J0D01*
G37*
G36*
G01X1469992D02*
G02I-800J0D01*
G37*
%LPD*%
G75*
G54D14*
X11782Y167036D03*
X18691Y167208D03*
X22409Y230021D03*
X19684Y237154D03*
X19230Y1446459D03*
X34281Y277798D03*
Y282916D03*
X35689Y298207D03*
X34281Y312916D03*
Y307798D03*
X35740Y363337D03*
X39320Y392269D03*
X28562Y517025D03*
X39967Y526709D03*
X30562Y533055D03*
X35952Y551605D03*
X35852Y670445D03*
Y667045D03*
Y681410D03*
Y678010D03*
Y692316D03*
Y703222D03*
Y688916D03*
Y699822D03*
X35010Y1289485D03*
X35040Y1292433D03*
X35080Y1298360D03*
X35040Y1295380D03*
X34584Y1307744D03*
Y1310244D03*
Y1312744D03*
Y1315244D03*
X33822Y1477075D03*
Y1486075D03*
Y1483075D03*
Y1480075D03*
X27205Y1501630D03*
Y1498230D03*
X38058Y1591405D03*
X35167Y1598896D03*
Y1626896D03*
Y1629405D03*
X32927Y1668587D03*
X42449Y282916D03*
Y277798D03*
X41492Y292892D03*
Y298207D03*
X47892Y295452D03*
X40500Y288500D03*
X55254Y292892D03*
X42449Y312916D03*
Y307798D03*
X51114Y360862D03*
X43020Y382942D03*
X40940Y387302D03*
X41933Y395652D03*
X47619Y419084D03*
X47618Y415184D03*
X49360Y428806D03*
X45960D03*
X49212Y451602D03*
X45812D03*
X47812Y517635D03*
X42810Y528070D03*
X39952Y551605D03*
X55099Y1298676D03*
Y1292676D03*
X51000Y1339200D03*
X42822Y1477075D03*
Y1483075D03*
Y1486075D03*
Y1480075D03*
X49265Y1490950D03*
Y1493450D03*
X49188Y1499181D03*
X41360Y1498971D03*
X41309Y1496173D03*
X38650Y1499326D03*
X49177Y1496272D03*
X48383Y1532395D03*
X48157Y1536296D03*
X49196Y1551294D03*
X48324Y1545961D03*
X48758Y1559295D03*
X48907Y1554972D03*
X47735Y1584885D03*
X47973Y1589981D03*
X43633Y1606896D03*
X46833Y1612596D03*
X43933Y1613818D03*
X47633Y1600896D03*
X53633Y1629896D03*
X41208Y1619896D03*
X42491Y1638656D03*
X40167Y1632405D03*
X40922Y1654869D03*
Y1658269D03*
X45052Y1684283D03*
X41679Y1673323D03*
Y1676723D03*
X65933Y28406D03*
Y48720D03*
X61157Y69340D03*
X64557D03*
X66650Y265316D03*
X57271Y272357D03*
X59780Y282866D03*
X62567Y295103D03*
X66289Y298207D03*
X59780Y312866D03*
X59322Y360702D03*
X63429D03*
X67681D03*
X53406Y402862D03*
X62812Y412100D03*
X62813Y416000D03*
X64821Y430806D03*
X60921D03*
X63540Y438802D03*
X64442Y510667D03*
X55682Y517595D03*
X62142Y539495D03*
X56192Y537795D03*
X63633Y528229D03*
X58365Y552365D03*
X53299D03*
X56627Y585818D03*
X59259Y737422D03*
X58751Y777718D03*
X61251D03*
Y775218D03*
X58751D03*
X61620Y768510D03*
X56440Y766180D03*
X58751Y790218D03*
Y792718D03*
Y780218D03*
X61251D03*
X56057Y792750D03*
X61251Y792718D03*
Y790218D03*
X56057Y790250D03*
Y787750D03*
X61251Y787718D03*
X56057Y785250D03*
X61251Y785218D03*
Y782718D03*
X56057Y782750D03*
X58751Y782718D03*
Y785218D03*
Y787718D03*
X57752Y808020D03*
X60547Y1276036D03*
X57747Y1270470D03*
X55099Y1289676D03*
X55043Y1295676D03*
X53700Y1342300D03*
X67010Y1476292D03*
X57822Y1477075D03*
X57777Y1490580D03*
X66710Y1485324D03*
Y1482324D03*
X66785Y1479175D03*
X57822Y1482791D03*
Y1485294D03*
Y1480075D03*
X64030Y1491595D03*
X57770Y1488047D03*
X66696Y1488010D03*
X64030Y1499095D03*
Y1501595D03*
Y1494095D03*
Y1496595D03*
X55370Y1551351D03*
X66229Y1549536D03*
X61605Y1546833D03*
X64275Y1546296D03*
X57811Y1598061D03*
X58633Y1587481D03*
X63633D03*
X61110Y1598146D03*
X58633Y1629896D03*
X64133Y1627896D03*
X64633Y1632896D03*
X64427Y1643496D03*
X64462Y1655624D03*
X61927Y1643496D03*
X65257Y1652941D03*
X56815Y1643431D03*
X62202Y1684579D03*
X66127Y1687362D03*
X72153Y75343D03*
X75553D03*
X79726Y145191D03*
X82026Y143491D03*
X71659Y149191D03*
X71779Y165194D03*
X71775Y153194D03*
X72462Y268223D03*
X77680Y378395D03*
Y380895D03*
X68020Y395222D03*
X80948Y525513D03*
Y521613D03*
X80318Y543313D03*
Y539413D03*
X80915Y767400D03*
X80784Y771366D03*
X68354Y1314097D03*
X80378Y1406676D03*
X83441Y1430500D03*
X81052Y1427410D03*
X81132Y1424195D03*
X79055Y1434000D03*
X73820Y1442893D03*
X81401Y1436105D03*
X73820Y1445945D03*
X73757Y1448500D03*
X81822Y1477075D03*
X77883Y1491440D03*
X80932D03*
X80852Y1488638D03*
X75245Y1491440D03*
X81822Y1480075D03*
Y1483075D03*
Y1486075D03*
X72396Y1491290D03*
X72390Y1499211D03*
X77883Y1499240D03*
X80833D03*
X77883Y1494040D03*
Y1496640D03*
X80932Y1494040D03*
Y1496640D03*
X75245Y1499240D03*
Y1494040D03*
Y1496640D03*
X72396Y1493890D03*
Y1496490D03*
X77920Y1538245D03*
X75796Y1545669D03*
X75396Y1542369D03*
X78796Y1545669D03*
X78096Y1542444D03*
X78372Y1556416D03*
Y1558916D03*
X78522Y1562641D03*
Y1565141D03*
Y1567888D03*
X78403Y1580311D03*
X81103D03*
X78522Y1570388D03*
X81468Y1570285D03*
X68133Y1587896D03*
X81006Y1593265D03*
X72660Y1587365D03*
X72375Y1604365D03*
X74133Y1610896D03*
X70567Y1625603D03*
X72255Y1616730D03*
X74134Y1621396D03*
X75380Y1627622D03*
X75764Y1636993D03*
X79164Y1636992D03*
X77427Y1644410D03*
X82127Y1687362D03*
X82500Y1698511D03*
Y1706511D03*
X82000Y1716331D03*
X82500Y1720331D03*
X82000Y1724331D03*
X94157Y75340D03*
X83157Y69340D03*
X97557Y75340D03*
X86557Y69340D03*
X92197Y143853D03*
X87137Y143663D03*
X93775Y197241D03*
Y212241D03*
Y207241D03*
Y202241D03*
X87520Y382219D03*
Y391391D03*
Y395865D03*
X90225Y610351D03*
X84057Y599372D03*
X84038Y602233D03*
X90225Y614351D03*
Y618351D03*
Y622351D03*
X94474Y766871D03*
X95790Y1278014D03*
X82953Y1307607D03*
X83023Y1311607D03*
X97546Y1385912D03*
X85736Y1391597D03*
X86827Y1404080D03*
X93000Y1417000D03*
Y1408000D03*
X93069Y1412500D03*
X85103Y1433051D03*
X93000Y1426000D03*
X97800Y1433000D03*
X93000Y1421500D03*
Y1444500D03*
Y1448500D03*
X84500Y1444500D03*
Y1448500D03*
X88722Y1476741D03*
X89092Y1491106D03*
X89042Y1488506D03*
X83991Y1491440D03*
X83892Y1488840D03*
X88722Y1479741D03*
Y1482741D03*
Y1485741D03*
X83892Y1499140D03*
X83991Y1494040D03*
Y1496540D03*
X84051Y1501690D03*
X83796Y1533746D03*
X83811Y1537296D03*
X91511Y1552296D03*
X93296Y1549142D03*
X97018Y1546331D03*
X88511Y1552296D03*
X83121Y1542294D03*
X94786Y1574205D03*
Y1576705D03*
X97486Y1574205D03*
Y1576705D03*
X83603Y1580311D03*
X84093Y1570285D03*
X90675Y1590783D03*
X96124Y1593458D03*
Y1595958D03*
X93424Y1593458D03*
X90675Y1593283D03*
X93424Y1595958D03*
X90675Y1595783D03*
X93537Y1598506D03*
X96237D03*
X90649Y1598507D03*
X84833Y1611896D03*
X90892Y1654749D03*
X85836Y1655143D03*
Y1658543D03*
X87891Y1671121D03*
Y1674521D03*
X90127Y1687362D03*
X96101Y1696469D03*
X82945Y1702511D03*
X95342Y1713741D03*
X96555Y1705508D03*
X95400Y1719741D03*
X95460Y1725241D03*
X105157Y69340D03*
X108557D03*
X101679Y151191D03*
X101675Y160694D03*
X100818Y165506D03*
Y168906D03*
X110616Y767400D03*
X110485Y771366D03*
X105165Y1300380D03*
Y1302880D03*
X107665D03*
Y1300380D03*
X102665Y1302880D03*
Y1300380D03*
X105165Y1305380D03*
X107665D03*
X102665D03*
Y1307880D03*
Y1310380D03*
Y1312880D03*
X105165Y1307880D03*
Y1310380D03*
Y1312880D03*
X107665D03*
Y1310380D03*
Y1307880D03*
X105165Y1315380D03*
X107665D03*
X105165Y1317880D03*
X107665D03*
X102665D03*
Y1315380D03*
X98101Y1369018D03*
Y1371559D03*
X104863Y1382593D03*
X99594Y1379933D03*
X104863Y1380085D03*
X112305Y1382130D03*
X108817Y1380530D03*
X111555Y1379562D03*
X101874Y1376408D03*
X111600Y1403100D03*
X113500Y1398600D03*
X110000Y1407425D03*
X110075Y1410500D03*
X101637Y1432938D03*
X102076Y1427833D03*
X101955Y1448660D03*
X101500Y1436000D03*
X102398Y1440000D03*
X113500Y1455600D03*
X112481Y1452424D03*
X112100Y1467500D03*
X103571Y1476485D03*
X103555Y1485128D03*
Y1479128D03*
Y1482128D03*
X109733Y1491367D03*
X110605Y1487896D03*
X104184Y1491292D03*
X106784D03*
X105453Y1487893D03*
X108053D03*
X102931Y1488097D03*
X101584Y1491292D03*
X106396Y1485113D03*
X108996D03*
X106371Y1482181D03*
X108971D03*
X107197Y1501756D03*
X109712Y1499196D03*
X104616Y1501811D03*
X107112Y1499196D03*
X109733Y1493967D03*
Y1496567D03*
X106784Y1493892D03*
Y1496492D03*
X101634D03*
X104512Y1499196D03*
X104184Y1496492D03*
Y1493892D03*
X101534Y1499244D03*
X101634Y1493992D03*
X101835Y1501863D03*
X109878Y1501879D03*
X102011Y1550242D03*
X99818Y1546296D03*
X111196Y1542569D03*
X111901Y1545543D03*
X112418Y1555680D03*
X112339Y1565015D03*
Y1562515D03*
X112418Y1558180D03*
X99986Y1574205D03*
Y1576705D03*
X108555Y1574657D03*
Y1577462D03*
X98824Y1593558D03*
X101524D03*
X98824Y1596058D03*
X101524D03*
X101637Y1598606D03*
X98937D03*
X112353Y1646612D03*
X110378Y1670313D03*
X99443Y1661931D03*
Y1658531D03*
X110378Y1674313D03*
X100443Y1684063D03*
Y1687463D03*
X107500Y1707450D03*
X116157Y75340D03*
X127153Y69343D03*
X119557Y75340D03*
X115016Y300281D03*
Y320715D03*
X118407Y526766D03*
X113042Y686285D03*
X113980Y717480D03*
X116480D03*
X118980D03*
X121480D03*
X123980D03*
X113980Y714980D03*
X116480D03*
X118980D03*
X121480D03*
X123980D03*
X116480Y722480D03*
X118980D03*
X121480D03*
X123980D03*
X113980Y719980D03*
X116480D03*
X118980D03*
X121480D03*
X123980D03*
X113980Y722480D03*
X124174Y766871D03*
X120965Y1307880D03*
Y1310380D03*
Y1312880D03*
X118465D03*
Y1310380D03*
Y1307880D03*
Y1300380D03*
X123465Y1302880D03*
Y1300380D03*
X120965Y1305380D03*
X118465D03*
X123465D03*
Y1307880D03*
Y1310380D03*
Y1312880D03*
X120965Y1300380D03*
Y1302880D03*
X118465D03*
X120965Y1315380D03*
X118465D03*
X120965Y1317880D03*
X118465D03*
X123465D03*
Y1315380D03*
X121207Y1363643D03*
X115321Y1372872D03*
X120181D03*
X117751D03*
X121241Y1367047D03*
Y1369947D03*
X127211Y1373177D03*
Y1378977D03*
X125111Y1377577D03*
X122945Y1379207D03*
X127211Y1376077D03*
X125011Y1374577D03*
X122945Y1376307D03*
X122050Y1403750D03*
X129200Y1401000D03*
X124700D03*
X126000Y1414000D03*
Y1418000D03*
X116700Y1415700D03*
Y1410500D03*
X120700Y1408100D03*
X116900Y1449000D03*
X113600Y1449100D03*
X116122Y1458000D03*
X119100Y1460300D03*
X124600Y1465100D03*
X121500Y1467400D03*
X113100Y1537346D03*
X114030Y1542419D03*
X114610Y1545543D03*
X121705Y1619460D03*
X114618Y1624541D03*
X117655Y1621766D03*
X118956Y1635244D03*
X124312Y1633488D03*
X126717Y1635893D03*
X126428Y1658587D03*
X126760Y1682383D03*
X123353Y1695941D03*
X127353Y1696062D03*
X127710Y1700166D03*
X127290Y1705666D03*
X125183Y1716741D03*
X127168Y1721695D03*
X129020Y1726741D03*
X138157Y75340D03*
X141557D03*
X130553Y69343D03*
X140360Y430160D03*
X141642Y488684D03*
Y494147D03*
X139980Y507420D03*
X139890Y503440D03*
X140471Y670445D03*
X131752Y668506D03*
X134902D03*
X140600Y683029D03*
X131752Y686074D03*
X134902D03*
X131960Y679290D03*
X140317Y767400D03*
Y771200D03*
X140265Y1307880D03*
Y1310380D03*
Y1312880D03*
X137765D03*
Y1310380D03*
Y1307880D03*
X135265Y1312880D03*
Y1310380D03*
Y1307880D03*
Y1305380D03*
X140265D03*
X137765D03*
X135265Y1300380D03*
Y1302880D03*
X140265Y1300380D03*
Y1302880D03*
X137765D03*
Y1300380D03*
X140265Y1315380D03*
X137765D03*
X135265D03*
Y1317880D03*
X140265D03*
X137765D03*
X130701Y1369018D03*
Y1371559D03*
X137463Y1382593D03*
X132194Y1379933D03*
X137463Y1380085D03*
X141417Y1380530D03*
X134474Y1376408D03*
X138000Y1400600D03*
X134800Y1408100D03*
X142000Y1414500D03*
X136000Y1432000D03*
X141500Y1433500D03*
Y1429500D03*
X139500Y1446000D03*
X133100Y1444100D03*
X138013Y1440487D03*
X141514Y1436500D03*
X128661Y1464000D03*
X139802Y1556133D03*
X129070Y1608338D03*
X137386Y1626412D03*
X135543Y1637055D03*
X132353Y1646612D03*
X136353D03*
X142465Y1662493D03*
X143000Y1701011D03*
X142293Y1705166D03*
X129493Y1711846D03*
X143000Y1709166D03*
X135722Y1715672D03*
X147920Y28261D03*
X148780Y48720D03*
X149153Y69343D03*
X152553D03*
X149231Y224204D03*
X148228Y216118D03*
X158380Y419760D03*
X147450Y423860D03*
X154770Y441830D03*
X147810Y475710D03*
X146982Y521997D03*
Y530997D03*
X159513Y674855D03*
X152822Y665500D03*
X153875Y766871D03*
X151065Y1307880D03*
Y1310380D03*
Y1312880D03*
X153565D03*
Y1310380D03*
Y1307880D03*
X156065Y1312880D03*
Y1310380D03*
Y1307880D03*
Y1305380D03*
X151065D03*
X153565D03*
X156065Y1300380D03*
Y1302880D03*
X151065Y1300380D03*
Y1302880D03*
X153565D03*
Y1300380D03*
X151065Y1315380D03*
X153565D03*
X156065D03*
Y1317880D03*
X151065D03*
X153565D03*
X152781Y1372872D03*
X150351D03*
X147921D03*
X153741Y1369977D03*
Y1367077D03*
X144905Y1382130D03*
X144155Y1379562D03*
X155545Y1379207D03*
Y1376307D03*
X145000Y1414425D03*
X150900Y1425500D03*
X154443Y1441195D03*
X156174Y1435396D03*
X156477Y1447733D03*
X154083Y1456007D03*
X148340Y1454674D03*
X154671Y1450019D03*
X154305Y1453101D03*
X159000Y1525480D03*
X155618Y1549331D03*
X155071Y1543604D03*
X152843Y1559146D03*
Y1562666D03*
X154945Y1624350D03*
X146453Y1614879D03*
X149171Y1616759D03*
X154945Y1627750D03*
X142576Y1640163D03*
X152353Y1646612D03*
X142576Y1643563D03*
X154111Y1663933D03*
X154010Y1676811D03*
X157410D03*
X143778Y1685087D03*
X147253Y1696343D03*
X155353Y1687843D03*
X159427Y1696652D03*
X152605Y1715941D03*
X149338Y1705603D03*
X156825Y1705510D03*
X146000Y1718241D03*
X146086Y1705603D03*
X145267Y1722241D03*
X152496Y1722941D03*
X146483Y1725636D03*
X155260Y1723682D03*
X161361Y75340D03*
X164761D03*
X162830Y396930D03*
X172120Y412350D03*
X172010Y474900D03*
X166760Y506880D03*
X166670Y502900D03*
X163372Y670863D03*
X172725Y667898D03*
X162482Y679319D03*
X161735Y684456D03*
X172725Y679230D03*
X169987Y767666D03*
Y771266D03*
X170265Y1312880D03*
Y1310380D03*
Y1307880D03*
X167765Y1312880D03*
Y1310380D03*
Y1307880D03*
Y1305380D03*
X170265D03*
X167765Y1300380D03*
Y1302880D03*
X170265D03*
Y1300380D03*
Y1315380D03*
X167765D03*
Y1317880D03*
X170265D03*
X163401Y1369018D03*
Y1371559D03*
X159811Y1373177D03*
X170163Y1382593D03*
X164894Y1379933D03*
X170163Y1380085D03*
X167174Y1376408D03*
X159811Y1378977D03*
Y1376077D03*
X157711Y1377577D03*
X157611Y1374577D03*
X163099Y1414400D03*
X162873Y1411611D03*
X163061Y1409048D03*
Y1406548D03*
X160684Y1441046D03*
X158704Y1439411D03*
X161210Y1443542D03*
X163271Y1441588D03*
X163148Y1474504D03*
X172180Y1490210D03*
X172070Y1495550D03*
X163460Y1491010D03*
X163320Y1494340D03*
X161188Y1510800D03*
X162188Y1518040D03*
X162531Y1523331D03*
Y1526731D03*
X167666Y1550751D03*
X165166D03*
X162666D03*
X170166D03*
X170230Y1542960D03*
X160150Y1553251D03*
Y1555751D03*
X162666D03*
X165166D03*
X167666D03*
X170166D03*
Y1553251D03*
X167666D03*
X165166D03*
X162666D03*
X170166Y1567621D03*
X167666D03*
X165166D03*
X162666D03*
X170166Y1565121D03*
X167666D03*
X165166D03*
X162666D03*
Y1562621D03*
X165166D03*
X167666D03*
X170166D03*
X162466Y1570121D03*
X164966D03*
X167466D03*
X169966D03*
X163735Y1635369D03*
Y1631969D03*
X157511Y1663933D03*
X165491Y1665582D03*
Y1662182D03*
X165336Y1675077D03*
Y1678477D03*
X162740Y1713172D03*
Y1704885D03*
X166467Y1720973D03*
X171925Y1717984D03*
X171945Y1730693D03*
X162740Y1723886D03*
X183357Y75343D03*
X172361Y69340D03*
X186757Y75343D03*
X175761Y69340D03*
X184930Y125502D03*
X181025Y159123D03*
X183890Y388180D03*
X174320Y395040D03*
X189290Y396730D03*
X177675Y419260D03*
X185160Y419220D03*
X181550Y441290D03*
X182500Y672500D03*
X172500Y684799D03*
X183576Y766871D03*
X183565Y1310380D03*
Y1312880D03*
X186065D03*
Y1310380D03*
Y1307880D03*
X172765D03*
Y1310380D03*
Y1312880D03*
X183565Y1307880D03*
Y1305380D03*
X186065D03*
X183565Y1300380D03*
Y1302880D03*
X186065D03*
Y1300380D03*
X172765Y1305380D03*
Y1300380D03*
Y1302880D03*
Y1315380D03*
X183565D03*
X186065D03*
X183565Y1317880D03*
X186065D03*
X172765D03*
X185481Y1372872D03*
X183051D03*
X180621D03*
X186481Y1370147D03*
Y1367247D03*
X177605Y1382130D03*
X174117Y1380530D03*
X176855Y1379562D03*
X185558Y1418560D03*
Y1416060D03*
X183058Y1418560D03*
Y1416060D03*
X173164Y1406397D03*
Y1408897D03*
X172976Y1411460D03*
X173202Y1414249D03*
X185558Y1421060D03*
Y1423560D03*
Y1426060D03*
X183058Y1421060D03*
Y1426060D03*
Y1423560D03*
Y1428560D03*
X185558D03*
X173490Y1542540D03*
X173050Y1555751D03*
Y1553251D03*
X178582Y1575390D03*
X181087Y1576135D03*
X178582Y1572490D03*
Y1569590D03*
X180292Y1582589D03*
X177792D03*
X177509Y1653825D03*
X177666Y1649223D03*
X183974Y1656804D03*
X183920Y1653973D03*
X184139Y1651088D03*
X180103Y1668921D03*
X177672Y1657538D03*
X183986Y1659548D03*
X182533Y1676854D03*
X185124Y1701851D03*
X185084Y1691988D03*
X179999Y1699156D03*
X185173Y1695138D03*
X178385Y1715441D03*
X183813Y1705404D03*
X178376Y1720559D03*
X185760Y1731666D03*
X194361Y69340D03*
X197761D03*
X204088Y138912D03*
X200577Y125502D03*
X190000Y143000D03*
X191264Y147768D03*
X193610Y153951D03*
X192592Y353072D03*
X188055Y731734D03*
X199718Y767400D03*
X197651Y769241D03*
X200365Y1312880D03*
Y1310380D03*
Y1307880D03*
Y1305380D03*
Y1300380D03*
Y1302880D03*
X188565Y1312880D03*
Y1310380D03*
Y1307880D03*
Y1305380D03*
Y1300380D03*
Y1302880D03*
X200365Y1315380D03*
Y1317880D03*
X188565Y1315380D03*
Y1317880D03*
X196301Y1369018D03*
Y1371559D03*
X192511Y1373177D03*
X197794Y1379933D03*
X200074Y1376408D03*
X188245Y1379207D03*
X190411Y1377577D03*
X192511Y1378977D03*
X190311Y1374577D03*
X188245Y1376307D03*
X192511Y1376077D03*
X200408Y1416249D03*
Y1418749D03*
X192983Y1417568D03*
X188058Y1416060D03*
Y1418560D03*
X190483Y1417568D03*
X197983D03*
X195483D03*
X188695Y1404813D03*
Y1407313D03*
X191995Y1404813D03*
Y1407313D03*
X194495Y1404813D03*
Y1407313D03*
X196995Y1404813D03*
Y1407313D03*
X199495Y1404813D03*
Y1407313D03*
X188507Y1409876D03*
X191807D03*
X194307D03*
X196807D03*
X199307D03*
X200558Y1421551D03*
X195483Y1420068D03*
X192983D03*
X195483Y1422568D03*
X197983D03*
X192983D03*
X188058Y1421060D03*
Y1423560D03*
X190483Y1420068D03*
Y1422568D03*
X197983Y1420068D03*
X188058Y1426060D03*
X193679Y1640052D03*
Y1643452D03*
X198698Y1662215D03*
X199747Y1675603D03*
X200424Y1686870D03*
X197780Y1696973D03*
X200478Y1701758D03*
X200448Y1690771D03*
X202076Y1717845D03*
X189760Y1713061D03*
X193274Y1709769D03*
X199843Y1709837D03*
X203510Y1712441D03*
X196763Y1710444D03*
X189760Y1723041D03*
Y1731564D03*
X194000Y1720551D03*
X203655Y1723000D03*
X198760Y1719991D03*
X216491Y69343D03*
X205495Y75340D03*
X208895D03*
X217687Y522453D03*
X214999Y585668D03*
X211254Y595145D03*
X208254D03*
X211009Y610001D03*
X208009D03*
X214202Y606943D03*
X208254Y603245D03*
X211254D03*
X214202Y609681D03*
X208326Y606918D03*
X211326D03*
X210199Y714074D03*
X206199D03*
X206254Y732537D03*
X206933Y737277D03*
X208818Y766871D03*
X205365Y1307880D03*
Y1310380D03*
Y1312880D03*
X202865D03*
Y1310380D03*
Y1307880D03*
X216165D03*
Y1310380D03*
Y1312880D03*
Y1305380D03*
Y1300380D03*
Y1302880D03*
X205365Y1305380D03*
X202865D03*
X205365Y1300380D03*
Y1302880D03*
X202865D03*
Y1300380D03*
X205365Y1315380D03*
X202865D03*
X216165D03*
Y1317880D03*
X205365D03*
X202865D03*
X213521Y1372872D03*
X215951D03*
X203063Y1382593D03*
Y1380085D03*
X210505Y1382130D03*
X207017Y1380530D03*
X209755Y1379562D03*
X205558Y1418560D03*
Y1416060D03*
X202945Y1415910D03*
Y1418410D03*
X208058Y1416060D03*
X208061Y1418605D03*
X205479Y1652130D03*
Y1648730D03*
X206788Y1660960D03*
X210833Y1660867D03*
X210217Y1668603D03*
X207807Y1681302D03*
Y1696409D03*
X211862Y1701100D03*
X212365Y1705403D03*
X211000Y1717675D03*
X229131Y26477D03*
X225731D03*
X229127Y50649D03*
X225727D03*
X227495Y75340D03*
X230895D03*
X219891Y69343D03*
X233284Y137195D03*
X221051Y153167D03*
X223687Y522453D03*
X229687D03*
X226599Y570970D03*
X217999Y585668D03*
X223999D03*
X220999D03*
X217202Y606943D03*
X220202D03*
X223202D03*
X223111Y603782D03*
X225895Y609691D03*
X228895D03*
X220111Y603782D03*
X217202Y609681D03*
X220202D03*
X223202D03*
X218024Y622385D03*
X221024D03*
X224024D03*
X227024D03*
X221024Y632385D03*
X218024D03*
X224024D03*
X227024D03*
X224157Y715915D03*
Y712915D03*
X229263Y765863D03*
X229275Y769292D03*
X218665Y1312880D03*
Y1310380D03*
Y1307880D03*
X221165Y1312880D03*
Y1310380D03*
Y1307880D03*
Y1305380D03*
X218665D03*
X221165Y1300380D03*
Y1302880D03*
X218665D03*
Y1300380D03*
Y1315380D03*
X221165D03*
Y1317880D03*
X218665D03*
X229101Y1369018D03*
Y1371559D03*
X218381Y1372872D03*
X219401Y1370067D03*
Y1367167D03*
X225411Y1373177D03*
X230594Y1379933D03*
X225411Y1378977D03*
Y1376077D03*
X221145Y1379207D03*
X223311Y1377577D03*
X223211Y1374577D03*
X221145Y1376307D03*
X238059Y26235D03*
X233335Y17665D03*
X235697Y21585D03*
X241306Y20325D03*
X246356Y26855D03*
X246506Y20365D03*
X242216Y39365D03*
X246216D03*
X238059Y37165D03*
X235697Y39755D03*
X248816Y48965D03*
X239816Y54365D03*
X248487Y68690D03*
X242920Y67915D03*
X238846Y72977D03*
X235186Y98067D03*
X234331Y103286D03*
X232529Y114830D03*
X238297Y121555D03*
X244818Y111546D03*
Y115546D03*
X235460Y115790D03*
X235186Y112022D03*
X238600Y130400D03*
X235147Y124435D03*
X243813Y132383D03*
X241271Y130719D03*
X234000Y148000D03*
X239988Y141986D03*
X236104Y151996D03*
X245486Y159705D03*
X234628Y166735D03*
X240413Y360867D03*
X233413D03*
X235913D03*
X243845Y656940D03*
X246045Y655540D03*
X243845Y651140D03*
Y654040D03*
X245945Y652540D03*
X232981Y743983D03*
X240200Y766300D03*
X246371Y772388D03*
X232965Y1297880D03*
X237965D03*
X235465D03*
Y1300380D03*
Y1302880D03*
X237965D03*
Y1300380D03*
X235465Y1305380D03*
X237965D03*
X232965Y1302880D03*
Y1300380D03*
Y1305380D03*
Y1307880D03*
Y1310380D03*
Y1312880D03*
X237965Y1307880D03*
Y1310380D03*
Y1312880D03*
X235465D03*
Y1310380D03*
Y1307880D03*
X237965Y1315380D03*
X235465D03*
X232965D03*
X246321Y1372872D03*
X235863Y1380085D03*
X243305Y1382130D03*
X239817Y1380530D03*
X242555Y1379562D03*
X235863Y1382593D03*
X232874Y1376408D03*
X255106Y16615D03*
X251106Y12615D03*
X250216Y39365D03*
X254046Y39425D03*
X259316Y48965D03*
X261016Y51565D03*
X252316Y48965D03*
X255816D03*
X254016Y51565D03*
X250516D03*
X257516D03*
X247893Y100546D03*
X248093Y92146D03*
X261416Y100665D03*
X253874Y111774D03*
X252800Y114800D03*
X256586Y138373D03*
X260596Y151065D03*
X248350Y165700D03*
X257252Y156730D03*
X258439Y214000D03*
X247859Y375389D03*
X250359D03*
X254859D03*
X247694Y378523D03*
X250194D03*
X254694D03*
X258751Y647987D03*
X262239Y649587D03*
X259501Y650555D03*
X255735Y657245D03*
X253305D03*
X250875D03*
X248111Y653810D03*
Y650910D03*
X250312Y663080D03*
Y660180D03*
X247587Y714760D03*
Y717260D03*
X252591Y714737D03*
Y717237D03*
X250091D03*
Y714737D03*
X247587Y712237D03*
X250087D03*
X252587D03*
X247587Y719760D03*
X252591Y719737D03*
X250091D03*
X247587Y724760D03*
X252587D03*
X250087D03*
X247587Y722260D03*
Y727260D03*
X250087Y729760D03*
X247587D03*
X250087Y727260D03*
X252587D03*
Y729760D03*
X252591Y722237D03*
X250091D03*
X254671Y776388D03*
X257071Y772770D03*
X260971Y777988D03*
X248765Y1297880D03*
X251265D03*
X248765Y1292880D03*
Y1295380D03*
X251265D03*
Y1292880D03*
X248765Y1307880D03*
Y1310380D03*
Y1312880D03*
X251265D03*
Y1310380D03*
Y1307880D03*
X248765Y1305380D03*
X251265D03*
X248765Y1300380D03*
Y1302880D03*
X251265D03*
Y1300380D03*
X248765Y1315380D03*
X251265D03*
Y1317880D03*
X248765D03*
X248751Y1372872D03*
X251181D03*
X252211Y1370232D03*
Y1367332D03*
X258211Y1373177D03*
X256111Y1377577D03*
X258211Y1378977D03*
X256011Y1374577D03*
X258211Y1376077D03*
X253945Y1379207D03*
Y1376307D03*
X261530Y1550300D03*
X275116Y28565D03*
X275896Y48875D03*
X266420Y39120D03*
X265365Y49171D03*
X263516Y51565D03*
X261816Y48965D03*
X263182Y73396D03*
X269860Y72741D03*
X262893Y77529D03*
Y80029D03*
X263316Y87665D03*
X275238Y83024D03*
X264916Y100665D03*
X268416D03*
X262916Y97965D03*
X266416D03*
X269916D03*
X273616Y96665D03*
X264293Y120972D03*
X269487Y121095D03*
X275793Y120248D03*
X266000Y125800D03*
X275793Y129595D03*
X266971Y140110D03*
X264574Y151206D03*
X276821Y140465D03*
X270178Y140322D03*
X262500Y161100D03*
X273500Y207500D03*
X266360Y203070D03*
X269925Y217700D03*
X274993Y522052D03*
X269568Y522366D03*
X266327Y522456D03*
X274096Y574698D03*
X273208Y588237D03*
X267601Y608378D03*
X271462Y650184D03*
X266193Y650032D03*
X272955Y658558D03*
X266193Y647524D03*
X269182Y653709D03*
X272955Y661099D03*
X276575Y685381D03*
Y688281D03*
Y691181D03*
X265891Y714737D03*
Y717237D03*
X263391D03*
Y714737D03*
X263387Y712237D03*
X265887D03*
X265891Y719737D03*
X263391D03*
X265787Y724760D03*
X263287D03*
X265787Y727260D03*
X263287D03*
X265787Y729760D03*
X263287D03*
X265787Y732260D03*
X263287D03*
X265891Y722237D03*
X263391D03*
X265787Y737260D03*
X263287D03*
X265787Y734760D03*
X263287D03*
X271161Y780588D03*
X268991Y783248D03*
X271245Y785474D03*
X274282Y786741D03*
X272054Y801112D03*
X270850Y797605D03*
X272165Y1256716D03*
X269665Y1259216D03*
X272165D03*
X269765Y1269234D03*
X272265D03*
X269765Y1261734D03*
Y1264234D03*
Y1266734D03*
X272265D03*
Y1264234D03*
Y1261734D03*
X267179Y1269273D03*
Y1266773D03*
Y1264273D03*
Y1261773D03*
Y1271773D03*
X269679D03*
X272179D03*
X262701Y1322872D03*
Y1325413D03*
X264194Y1333787D03*
X269463Y1333939D03*
X273417Y1334384D03*
X276155Y1333416D03*
X269463Y1336447D03*
X266474Y1330262D03*
X269829Y1521436D03*
X273597Y1519845D03*
X269144Y1511953D03*
X273474Y1516120D03*
Y1512220D03*
X269144Y1514453D03*
Y1516953D03*
X267322Y1519250D03*
X276624Y1516120D03*
Y1512220D03*
X276637Y1521436D03*
X274546Y1549295D03*
Y1546795D03*
X267297Y1546119D03*
X286996Y20365D03*
X290795Y28365D03*
X284228Y25935D03*
X280828D03*
X282716Y40020D03*
X290716D03*
X287988Y54893D03*
X291379Y55746D03*
X293157Y50525D03*
X284226Y50649D03*
X280826D03*
X278638Y83024D03*
X288553Y105006D03*
X285353D03*
X280853Y109906D03*
X282853Y115606D03*
X285853D03*
X280853Y107306D03*
X286996Y139865D03*
X283049Y139731D03*
X288000Y209000D03*
X290000Y222575D03*
X289163Y212503D03*
X278425Y230925D03*
X289393Y498960D03*
X278547Y523041D03*
X284018Y522300D03*
X287723Y548499D03*
X289421Y575098D03*
X291481Y682228D03*
X280841Y688051D03*
X278675Y686781D03*
X280841Y685151D03*
X288465Y691493D03*
X283605D03*
X286035D03*
X278775Y689781D03*
X283042Y697280D03*
Y694380D03*
X285317Y746478D03*
X282817D03*
X280317D03*
Y759110D03*
X285317D03*
X282817D03*
X285317Y761610D03*
X285321Y748978D03*
Y751478D03*
Y753978D03*
X282821D03*
Y751478D03*
Y748978D03*
X285321Y756478D03*
X282821D03*
X280317Y756610D03*
Y751610D03*
Y754110D03*
Y749110D03*
Y761610D03*
X282817D03*
X284035Y796850D03*
X285258Y799314D03*
X282323Y794867D03*
X281449Y809609D03*
X283987Y811342D03*
X285565Y1246716D03*
X288065D03*
X283065D03*
X288065Y1251716D03*
X285565D03*
X283065D03*
X288065Y1249216D03*
X285565D03*
X283065D03*
Y1254216D03*
X288065D03*
X285565D03*
X283065Y1269234D03*
X285565D03*
X283065Y1261734D03*
Y1264234D03*
Y1266734D03*
X285565D03*
Y1264234D03*
Y1261734D03*
X283065Y1256716D03*
X285565D03*
X288065D03*
X283065Y1259216D03*
X285565D03*
X288065D03*
Y1266716D03*
Y1264216D03*
Y1261716D03*
Y1269216D03*
X285479Y1271773D03*
X282979D03*
X287979D03*
X284781Y1326726D03*
X282351D03*
X279921D03*
X285891Y1320942D03*
Y1323842D03*
X289611Y1328431D03*
X276905Y1335984D03*
X289711Y1331431D03*
X287545Y1330161D03*
Y1333061D03*
X280088Y1509469D03*
X282588D03*
X279774Y1512220D03*
Y1516120D03*
X284024Y1514576D03*
X279499Y1519845D03*
X284024Y1512076D03*
X290593Y1523331D03*
Y1526731D03*
X291416Y1541795D03*
Y1549295D03*
Y1546795D03*
Y1544295D03*
X285586Y1551844D03*
X288004Y1551099D03*
X290509Y1551844D03*
X288004Y1548199D03*
X284014Y1538682D03*
X286514D03*
X284546Y1549295D03*
Y1546795D03*
Y1541795D03*
Y1544295D03*
X287046D03*
Y1541795D03*
X277046Y1546795D03*
Y1549295D03*
X282046D03*
Y1546795D03*
Y1544295D03*
X279546Y1549295D03*
Y1546795D03*
X282046Y1541795D03*
X300230Y14820D03*
X302606Y26365D03*
X292056Y24475D03*
X295516Y26365D03*
X300244Y28365D03*
X299496Y22865D03*
X304923Y24657D03*
X304968Y28365D03*
X303252Y38199D03*
X298716Y40020D03*
X296337Y55855D03*
X301306Y52485D03*
X298542Y51088D03*
X303711Y50860D03*
X295755Y72800D03*
X301107Y75676D03*
X305820Y73693D03*
X303852Y65042D03*
X306470Y65160D03*
X301780Y82900D03*
X299002Y88700D03*
X307816Y95727D03*
X301179Y112806D03*
Y110006D03*
Y107106D03*
X296478Y149203D03*
X296474Y158706D03*
X292811Y213242D03*
X296283Y242391D03*
X306528Y256528D03*
X297815Y580384D03*
X294299Y577188D03*
X302130Y584160D03*
X304192Y684425D03*
X298923Y684273D03*
X294969Y683828D03*
X292231Y684796D03*
X298923Y681765D03*
X301912Y687950D03*
X305685Y695340D03*
Y692799D03*
X298617Y746478D03*
X296117D03*
X301117D03*
X298621Y753978D03*
X296121D03*
Y751478D03*
Y748978D03*
X298621Y756478D03*
X296121D03*
X301121Y748996D03*
Y751496D03*
Y753996D03*
Y756496D03*
X296117Y759110D03*
Y761610D03*
X301117Y759110D03*
X298617D03*
X301117Y761610D03*
X298617D03*
X298621Y748978D03*
Y751478D03*
X301117Y766610D03*
X296117D03*
Y764110D03*
X301117Y771610D03*
X298617D03*
Y769110D03*
X301117D03*
X296117Y771610D03*
Y769110D03*
X298617Y766610D03*
Y764110D03*
X301117D03*
X305061Y1254131D03*
X300061D03*
X302561D03*
X305061Y1249131D03*
Y1251631D03*
X300061D03*
X302561D03*
X300061Y1249131D03*
X302561D03*
X305061Y1246631D03*
X300061D03*
X302561D03*
X302661Y1269149D03*
X305161D03*
X302661Y1261649D03*
Y1264149D03*
Y1266649D03*
X305161D03*
Y1264149D03*
Y1261649D03*
X300061Y1269131D03*
Y1266631D03*
X305061Y1259131D03*
Y1256631D03*
X300061D03*
Y1259131D03*
Y1261631D03*
Y1264131D03*
X302561Y1256631D03*
Y1259131D03*
X305075Y1271688D03*
X302575D03*
X300075D03*
X295597Y1322844D03*
Y1325385D03*
X291811Y1327031D03*
X297090Y1333759D03*
X302359Y1333911D03*
X306313Y1334356D03*
X302359Y1336419D03*
X299370Y1330234D03*
X291811Y1332831D03*
Y1329931D03*
X294725Y1381612D03*
X294533Y1384401D03*
X305204Y1381461D03*
X305012Y1384250D03*
X294684Y1387040D03*
X305163Y1386889D03*
X294683Y1390281D03*
X305163Y1389678D03*
X295042Y1530596D03*
X296416Y1549295D03*
X293916D03*
Y1546795D03*
X296416D03*
Y1544295D03*
X293916D03*
X296416Y1541795D03*
X293916D03*
X298916D03*
Y1549295D03*
Y1546795D03*
Y1544295D03*
X303041Y1544299D03*
X297323Y1657172D03*
Y1653772D03*
X310396Y50365D03*
X306566Y50225D03*
X323036Y73125D03*
X310455Y75895D03*
X320190Y77648D03*
X314653Y71806D03*
Y68906D03*
X312410Y89060D03*
X322871Y84321D03*
X316982Y89003D03*
X311053Y112806D03*
Y110006D03*
Y107106D03*
X323646Y147120D03*
Y152120D03*
X308240Y148100D03*
X317472Y222262D03*
Y225217D03*
X319970Y228167D03*
X320095Y231810D03*
X319075Y260075D03*
X311749Y440921D03*
X314780Y545716D03*
X322955Y556148D03*
X310445Y700931D03*
X312611Y702301D03*
X321235Y711636D03*
X316375D03*
X318805D03*
X311545Y709931D03*
X310445Y703931D03*
X311445Y706931D03*
X313611Y708201D03*
Y705301D03*
X315912Y717400D03*
Y714500D03*
X313087Y769160D03*
Y771660D03*
Y774160D03*
Y776660D03*
X318091Y769128D03*
Y771628D03*
Y774128D03*
X315591D03*
Y771628D03*
Y769128D03*
X318091Y776628D03*
X315591D03*
X313087Y766628D03*
X315587D03*
X318087D03*
Y791660D03*
X313087D03*
X315587D03*
X318087Y789160D03*
X313087D03*
X315587D03*
Y779160D03*
X313087Y784160D03*
X315587D03*
X313087Y786660D03*
X315587D03*
X313087Y781660D03*
X315587D03*
X313087Y779160D03*
X318087Y786660D03*
Y784160D03*
Y779160D03*
Y781660D03*
X313284Y1218522D03*
Y1215122D03*
X318461Y1254131D03*
X320961D03*
X315961D03*
Y1249131D03*
X318461D03*
X320961D03*
X315961Y1251631D03*
X318461D03*
X320961D03*
X315961Y1246631D03*
X318461D03*
X320961D03*
X315961Y1269149D03*
X318461D03*
X315961Y1261649D03*
Y1264149D03*
Y1266649D03*
X318461D03*
Y1264149D03*
Y1261649D03*
X320961Y1269131D03*
Y1256631D03*
Y1259131D03*
Y1261631D03*
X318461Y1256631D03*
Y1259131D03*
X320961Y1264131D03*
Y1266631D03*
X315961Y1256631D03*
Y1259131D03*
X320875Y1271688D03*
X315875D03*
X318375D03*
X312817Y1326698D03*
X315247D03*
X317677D03*
X318811Y1320902D03*
Y1323802D03*
X309801Y1335956D03*
X309051Y1333388D03*
X320441Y1330133D03*
Y1333033D03*
X307255Y1643750D03*
Y1647150D03*
X323113Y76941D03*
X334339Y162580D03*
X323646Y160120D03*
Y156120D03*
X331780Y182900D03*
X336000Y284000D03*
X324406Y367744D03*
X325816Y543012D03*
X324647Y566086D03*
X334031Y613498D03*
Y610498D03*
X331391D03*
Y613498D03*
X333502Y600019D03*
Y603019D03*
X330109Y602883D03*
Y605883D03*
X334031Y619398D03*
Y616498D03*
X331391D03*
Y619398D03*
X324251Y702378D03*
X331693Y701915D03*
Y704423D03*
X327739Y703978D03*
X325001Y704946D03*
X334682Y708100D03*
X331391Y769128D03*
Y771628D03*
Y774128D03*
X328891D03*
Y771628D03*
Y769128D03*
X331391Y776628D03*
X328891D03*
X333887Y766628D03*
X328887D03*
X331387D03*
X333891Y776646D03*
Y774146D03*
Y771646D03*
Y769146D03*
X333887Y791660D03*
X328887D03*
X331387D03*
X333887Y789160D03*
X328887D03*
X331387D03*
X333887Y779160D03*
Y781660D03*
X331387Y779160D03*
X328887D03*
Y781660D03*
X331387D03*
X333887Y786660D03*
X328887D03*
X331387D03*
X333887Y784160D03*
X328887D03*
X331387D03*
X335465Y1246631D03*
X332965D03*
X335465Y1249131D03*
X332965D03*
X335465Y1251631D03*
X332965D03*
X335465Y1254131D03*
X332965D03*
X335465Y1259131D03*
Y1256631D03*
X332965Y1259131D03*
Y1256631D03*
X335565Y1269149D03*
Y1261649D03*
Y1264149D03*
Y1266649D03*
X332961Y1269188D03*
Y1266688D03*
Y1261688D03*
Y1264188D03*
Y1271688D03*
X335461D03*
X328501Y1322787D03*
Y1325328D03*
X324707Y1327003D03*
X322507Y1328403D03*
X329994Y1333702D03*
X335263Y1333854D03*
Y1336362D03*
X332274Y1330177D03*
X324707Y1332803D03*
X322607Y1331403D03*
X324707Y1329903D03*
X334038Y1373469D03*
X334230Y1370680D03*
X323559Y1373620D03*
X323751Y1370831D03*
X334189Y1376108D03*
X323710Y1376259D03*
X334189Y1378897D03*
X323709Y1379500D03*
X341082Y56308D03*
X340436Y120555D03*
X343446Y131170D03*
X338244Y192264D03*
X344984Y199299D03*
X344106Y222659D03*
X348107Y220420D03*
X341895Y233980D03*
X348645Y229180D03*
X352000Y230643D03*
Y235643D03*
X344034Y282609D03*
X348890Y409120D03*
Y411620D03*
X340337Y496462D03*
X346751Y515376D03*
X351157Y550415D03*
X350566Y541882D03*
X351018Y554896D03*
X351157Y566936D03*
X345521Y564388D03*
X349397Y564459D03*
X351157Y570415D03*
X341500Y574500D03*
X342500Y582500D03*
Y578500D03*
X338420Y574500D03*
X351157Y590415D03*
Y586415D03*
X337031Y607498D03*
Y613498D03*
Y610498D03*
X346031Y607498D03*
X343031D03*
X349031D03*
X346031Y610498D03*
X343031D03*
X349031D03*
X340031Y607498D03*
Y610498D03*
Y613498D03*
X346031Y604498D03*
X343031D03*
X349031D03*
X340031D03*
X343691Y614018D03*
X346191D03*
X348691D03*
X343721Y618348D03*
X346221D03*
X348721D03*
X351191Y614018D03*
X351221Y618348D03*
X340031Y619398D03*
Y616498D03*
X337031Y619398D03*
Y616498D03*
X342675Y640994D03*
X345175D03*
X347675D03*
X350175D03*
X342675Y643494D03*
X345175D03*
X347675D03*
X350175D03*
X342595Y646054D03*
X345095D03*
X347595D03*
X350095D03*
X336962Y704575D03*
X338455Y715490D03*
Y712949D03*
X349435Y711368D03*
X346671Y705033D03*
X344505Y706663D03*
X346671Y707933D03*
X344605Y709663D03*
X342405Y705263D03*
Y708163D03*
Y711063D03*
X348395Y717060D03*
Y714160D03*
X346051Y769058D03*
Y771558D03*
Y774058D03*
Y776558D03*
X351151Y769040D03*
Y771540D03*
Y774040D03*
X348651D03*
Y771540D03*
Y769040D03*
X351151Y776540D03*
X348651D03*
X351147Y766540D03*
X348647D03*
X346147D03*
X346051Y791558D03*
X348551D03*
X351051D03*
X346051Y789058D03*
X348551D03*
X346051Y784058D03*
X348551D03*
X346051Y786558D03*
X348551D03*
X346051Y779058D03*
X348551D03*
X346051Y781558D03*
X348551D03*
X351051Y789058D03*
Y784058D03*
Y786558D03*
Y779058D03*
Y781558D03*
X347107Y1174343D03*
X339278Y1192112D03*
X336778D03*
X347885Y1206426D03*
X339532Y1218605D03*
X349938Y1214563D03*
X337965Y1251631D03*
Y1249131D03*
Y1254131D03*
X348865Y1246631D03*
Y1251631D03*
Y1249131D03*
Y1254131D03*
X337965Y1246631D03*
X348865Y1269149D03*
Y1261649D03*
Y1264149D03*
Y1266649D03*
X338065Y1269149D03*
Y1266649D03*
Y1264149D03*
Y1261649D03*
X337965Y1256631D03*
Y1259131D03*
X348865D03*
Y1256631D03*
X337961Y1271688D03*
X348861D03*
X348151Y1326641D03*
X350581D03*
X345721D03*
X342705Y1335899D03*
X339217Y1334299D03*
X341955Y1333331D03*
X346464Y1380102D03*
X343964D03*
X348964D03*
Y1387602D03*
Y1385102D03*
Y1382602D03*
X343964Y1385102D03*
Y1387602D03*
X346464Y1385102D03*
Y1387602D03*
X343964Y1382602D03*
X346464D03*
X348964Y1390102D03*
X343964D03*
Y1392602D03*
X346464D03*
Y1390102D03*
X343777Y1395166D03*
X346302Y1395242D03*
X348828Y1395392D03*
X349032Y1392675D03*
X361744Y120713D03*
X363621Y127665D03*
X361171Y223114D03*
X358618Y223129D03*
X361171Y220614D03*
X358671D03*
X355910Y223847D03*
X365739Y221871D03*
X365559Y238896D03*
X357925Y304082D03*
X351390Y409120D03*
X353890D03*
Y411620D03*
X351390D03*
X365852Y516466D03*
X365071Y551038D03*
X355100Y544390D03*
X362200Y566750D03*
X364047Y556773D03*
X359200Y566990D03*
X360261Y561044D03*
X359657Y570702D03*
X359157Y574415D03*
X365158Y597546D03*
Y593580D03*
X352031Y607498D03*
Y610498D03*
X355031Y607498D03*
Y613498D03*
Y610498D03*
X352031Y604498D03*
X355031D03*
X361031Y607498D03*
Y613498D03*
Y610498D03*
X358031Y607498D03*
Y613498D03*
Y610498D03*
Y604498D03*
Y619398D03*
Y616498D03*
X355031Y619398D03*
Y616498D03*
X361031Y619398D03*
Y616498D03*
X352675Y640994D03*
Y643494D03*
X355275Y641034D03*
Y643534D03*
X355195Y646094D03*
X352595Y646054D03*
X357311Y702110D03*
X364753Y701647D03*
Y704155D03*
X360799Y703710D03*
X358061Y704678D03*
X351865Y711368D03*
X354295D03*
X364451Y769040D03*
Y771540D03*
Y774040D03*
X361951D03*
Y771540D03*
Y769040D03*
X364451Y776540D03*
X361951D03*
X364447Y766540D03*
X361947D03*
X364451Y791558D03*
X361951D03*
X364451Y786558D03*
Y789058D03*
X361951D03*
Y786558D03*
X364451Y784058D03*
X361951Y781558D03*
X364451Y779058D03*
Y781558D03*
X361951Y779058D03*
Y784058D03*
X361671Y803588D03*
X356671D03*
X351671D03*
X363313Y812088D03*
X359813Y812188D03*
X356313D03*
X352813D03*
X356535Y849708D03*
X364897Y852564D03*
X364821Y861852D03*
X357400Y855982D03*
X356895Y859791D03*
X353281Y859620D03*
X363236Y1199632D03*
X361922Y1206891D03*
X357271Y1208988D03*
X351413Y1210052D03*
X365461Y1254188D03*
Y1251688D03*
Y1249188D03*
Y1246688D03*
X351365Y1246631D03*
X353865D03*
Y1251631D03*
X351365D03*
X353865Y1249131D03*
X351365D03*
X353865Y1254131D03*
X351365D03*
Y1269149D03*
Y1266649D03*
Y1264149D03*
Y1261649D03*
X365461Y1256688D03*
Y1259188D03*
X353865Y1266631D03*
Y1264131D03*
Y1261631D03*
Y1269131D03*
X351365Y1259131D03*
Y1256631D03*
X353865Y1259131D03*
Y1256631D03*
X365561Y1269288D03*
Y1264288D03*
Y1266788D03*
Y1261788D03*
Y1271788D03*
X351361Y1271688D03*
X353861D03*
X361301Y1322987D03*
Y1325528D03*
X351651Y1320942D03*
Y1323842D03*
X357611Y1326946D03*
X355411Y1328346D03*
X362794Y1333902D03*
X365074Y1330377D03*
X353345Y1332976D03*
X357611Y1329846D03*
X353345Y1330076D03*
X355511Y1331346D03*
X357611Y1332746D03*
X356764Y1359296D03*
X354264D03*
X364764D03*
X362264D03*
X359764D03*
X351632Y1359203D03*
X351923Y1364724D03*
X354423D03*
X356923D03*
X359423D03*
X362223D03*
X364723D03*
X351772Y1362085D03*
X354272D03*
X356772D03*
X359272D03*
X362072D03*
X364572D03*
X363964Y1385102D03*
X356464Y1380102D03*
X358964D03*
X361464D03*
X353964D03*
X351464D03*
X363964D03*
Y1382602D03*
X351464Y1385102D03*
X353964D03*
X361464D03*
X356464D03*
X358964D03*
X351464Y1382602D03*
X361464D03*
X358964D03*
X356464D03*
X353964D03*
X352067Y1387665D03*
X354567D03*
X357067D03*
X359567D03*
X363190Y1387527D03*
X365979Y1387641D03*
X352332Y1391886D03*
X354832D03*
X357332D03*
X359832D03*
X363191Y1390292D03*
Y1392792D03*
X365980Y1392906D03*
Y1390406D03*
X363003Y1395393D03*
X365792Y1395507D03*
X352313Y1395223D03*
X359859D03*
X357208D03*
X365493Y1655107D03*
X370888Y155250D03*
X377118Y222229D03*
X380012Y239615D03*
X370327Y228951D03*
X370352Y235455D03*
X366671Y297114D03*
X369171D03*
X369671Y292114D03*
Y294614D03*
X380935Y443386D03*
X375935D03*
X378435D03*
X382184Y466351D03*
X378976Y479226D03*
X379633Y493942D03*
X371962Y524954D03*
X368371Y553038D03*
X371971Y553138D03*
X375410Y552254D03*
X377502Y554193D03*
X380157Y553090D03*
X375271Y542191D03*
X379114Y544866D03*
X368647Y550422D03*
X370271Y555038D03*
X379689Y586040D03*
X368798Y587938D03*
X369271Y600138D03*
X373477Y593338D03*
X378577Y593026D03*
X377577Y590126D03*
X370022Y704307D03*
X371515Y715222D03*
Y712681D03*
X367742Y707832D03*
X379711Y708001D03*
Y705101D03*
X375445Y708231D03*
X377545Y706731D03*
X375445Y705331D03*
X377645Y709731D03*
X375445Y711131D03*
X366951Y769058D03*
Y771558D03*
Y774058D03*
Y776558D03*
X379187Y766428D03*
Y768960D03*
Y771460D03*
Y773960D03*
Y776460D03*
X366947Y766540D03*
X366951Y781558D03*
Y786558D03*
Y789058D03*
Y784058D03*
X379187Y786460D03*
Y783960D03*
Y788960D03*
Y778960D03*
Y781460D03*
X366951Y791558D03*
X379187Y791460D03*
X366951Y779058D03*
X376671Y803588D03*
X371671D03*
X366671D03*
X366864Y857274D03*
X369626Y860717D03*
X370316Y1204673D03*
X367931Y1196981D03*
X376271Y1207488D03*
X380718Y1221906D03*
X379223Y1219527D03*
X372126Y1214455D03*
X368726D03*
X367961Y1254188D03*
Y1251688D03*
Y1249188D03*
Y1246688D03*
X370461Y1254188D03*
Y1249188D03*
Y1251688D03*
Y1246688D03*
X367961Y1256688D03*
Y1259188D03*
X370461D03*
Y1256688D03*
X368061Y1269206D03*
X370561D03*
X368061Y1261706D03*
Y1264206D03*
Y1266706D03*
X370561D03*
Y1264206D03*
Y1261706D03*
Y1271788D03*
X368061D03*
X380951Y1326841D03*
X378521D03*
X368063Y1334054D03*
X375505Y1336099D03*
X372017Y1334499D03*
X374755Y1333531D03*
X368063Y1336562D03*
X368964Y1382602D03*
Y1385102D03*
X366464D03*
X368964Y1380102D03*
X366464D03*
Y1382602D03*
X368542Y1387639D03*
X368543Y1390404D03*
Y1392904D03*
X368355Y1395505D03*
X374432Y1582600D03*
X375050Y1639400D03*
X371823Y1644516D03*
X370533Y1658605D03*
X374962Y1648511D03*
X372953Y1653197D03*
X373330Y1668539D03*
X370369Y1661817D03*
X372449Y1680520D03*
X372395Y1677449D03*
X395048Y121178D03*
X384375Y147365D03*
X386350Y138980D03*
X395590Y147010D03*
X391310Y227871D03*
X389912Y280345D03*
X390881Y284156D03*
X395053Y318125D03*
X383525Y443386D03*
X389784Y476070D03*
X384827Y507057D03*
X397184Y507101D03*
X382184D03*
X388985Y554870D03*
X383071Y553738D03*
X382705Y546433D03*
X395171Y559463D03*
X395669Y563328D03*
X385318Y555238D03*
X394168Y568482D03*
X395157Y573815D03*
X393481Y571239D03*
X387103Y584506D03*
X392471Y596988D03*
X391021Y588788D03*
X390351Y702178D03*
X393839Y703778D03*
X391101Y704746D03*
X382475Y711436D03*
X387335D03*
X384905D03*
X381812Y717060D03*
Y714160D03*
X394987Y766428D03*
X381687D03*
X384187D03*
X394991Y773928D03*
Y771428D03*
Y768928D03*
Y776428D03*
X384191Y768928D03*
Y771428D03*
Y773928D03*
X381691D03*
Y771428D03*
Y768928D03*
X384191Y776428D03*
X381691D03*
X381687Y791460D03*
X384187D03*
X394987Y784060D03*
Y779060D03*
Y781560D03*
Y789060D03*
Y786560D03*
X381687Y778960D03*
Y786460D03*
Y783960D03*
Y788960D03*
Y781460D03*
X384187Y788960D03*
Y786460D03*
Y783960D03*
Y778960D03*
Y781460D03*
X386381Y1015474D03*
X393861D03*
X386381Y1022560D03*
Y1019017D03*
X393861Y1022560D03*
Y1019017D03*
X390974Y1222849D03*
Y1219449D03*
X388630Y1236747D03*
X381361Y1254188D03*
Y1249188D03*
Y1251688D03*
Y1246688D03*
X383861Y1254188D03*
X386361D03*
X383861Y1249188D03*
X386361D03*
X383861Y1251688D03*
X386361D03*
X383861Y1246688D03*
X386361D03*
X388630Y1240147D03*
X381361Y1269206D03*
X383861D03*
X381361Y1261706D03*
Y1264206D03*
Y1266706D03*
X383861D03*
Y1264206D03*
Y1261706D03*
X381361Y1256688D03*
Y1259188D03*
X386361Y1256688D03*
Y1259188D03*
X383861Y1256688D03*
Y1259188D03*
X386361Y1269288D03*
Y1261788D03*
Y1266788D03*
Y1264288D03*
X381361Y1271788D03*
X386361D03*
X383861D03*
X383381Y1326841D03*
X384481Y1321192D03*
Y1324092D03*
X388211Y1328546D03*
X393883Y1342318D03*
X388311Y1331546D03*
X386145Y1333176D03*
Y1330276D03*
X386611Y1336056D03*
X388771Y1337546D03*
Y1334546D03*
X395376Y1353233D03*
X393883Y1344859D03*
X395384Y1519250D03*
X395359Y1546519D03*
X389290Y1561250D03*
X387939Y1565534D03*
X389276Y1568413D03*
X391526Y1582373D03*
X394521Y1575891D03*
X388784Y1581801D03*
X393005Y1592304D03*
X381711Y1593842D03*
X381607Y1590393D03*
X388445Y1585898D03*
X389333Y1598816D03*
X387805Y1617302D03*
Y1614802D03*
X394824Y1629713D03*
X394000Y1621500D03*
X389824Y1629713D03*
X389000Y1621500D03*
X384824Y1629713D03*
X381350Y1649000D03*
Y1642900D03*
Y1645800D03*
X382115Y1661545D03*
X387324Y1680495D03*
X392324D03*
X382642Y1680979D03*
X385068Y1683502D03*
X410500Y104883D03*
X410400Y107383D03*
X399264Y121144D03*
X403141Y148300D03*
X410678Y159140D03*
X408603Y152278D03*
X411299Y212096D03*
X400000Y220300D03*
X411940Y240501D03*
X410000Y304000D03*
X402184Y466469D03*
X410984Y496649D03*
X406184Y507900D03*
X403657Y546915D03*
X408550Y557850D03*
X404871Y567338D03*
X403381Y573516D03*
X410111Y572608D03*
X407543Y577415D03*
Y580490D03*
X408445Y687531D03*
X397793Y701715D03*
X410645Y691931D03*
X410545Y688931D03*
X408445Y690431D03*
Y693331D03*
X403062Y704375D03*
X397793Y704223D03*
X404555Y715290D03*
Y712749D03*
X400782Y707900D03*
X399991Y776560D03*
X397491Y768928D03*
Y771428D03*
Y773928D03*
Y776428D03*
X397487Y766428D03*
X399991Y771560D03*
Y769060D03*
X399987Y766428D03*
X399991Y774060D03*
X397487Y779060D03*
Y781560D03*
Y786560D03*
Y784060D03*
X399991D03*
Y779060D03*
Y781560D03*
X401341Y1015474D03*
Y1019017D03*
Y1022560D03*
X403347Y1266162D03*
Y1268662D03*
X400847Y1266162D03*
X398347D03*
X400847Y1268662D03*
X398347D03*
X403347Y1271162D03*
Y1273662D03*
X400847Y1271162D03*
X398347D03*
X400847Y1273662D03*
X398347D03*
X403347Y1276162D03*
Y1278662D03*
X400847D03*
Y1276162D03*
X398347Y1278662D03*
Y1276162D03*
X398447Y1281262D03*
Y1283762D03*
X400947Y1281180D03*
Y1283680D03*
X403447D03*
Y1281180D03*
X400947Y1288680D03*
X403447D03*
X400947Y1286180D03*
X403447D03*
X398447Y1286262D03*
Y1288762D03*
X398461Y1291319D03*
X403461D03*
X400961D03*
X400645Y1353385D03*
X408087Y1355430D03*
X404599Y1353830D03*
X407337Y1352862D03*
X400645Y1355893D03*
X397656Y1349708D03*
X401536Y1516120D03*
Y1512220D03*
X397206Y1516953D03*
Y1511953D03*
Y1514453D03*
X397891Y1521436D03*
X401659Y1519845D03*
X404686Y1516120D03*
Y1512220D03*
X410650Y1509469D03*
X408150D03*
X407836Y1512220D03*
Y1516120D03*
X407561Y1519845D03*
X404699Y1521436D03*
X410108Y1535680D03*
X408895Y1553644D03*
X405331Y1548928D03*
X410851Y1557434D03*
X407198Y1564990D03*
X401249Y1564422D03*
X405758Y1557900D03*
X402912Y1558011D03*
X396452Y1577738D03*
X403163Y1579357D03*
X403004Y1582457D03*
X408925Y1573805D03*
Y1576805D03*
X404669Y1594317D03*
X403837Y1609056D03*
Y1612456D03*
X399447Y1612609D03*
X399801Y1606376D03*
X406697Y1604207D03*
X408856Y1623435D03*
X400380Y1621500D03*
X405436Y1620268D03*
X406343Y1613847D03*
X405747Y1623350D03*
X404640Y1637425D03*
X397822Y1629615D03*
X409552Y1633606D03*
X405342Y1628611D03*
X404661Y1634139D03*
X412000Y1647177D03*
X403844Y1665769D03*
X405000Y1675000D03*
X397324Y1680495D03*
X409000Y1683500D03*
X424975Y54762D03*
X417025D03*
X416549Y66365D03*
Y71665D03*
X427300Y71300D03*
X419900Y96620D03*
X414100D03*
X424084Y110839D03*
X417486Y124179D03*
Y127579D03*
X424086Y123023D03*
X422890Y136700D03*
X424086Y133265D03*
X412370Y188210D03*
X411610Y223140D03*
X424815Y217646D03*
X422936Y223501D03*
X419299Y212096D03*
X423299D03*
X420115Y230323D03*
Y240501D03*
Y235442D03*
Y226323D03*
X411940Y235442D03*
X412715Y251165D03*
Y258165D03*
Y266165D03*
X419617Y308000D03*
X424151Y453174D03*
X415984Y466392D03*
X424784Y496572D03*
X419984Y508000D03*
X411500Y510800D03*
X412771Y524820D03*
X414402Y544690D03*
X423351Y684378D03*
X424101Y686946D03*
X412711Y687301D03*
X420335Y693636D03*
X415475D03*
X417905D03*
X412711Y690201D03*
X414712Y699440D03*
Y696540D03*
X420158Y748643D03*
X415158Y756175D03*
Y751175D03*
Y753675D03*
X417658Y748643D03*
X415158D03*
Y761175D03*
X420158D03*
X417658D03*
X415158Y758675D03*
X420162Y751143D03*
Y753643D03*
Y756143D03*
X417662D03*
Y753643D03*
Y751143D03*
X420162Y758643D03*
X417662D03*
X415158Y771175D03*
X420158Y763675D03*
Y766175D03*
X417658Y768675D03*
X415158D03*
X417658Y763675D03*
Y766175D03*
X415158Y763675D03*
Y766175D03*
X415318Y1009765D03*
Y1006025D03*
X424873Y1014745D03*
X423811Y1005800D03*
X415318Y1013505D03*
X424873Y1023013D03*
Y1018879D03*
X415318Y1028466D03*
Y1020986D03*
Y1024726D03*
Y1017245D03*
X418918Y1032206D03*
X423811Y1032431D03*
X424024Y1267144D03*
X414247Y1268662D03*
X416747D03*
X419247D03*
X424024Y1269644D03*
Y1272144D03*
X414247Y1281180D03*
Y1283680D03*
X416747D03*
Y1281180D03*
Y1271162D03*
X414247D03*
X416747Y1278662D03*
Y1276162D03*
X419247Y1278662D03*
Y1276162D03*
Y1273662D03*
X416747D03*
X414247Y1278662D03*
Y1276162D03*
Y1273662D03*
X419361Y1283719D03*
Y1281219D03*
X419247Y1271162D03*
X424024Y1274644D03*
X414247Y1288680D03*
X416747D03*
X414247Y1286180D03*
X416747D03*
X419361Y1288719D03*
Y1291219D03*
X414361D03*
X416861D03*
X419361Y1286219D03*
X417063Y1340523D03*
Y1343423D03*
X415963Y1346172D03*
X413533D03*
X411103D03*
X421315Y1354276D03*
Y1351376D03*
X421205Y1348586D03*
Y1345686D03*
X418675Y1352166D03*
Y1349266D03*
X425631Y1517138D03*
X425087Y1510708D03*
X422587D03*
X423131Y1517138D03*
X412086Y1512076D03*
Y1514576D03*
X422557Y1537595D03*
X420057D03*
X417098Y1536411D03*
X418157Y1549295D03*
X423157Y1541795D03*
Y1544295D03*
X415657Y1541795D03*
X418157Y1546795D03*
Y1544295D03*
Y1541795D03*
X415657Y1549295D03*
Y1546795D03*
Y1544295D03*
X420657Y1541795D03*
Y1544295D03*
Y1546795D03*
Y1549295D03*
X417098Y1538911D03*
X424115Y1548199D03*
Y1551099D03*
X421697Y1551844D03*
X421683Y1565312D03*
X421108Y1560235D03*
X424488Y1565400D03*
X413540Y1556646D03*
X424616Y1560086D03*
X414202Y1559396D03*
X421294Y1557729D03*
X419254Y1566828D03*
X427081Y1581620D03*
X421277Y1571923D03*
X413396Y1594597D03*
X410991Y1597002D03*
X425469Y1595433D03*
X422069D03*
X419277Y1600725D03*
X414500Y1639075D03*
X417365Y1627695D03*
X420765D03*
X423500Y1652500D03*
X411448Y1650598D03*
X420000Y1664925D03*
X411500Y1657500D03*
X417000Y1675000D03*
X413000Y1683500D03*
X415500Y1672500D03*
X433673Y73960D03*
X428149Y65016D03*
X431359Y82589D03*
X433997Y166400D03*
X437997D03*
X436103Y158594D03*
X437997Y170701D03*
X433997D03*
X438200Y212096D03*
X431299Y212095D03*
X437440Y237270D03*
X442710Y237990D03*
X435710Y250340D03*
X440710D03*
X426947Y320749D03*
X433277Y471970D03*
X429784Y466315D03*
X426208Y468977D03*
X436226Y475526D03*
X437084Y501865D03*
X429784Y506947D03*
X442084Y511870D03*
X427500Y510553D03*
X426011Y524888D03*
X436062Y686575D03*
X430793Y686423D03*
X426839Y685978D03*
X430793Y683915D03*
X437555Y697490D03*
Y694949D03*
X433782Y690100D03*
X430958Y748643D03*
X433458D03*
X433462Y751143D03*
Y753643D03*
Y756143D03*
X430962D03*
Y753643D03*
Y751143D03*
Y758643D03*
X440159Y970341D03*
Y977841D03*
Y985341D03*
X438359Y993766D03*
X438434Y989766D03*
X438359Y997766D03*
X427551Y1005800D03*
X434716Y1014745D03*
X431291Y1005800D03*
X435031D03*
X438771D03*
X438359Y1001766D03*
X434716Y1018879D03*
Y1023013D03*
X431291Y1032431D03*
X435031D03*
X438771D03*
X427551D03*
X427615Y1282917D03*
Y1275417D03*
Y1280417D03*
Y1277917D03*
X436903Y1285694D03*
Y1289694D03*
X436924Y1462595D03*
X433524D03*
X440224Y1452895D03*
X427286Y1483590D03*
Y1480190D03*
Y1501990D03*
Y1505390D03*
X426704Y1523331D03*
Y1526731D03*
X439935Y1532600D03*
X430027Y1546795D03*
Y1544295D03*
X432527Y1541795D03*
Y1549295D03*
Y1546795D03*
Y1544295D03*
X430027Y1541795D03*
Y1549295D03*
X435027D03*
Y1546795D03*
Y1544295D03*
Y1541795D03*
X427527Y1549295D03*
Y1546795D03*
Y1544295D03*
Y1541795D03*
X426620Y1551844D03*
X437736Y1544392D03*
X431923Y1565790D03*
X432051Y1560635D03*
X437910Y1553910D03*
X433440Y1581700D03*
X429947Y1594398D03*
X436776Y1610394D03*
X430500Y1605835D03*
X431664Y1624342D03*
X436776Y1613794D03*
X433012Y1621612D03*
X430500Y1613709D03*
X434500Y1641500D03*
X431000Y1640500D03*
X432000Y1650000D03*
X436925Y1649500D03*
X441182Y77125D03*
X445267Y82124D03*
X452948Y104003D03*
X445997Y166400D03*
X453997D03*
X449997D03*
X448038Y158659D03*
X441997Y170701D03*
X449997D03*
X448499Y212036D03*
X443299Y212095D03*
X456231Y227764D03*
X443299Y220046D03*
X447299D03*
X456231Y232883D03*
X455422Y244103D03*
X444310Y243370D03*
X446710Y249340D03*
X454518Y280793D03*
X447840Y275970D03*
X441320Y295170D03*
Y301170D03*
Y307170D03*
Y313170D03*
Y316170D03*
X442297Y474442D03*
X453269Y478388D03*
X449496Y474009D03*
X446547Y480123D03*
X443683Y502256D03*
X448024Y505345D03*
X452084Y511870D03*
X447084D03*
X457084D03*
X453723Y526558D03*
X444441Y565549D03*
X450305Y669036D03*
X452735D03*
X447875D03*
X440845Y668731D03*
Y665831D03*
X445111Y662701D03*
X442945Y664331D03*
X440845Y662931D03*
X443045Y667331D03*
X445111Y665601D03*
X447212Y671640D03*
Y674540D03*
X446686Y726660D03*
Y729160D03*
Y731660D03*
X449190Y726528D03*
Y729028D03*
Y731528D03*
X451690D03*
Y729028D03*
Y726528D03*
X446686Y724028D03*
X449186D03*
X451686D03*
Y741660D03*
X449186D03*
Y739160D03*
Y736660D03*
X451686Y739160D03*
Y736660D03*
X446686Y741660D03*
Y736660D03*
Y739160D03*
Y734160D03*
X449190Y734028D03*
X451690D03*
X453810Y1014745D03*
X449992Y1005800D03*
X453732D03*
X443574Y1014745D03*
X446252Y1005800D03*
X442511D03*
X453810Y1023013D03*
X443574D03*
X453810Y1018879D03*
X443574D03*
X453732Y1032431D03*
X442884Y1038766D03*
X442511Y1032431D03*
X442884Y1042766D03*
X446252Y1032431D03*
X449992D03*
X441159Y1051541D03*
X443764Y1179395D03*
X443624Y1452895D03*
X453624Y1472295D03*
X446810Y1565020D03*
X446910Y1562098D03*
X446653Y1573264D03*
X441931Y1581662D03*
X443590Y1593880D03*
X441460Y1596020D03*
X450500Y1612450D03*
X446182Y1625555D03*
X450180Y1614950D03*
X445800Y1633200D03*
Y1636000D03*
X446000Y1650000D03*
X462653Y72525D03*
X462456Y95101D03*
X459056D03*
X470010Y141070D03*
X461997Y166400D03*
X471371Y227764D03*
X461931Y212703D03*
X468574Y213104D03*
X471371Y222764D03*
X464440Y218253D03*
X460567Y225205D03*
Y235442D03*
X460624Y240953D03*
Y230323D03*
X463240Y244980D03*
X456720Y285158D03*
X457248Y280143D03*
Y282643D03*
X470243Y285693D03*
X467545Y356864D03*
X460441Y499842D03*
X457424Y497978D03*
X468638Y514096D03*
X465766Y524991D03*
X458725Y524480D03*
X470331Y566632D03*
X465331D03*
X467831D03*
X462831D03*
X467831Y569132D03*
X470331D03*
X459931Y566632D03*
X457431D03*
X462831Y569132D03*
X457431D03*
X459931D03*
X465331D03*
X470331Y576132D03*
X467831Y571632D03*
X465331D03*
X467831Y576132D03*
X465331D03*
X470331Y571632D03*
X462831D03*
Y576132D03*
X457431Y571632D03*
Y574132D03*
X459931Y571632D03*
Y574132D03*
X457431Y576632D03*
X459931D03*
X462831Y598514D03*
X467831D03*
X470331D03*
X465331D03*
X457711D03*
X460211D03*
X462831Y601014D03*
X467831D03*
X470331D03*
X465331D03*
X457711D03*
X460211D03*
X469955Y672890D03*
X463193Y659315D03*
X468462Y661975D03*
X463193Y661823D03*
X455751Y659778D03*
X459239Y661378D03*
X469955Y670349D03*
X456501Y662346D03*
X466182Y665500D03*
X462490Y731528D03*
Y726528D03*
Y729028D03*
X464990D03*
Y726528D03*
X467486Y724028D03*
X464986D03*
X462486D03*
X467490Y726660D03*
X457472Y1005800D03*
X465965Y1009765D03*
Y1006025D03*
Y1013505D03*
Y1020986D03*
Y1024726D03*
Y1028466D03*
Y1017245D03*
Y1032206D03*
X457472Y1032431D03*
X463724Y1462595D03*
X470424Y1452895D03*
X460324Y1462595D03*
X467024Y1452895D03*
X457024Y1472295D03*
X462215Y1581510D03*
X462753Y1641289D03*
X459500Y1659000D03*
X467500Y1651500D03*
X457000Y1650000D03*
X468075Y1662500D03*
X470463Y1670038D03*
X464925Y1662500D03*
X467500Y1678500D03*
X468575Y1704000D03*
X462500Y1697000D03*
X466000Y1714575D03*
X468575Y1731000D03*
X479400Y90574D03*
Y94574D03*
Y97574D03*
Y110930D03*
X479465Y119644D03*
Y115644D03*
X482255Y133222D03*
Y129822D03*
X479465Y123644D03*
X482380Y141942D03*
X483800Y189400D03*
X480200Y191900D03*
X480700Y208200D03*
X480715Y211099D03*
X471371Y235764D03*
X483227Y233000D03*
X487620Y270400D03*
X479870D03*
X483823Y285893D03*
X474808Y291492D03*
X482893Y291293D03*
X479148Y315502D03*
X484063Y305669D03*
X480773Y307153D03*
X471015Y527283D03*
X475731Y566632D03*
X473231D03*
Y569132D03*
X475731D03*
Y574132D03*
Y571632D03*
X473231Y574132D03*
Y571632D03*
X475731Y576632D03*
X473231D03*
X485335Y642536D03*
X480475D03*
X482905D03*
X473445Y642231D03*
X477711Y639101D03*
X475645Y640831D03*
X473445Y639331D03*
X475545Y637831D03*
X473445Y636431D03*
X477711Y636201D03*
X479812Y645240D03*
Y648140D03*
X479058Y702660D03*
Y700160D03*
X484062Y700028D03*
Y702528D03*
X481562D03*
Y700028D03*
X479058Y697528D03*
X481558D03*
X484058D03*
X479058Y717660D03*
Y707660D03*
Y712660D03*
Y710160D03*
Y715160D03*
X484058Y710160D03*
Y712660D03*
X481558Y710160D03*
Y712660D03*
X484058Y715160D03*
X481558D03*
X484062Y707528D03*
X481562D03*
X479058Y705160D03*
X484062Y705028D03*
X481562D03*
X480803Y1015474D03*
Y1022560D03*
Y1019017D03*
X483824Y1472295D03*
X480424D03*
X483500Y1658500D03*
X479500Y1666500D03*
X473500Y1662500D03*
X477538Y1661463D03*
X474000Y1704000D03*
X478500Y1697000D03*
Y1710500D03*
Y1733500D03*
X491849Y55095D03*
Y60105D03*
X497885Y51315D03*
X491849Y64965D03*
X500674Y116261D03*
X490380Y131442D03*
X493780D03*
X485780Y141942D03*
X500136Y141058D03*
X495500Y161386D03*
X497700Y157200D03*
X492685Y160994D03*
X486682Y193516D03*
X495232D03*
Y185516D03*
X486682Y189516D03*
X496831Y205030D03*
X499380Y222510D03*
X491635Y225970D03*
X494144Y221370D03*
X487442Y223377D03*
X500209Y227881D03*
X491635Y215652D03*
X500209Y233000D03*
X491859D03*
X500119Y243173D03*
X500209Y238119D03*
X491577Y238120D03*
Y243240D03*
X485962Y290679D03*
X487827Y354017D03*
X490419Y362138D03*
X498500Y419425D03*
X495793Y632815D03*
X495839Y635323D03*
X488351Y633278D03*
X491839Y634878D03*
X489101Y635846D03*
X498782Y639000D03*
X497362Y700028D03*
Y702528D03*
X494862D03*
Y700028D03*
X499858Y697528D03*
X497358D03*
X494858D03*
X499862Y700160D03*
Y702660D03*
X494862Y705028D03*
X497362D03*
X499862Y705160D03*
X488384Y1015474D03*
X495884D03*
X488384Y1022560D03*
Y1019017D03*
X495884Y1022560D03*
Y1019017D03*
X490524Y1462595D03*
X497224Y1452895D03*
X487124Y1462595D03*
X493824Y1452895D03*
X512658Y46613D03*
X504796Y86320D03*
X516020Y105370D03*
Y109270D03*
X513772Y121220D03*
X502750Y111276D03*
X503000Y135600D03*
X509346Y125842D03*
X507945Y160919D03*
X503161Y154620D03*
X500600Y157100D03*
X505315Y196944D03*
X503507Y185516D03*
X504351Y202776D03*
X508238Y199506D03*
X512076Y206404D03*
X511684Y221219D03*
X504351Y215901D03*
X508001Y220166D03*
X515223Y289035D03*
Y313200D03*
Y305145D03*
X513775Y608436D03*
X506745Y608131D03*
X508945Y606731D03*
X506745Y602331D03*
Y605231D03*
X508845Y603731D03*
X511011Y602101D03*
Y605001D03*
X513012Y611040D03*
Y613940D03*
X501062Y635475D03*
X502555Y646390D03*
Y643849D03*
X514162Y673428D03*
Y665928D03*
Y668428D03*
Y670928D03*
X514158Y663428D03*
Y678460D03*
Y683460D03*
Y680960D03*
Y675960D03*
X509572Y865327D03*
X513572D03*
X513924Y1462595D03*
X510624Y1472295D03*
X507224D03*
X524713Y33346D03*
X529713D03*
X516058Y46613D03*
X519765Y40328D03*
X523165D03*
X519743Y71436D03*
X523143D03*
X524993Y125914D03*
X521618Y165428D03*
X519268Y167428D03*
X519601Y196117D03*
X518691Y191846D03*
X517314Y200449D03*
X519248Y280721D03*
X516723D03*
X521773D03*
X520273Y289035D03*
X517748D03*
X522798D03*
X520273Y313200D03*
X517748D03*
X520273Y305145D03*
X517748D03*
X515523Y335613D03*
X529317Y403784D03*
X524680Y417602D03*
X529095Y452049D03*
X529153Y598735D03*
X529235Y601543D03*
X521651Y599178D03*
X525139Y600778D03*
X522401Y601746D03*
X516205Y608436D03*
X518635D03*
X529962Y673428D03*
Y670928D03*
Y668428D03*
Y665928D03*
X516662Y673428D03*
Y670928D03*
Y668428D03*
Y665928D03*
X527462Y673428D03*
Y665928D03*
Y668428D03*
Y670928D03*
X516658Y663428D03*
X527458D03*
X529958D03*
X516658Y678460D03*
Y683460D03*
Y680960D03*
X527458Y678460D03*
X516658Y675960D03*
X527458D03*
X529958D03*
Y678460D03*
X526474Y851934D03*
Y849434D03*
X517009Y856494D03*
X523074Y853439D03*
Y855939D03*
X528220Y1167366D03*
X517118D03*
X520818D03*
X517324Y1462595D03*
X524024Y1452895D03*
X520624D03*
X539120Y31340D03*
X535117D03*
X544721Y42892D03*
X539721Y42862D03*
X533918Y47067D03*
X537318D03*
X541003Y71436D03*
X544403D03*
X538210Y90618D03*
X540615Y88213D03*
X535170Y111230D03*
Y115130D03*
X530567Y125914D03*
X543408Y133912D03*
X538166Y130698D03*
X541675Y146874D03*
Y151470D03*
Y142021D03*
Y137169D03*
Y156195D03*
X533442Y164428D03*
X532222Y207849D03*
X540695Y217874D03*
X534277Y224930D03*
X538613Y227882D03*
X537051Y211959D03*
X538613Y238119D03*
X534277Y230441D03*
Y235560D03*
X538613Y233000D03*
X539217Y245270D03*
X543780Y294168D03*
X541808Y289743D03*
X544628Y291633D03*
Y289133D03*
X542983Y334531D03*
X533211Y350838D03*
X533543Y404130D03*
X530729Y398634D03*
X543170Y434737D03*
X534455Y428561D03*
X531753Y453232D03*
X540616Y463486D03*
X538067Y592652D03*
X542071Y593089D03*
X535855Y612290D03*
X539657Y607658D03*
X534362Y601375D03*
X535855Y609749D03*
X532082Y604900D03*
X534962Y670960D03*
Y665960D03*
Y668460D03*
X532462D03*
Y665960D03*
Y670960D03*
Y673460D03*
Y663460D03*
X534962D03*
Y673460D03*
Y675960D03*
X532462D03*
X531921Y1167366D03*
X537424Y1452895D03*
X534024D03*
X544794Y1480682D03*
Y1484082D03*
Y1497482D03*
Y1494082D03*
X543947Y1516120D03*
Y1512220D03*
X543672Y1519845D03*
X540810Y1521436D03*
X533317Y1511953D03*
Y1514453D03*
Y1516953D03*
X531495Y1519250D03*
X537770Y1519845D03*
X537647Y1516120D03*
Y1512220D03*
X534002Y1521436D03*
X540797Y1516120D03*
Y1512220D03*
X543719Y1549295D03*
Y1546795D03*
X541219D03*
Y1549295D03*
X538719D03*
Y1546795D03*
X531339Y1546481D03*
X553620Y31048D03*
X549919D03*
X554984Y45312D03*
X553651Y48842D03*
X546350Y39562D03*
X550972Y42902D03*
X561721Y41024D03*
X556351Y41538D03*
X548610Y48082D03*
X547821Y79372D03*
X551721D03*
X555176Y71436D03*
X558576D03*
X552105Y112203D03*
X555505D03*
X553780Y121240D03*
Y124640D03*
X559484Y156667D03*
X553757Y160075D03*
X547196Y190256D03*
X550196D03*
X554196D03*
X553578Y193541D03*
X547196Y199256D03*
X550553Y200304D03*
Y197778D03*
X548963Y218441D03*
X549248Y237652D03*
Y230441D03*
X555567Y236970D03*
X549248Y234152D03*
X559774Y243176D03*
X557243Y294693D03*
X561808Y300492D03*
X562030Y372872D03*
X551044Y373085D03*
X562208Y383668D03*
Y404717D03*
X550573Y399586D03*
Y403586D03*
X562208Y397599D03*
X550573Y414274D03*
X549854Y406298D03*
X547529Y425411D03*
X551591Y443665D03*
X552510Y446490D03*
X547751Y472678D03*
X550925Y475178D03*
X553360Y477822D03*
X555727Y479968D03*
X558379Y482096D03*
X549957Y658478D03*
Y661478D03*
X558690Y1226149D03*
X558876Y1454905D03*
Y1458305D03*
X546253Y1454107D03*
Y1457507D03*
X555348Y1483590D03*
Y1480190D03*
Y1501990D03*
Y1505390D03*
X548197Y1514641D03*
X550471Y1513584D03*
Y1511031D03*
X548197Y1512088D03*
X554766Y1523331D03*
Y1526731D03*
X550939Y1536646D03*
X559215Y1530596D03*
X546219Y1549295D03*
Y1541795D03*
Y1546795D03*
Y1544295D03*
X548719Y1549295D03*
Y1546795D03*
Y1541795D03*
Y1544295D03*
X551219D03*
Y1541795D03*
X549674Y1538890D03*
X558089Y1541795D03*
Y1544295D03*
Y1546795D03*
Y1549295D03*
X555589Y1541795D03*
Y1549295D03*
Y1546795D03*
Y1544295D03*
X549759Y1551844D03*
X552177Y1551099D03*
X554682Y1551844D03*
X552177Y1548199D03*
X565185Y47982D03*
X575331Y47672D03*
X573191Y42912D03*
X570209Y47982D03*
X566771Y41133D03*
X564794Y58911D03*
X567997Y58992D03*
X573763Y58688D03*
X562331Y48438D03*
X570860Y121310D03*
Y124710D03*
X563951Y153640D03*
Y148640D03*
Y157494D03*
X572003Y164356D03*
Y169415D03*
X568804Y221926D03*
X571427Y217771D03*
X569004Y225496D03*
X568736Y235821D03*
X565093Y242640D03*
X570823Y294893D03*
X572447Y299470D03*
X569893Y300293D03*
X571063Y314669D03*
X566148Y324502D03*
X567773Y316153D03*
X575913Y413287D03*
X570863Y410728D03*
X572121Y437038D03*
X564407Y431638D03*
X568709Y434227D03*
X563763Y486350D03*
X567297Y487551D03*
X560890Y484664D03*
X569923Y490726D03*
X561346Y1228547D03*
X564669Y1238907D03*
X564283Y1231192D03*
X565537Y1235456D03*
X574200Y1229900D03*
X567127Y1249536D03*
X570775Y1263008D03*
X564986Y1462595D03*
X571686Y1452895D03*
X561586Y1462595D03*
X568286Y1452895D03*
X560589Y1541795D03*
Y1544295D03*
Y1546795D03*
Y1549295D03*
X563089Y1541795D03*
Y1549295D03*
Y1546795D03*
Y1544295D03*
X567214Y1544299D03*
X591938Y46308D03*
X576478Y58563D03*
X591070Y60201D03*
X586953Y63441D03*
X583685Y70678D03*
X586390Y69291D03*
X579561Y73090D03*
X585000Y82500D03*
X584752Y86248D03*
X590501Y86909D03*
X578454Y88926D03*
X586394Y95948D03*
X591811Y97421D03*
X580485Y133056D03*
Y130530D03*
X583485D03*
Y133056D03*
X589203Y164356D03*
X581203D03*
X589203Y169415D03*
X585685Y174975D03*
X581203Y169415D03*
X575425Y189835D03*
X582124Y194150D03*
X588244Y208991D03*
X575440Y200785D03*
X582002Y197481D03*
X582766Y225496D03*
Y221421D03*
X588554Y217277D03*
Y225277D03*
X580343Y217771D03*
X588215Y214079D03*
X588968Y240112D03*
X582816Y228696D03*
X581099Y263680D03*
X586157Y366827D03*
X585585Y372052D03*
X577482Y383668D03*
X581985Y387227D03*
Y376427D03*
X587710Y399287D03*
X581985Y401158D03*
X587710Y404287D03*
X588723Y415846D03*
X588798Y435949D03*
X588723Y427949D03*
X588742Y431976D03*
X577845Y437151D03*
X587829Y445138D03*
X575345Y437151D03*
X580523Y435949D03*
X575075Y451263D03*
X582390Y464701D03*
X589507Y462559D03*
X583116Y476745D03*
X587500Y470308D03*
X587795Y479631D03*
X581335Y472100D03*
X581421Y813078D03*
X588500Y812093D03*
X584271Y1263988D03*
X588386Y1462595D03*
X585086Y1472295D03*
X581686D03*
X602837Y32910D03*
X603064Y48023D03*
X599284Y42481D03*
X597956Y48047D03*
X606585Y43529D03*
X601073Y60301D03*
X603350Y73642D03*
X599295Y100747D03*
X606183Y95873D03*
X597275Y94922D03*
X596068Y106798D03*
X591385Y109165D03*
X602328Y109062D03*
X597769Y153640D03*
Y148640D03*
X603344Y139131D03*
X598552Y159066D03*
X600161Y188776D03*
X593661D03*
X604293Y193185D03*
X597293Y193186D03*
X602294Y203786D03*
X598968Y238878D03*
X603526Y229995D03*
X597050Y281950D03*
X602223Y298035D03*
X603723Y289721D03*
X602223Y314145D03*
Y322200D03*
X598414Y372357D03*
X598208Y383668D03*
X599884Y412000D03*
X593758Y415850D03*
X603326Y429530D03*
X590326Y445015D03*
X592529Y461563D03*
X598496Y451421D03*
X597500Y483500D03*
X602833Y791746D03*
X590710Y804192D03*
X603743Y794963D03*
X595619Y806084D03*
X600337Y800649D03*
X596821Y802688D03*
X592572Y809088D03*
X596621Y1240366D03*
X595253Y1266668D03*
X596944Y1270115D03*
X595532Y1262668D03*
X605771Y1263098D03*
X598112Y1264365D03*
X594991Y1285582D03*
Y1289582D03*
X591786Y1462595D03*
X598486Y1452895D03*
X595086D03*
X613025Y42725D03*
X612608Y35961D03*
X618732Y39913D03*
X619563Y49193D03*
X615587Y45611D03*
X606263Y60301D03*
X616815Y60277D03*
X611579D03*
X615190Y74533D03*
X615772Y106645D03*
X618182Y100786D03*
X610009Y100748D03*
X614282Y95873D03*
X617420Y119640D03*
X619240Y123232D03*
X605853Y149640D03*
Y145640D03*
Y152140D03*
Y155131D03*
X618801Y165356D03*
Y175534D03*
Y170415D03*
X616357Y182229D03*
X608794Y203786D03*
X607868Y257562D03*
X618705Y285305D03*
X608773Y289721D03*
X609798Y298035D03*
X607273D03*
X606248Y289721D03*
X604748Y298035D03*
X609798Y314145D03*
X607273D03*
X604748D03*
X621585Y331358D03*
X609798Y322200D03*
X607273D03*
X604748D03*
X611118Y359462D03*
X613565Y350819D03*
X619035Y369542D03*
X613482Y383668D03*
X617985Y387227D03*
Y376427D03*
Y401728D03*
X606032Y418968D03*
X617985Y407346D03*
X617998Y415546D03*
X606811Y429528D03*
X611925Y437000D03*
X605769Y442593D03*
X615903Y493474D03*
X608886Y494400D03*
X618680Y511302D03*
X618957Y502306D03*
X616457D03*
X611896Y535178D03*
Y538178D03*
X607091Y528168D03*
X618645Y783582D03*
X609402Y788678D03*
X615571Y788448D03*
X608940Y1265991D03*
X610551Y1262988D03*
X618761Y1266988D03*
X615591Y1282038D03*
X618761Y1278668D03*
X606619Y1278302D03*
X610551Y1269888D03*
X616037Y1367166D03*
X608148Y1373890D03*
X616615Y1386232D03*
X616629Y1375082D03*
X618586Y1462595D03*
X615186D03*
X611886Y1472295D03*
X608486D03*
X613948Y1641600D03*
X624634Y48104D03*
X628410Y45381D03*
X624689Y58262D03*
X627881Y57120D03*
X622207Y60573D03*
X627496Y74977D03*
X626642Y71365D03*
X622156Y95948D03*
X626208Y100861D03*
X628885Y127057D03*
X630810Y122089D03*
X625532Y146982D03*
X625553Y152683D03*
X625755Y168917D03*
X626372Y193431D03*
X626824Y182080D03*
X620455Y219277D03*
Y228777D03*
X631505Y284355D03*
X626705Y285305D03*
X622705D03*
X626473Y305338D03*
X626388Y330536D03*
X631694Y341300D03*
X626555Y343929D03*
X624133Y346520D03*
X626596Y360196D03*
X636500Y360362D03*
X634105Y404652D03*
X635058Y399700D03*
X627925Y421966D03*
X631075Y429888D03*
X632281Y441904D03*
X622174Y438925D03*
X622197Y436116D03*
X622800Y461348D03*
X627880Y455310D03*
X620800Y474700D03*
X627364Y478823D03*
X632984Y471462D03*
X630758Y505874D03*
X633406Y497964D03*
X624381Y503765D03*
X631510Y510613D03*
X624718Y553428D03*
X634794Y590504D03*
X635567Y671774D03*
X631557Y773359D03*
X631741Y770318D03*
X633406Y1358576D03*
X634776Y1353739D03*
X630477Y1350109D03*
Y1353109D03*
X624795Y1373257D03*
X624976Y1378313D03*
X630195Y1384263D03*
X625195Y1383457D03*
X622352Y1393285D03*
X630523Y1392554D03*
X635849Y1393376D03*
X625286Y1452895D03*
X621886D03*
X629808Y1668863D03*
X633422Y1673488D03*
X631643Y1670946D03*
X635491Y1696845D03*
X635472Y1711808D03*
X644963Y29143D03*
X638490Y33340D03*
X642157Y44695D03*
X639876Y49193D03*
X651042Y41545D03*
X647987Y47606D03*
X646042Y41545D03*
X640653Y58274D03*
X640670Y74369D03*
X650846Y74074D03*
X647938Y83795D03*
X644202Y84604D03*
X642607Y94116D03*
X645752Y134988D03*
X643800Y166053D03*
X641111Y158300D03*
X641006Y161829D03*
X643800Y161862D03*
X640923Y169388D03*
X649871Y181942D03*
X641276Y187557D03*
X637804Y235371D03*
X640804D03*
X637804Y239371D03*
X640804D03*
X640084Y227113D03*
X637804Y243371D03*
X640804D03*
X642171Y311280D03*
X641013Y324459D03*
X640922Y360342D03*
X639000Y364862D03*
X642128Y363279D03*
X636579Y366941D03*
X642617Y389299D03*
X637314Y393680D03*
X640784Y395957D03*
X651279Y404458D03*
X637160Y405449D03*
X635243Y433518D03*
X637432Y428935D03*
X642406Y427614D03*
X639211Y433862D03*
Y438191D03*
X635449Y449797D03*
X639002Y449862D03*
X639500Y442362D03*
X639313Y452361D03*
X635690Y461441D03*
X648500Y453862D03*
X635640Y464257D03*
X644849Y495582D03*
X647576Y497964D03*
X643053Y502891D03*
X640076Y497964D03*
X635906D03*
X642310Y535773D03*
X649592Y540078D03*
X639757Y533440D03*
X636055Y528605D03*
X646151Y535227D03*
X648314Y571169D03*
X644414D03*
X638694Y590504D03*
X650258Y590316D03*
X646358D03*
X650228Y674761D03*
X638967Y671774D03*
X646446Y674643D03*
X640271Y763488D03*
X636551Y767900D03*
X642804Y766871D03*
X636247Y771179D03*
X635092Y1277102D03*
X634995Y1384457D03*
X638053Y1384491D03*
X647401Y1384160D03*
X645386Y1462595D03*
X641986D03*
X648686Y1452895D03*
X638686Y1472295D03*
X635286D03*
X639907Y1570443D03*
X639132Y1573127D03*
X645180Y1597800D03*
X645190Y1595050D03*
X649153Y1625726D03*
X649297Y1623185D03*
X640242Y1639951D03*
X647630Y1641522D03*
X643128Y1639803D03*
X642716Y1653939D03*
X637218Y1654131D03*
X644905Y1646491D03*
X639800Y1646650D03*
X643074Y1668505D03*
X647574D03*
X647460Y1662952D03*
X640846Y1665189D03*
X650158Y1687189D03*
X643041Y1682883D03*
X647500Y1674805D03*
X640600D03*
X643300D03*
X639391Y1700695D03*
X640690Y1703547D03*
X651143Y1706162D03*
X644975Y1725236D03*
X635210Y1718395D03*
X641825Y1730516D03*
X640865Y1719684D03*
X657921Y30864D03*
X654117Y29099D03*
X654582Y45448D03*
X660928Y60707D03*
X651014Y60820D03*
X656600Y60537D03*
X661601Y75562D03*
X656501Y69662D03*
X657166Y79131D03*
X656427Y75431D03*
X661588Y69662D03*
X658228Y88447D03*
X666200Y84862D03*
X654037Y93241D03*
Y96041D03*
X651950Y99890D03*
X658949Y139840D03*
X662881Y149912D03*
Y146912D03*
X654326Y174437D03*
X653700Y179962D03*
X659881Y208262D03*
Y205762D03*
Y210762D03*
X662781Y207862D03*
Y205362D03*
Y210362D03*
X663915Y234476D03*
X659918Y326503D03*
X658905Y341885D03*
X661019Y344831D03*
X663551Y346035D03*
X649500Y373500D03*
X652425Y385924D03*
X659095Y381020D03*
X649495Y385118D03*
X659354Y393938D03*
X653523Y399987D03*
X652954Y394284D03*
X661297Y409857D03*
X662016Y417897D03*
X652027Y415930D03*
X654273Y419251D03*
X662000Y433862D03*
X654248Y422500D03*
X657535Y422694D03*
X666000Y429844D03*
X651432Y433532D03*
X662000Y429844D03*
X652763Y427866D03*
X651384Y445252D03*
X661546Y444497D03*
X662000Y449862D03*
X654441Y449618D03*
X662000Y437844D03*
X657622Y437819D03*
X651853Y439518D03*
X653449Y458542D03*
X662570Y461547D03*
Y457755D03*
X662000Y473862D03*
X666000Y473844D03*
X651072Y465939D03*
X654000Y465824D03*
X654014Y473862D03*
X662000Y465862D03*
X651114Y473884D03*
X662000Y469862D03*
X653266Y479106D03*
X663374Y484295D03*
X652380Y482390D03*
X657520Y486330D03*
X649500Y490260D03*
X660215Y483109D03*
X658758Y497964D03*
X655917D03*
X661718Y498056D03*
X651406Y501178D03*
X650404Y496102D03*
X652576Y497964D03*
X659425Y521075D03*
X665689Y550294D03*
X649922Y545610D03*
X655967Y544375D03*
X658642Y573893D03*
X661718Y579932D03*
X653368Y581468D03*
X655572Y572603D03*
X656832Y577205D03*
X662992Y598660D03*
X658613Y599534D03*
X662628Y674761D03*
X660175Y679517D03*
X657428Y674761D03*
X663580Y731509D03*
X658947Y767300D03*
Y771100D03*
X662600Y1311502D03*
Y1308502D03*
X653376Y1365793D03*
X661719Y1363394D03*
X651973Y1363038D03*
X653149Y1372500D03*
X653101Y1369862D03*
X652651Y1375308D03*
X661813Y1370081D03*
X653117Y1378037D03*
X651877Y1391074D03*
X652086Y1452895D03*
X662086D03*
X663160Y1511734D03*
Y1516734D03*
Y1519234D03*
Y1521734D03*
X660660Y1519234D03*
X661710Y1514148D03*
X663160Y1524234D03*
X666092Y1553650D03*
X660953Y1539998D03*
X663133Y1543744D03*
Y1541244D03*
Y1538744D03*
X660953Y1542498D03*
X657430Y1555228D03*
X659532Y1546519D03*
X664246Y1561009D03*
X661731Y1561083D03*
X661156Y1626532D03*
X650966Y1618934D03*
X651870Y1612986D03*
X650753Y1615912D03*
X653542Y1649059D03*
X660058Y1648889D03*
X660389Y1654481D03*
X663431Y1645780D03*
X654712Y1653813D03*
X664315Y1654484D03*
X650074Y1668505D03*
X658648Y1664169D03*
X655683Y1664212D03*
X653154Y1683265D03*
X664159Y1674844D03*
X661528Y1674865D03*
X650200Y1674805D03*
X658491Y1688965D03*
X649464Y1691180D03*
X659837Y1698400D03*
X659557Y1714672D03*
X658759Y1707147D03*
X659028Y1710047D03*
X660930Y1730277D03*
X662120Y1720404D03*
X670613Y42464D03*
X674013D03*
X677476Y33317D03*
X680864Y38190D03*
X666506Y32750D03*
X674647Y38190D03*
X677305Y57947D03*
X665469Y58525D03*
X674036Y74522D03*
X675509Y88173D03*
X667941Y80142D03*
X677561Y118409D03*
X677738Y115428D03*
X665651Y147692D03*
X673011Y169021D03*
X679035Y204181D03*
X678226Y215771D03*
X674348Y218580D03*
X666552Y346115D03*
X677111Y345662D03*
X672111D03*
X674611D03*
X676800Y369362D03*
X672800D03*
X680800Y380280D03*
X672800Y382362D03*
X676000Y378100D03*
X667090Y385150D03*
X671500Y390862D03*
X679940Y400933D03*
X675500Y398862D03*
Y390862D03*
X670018Y418690D03*
X669929Y407999D03*
X666000Y433862D03*
Y425862D03*
X670000Y429864D03*
Y433844D03*
Y425894D03*
X666000Y437844D03*
X670000Y442362D03*
Y437844D03*
X666000Y442362D03*
X670000Y446362D03*
X679062Y455140D03*
X666000Y453844D03*
Y457862D03*
X670000Y453844D03*
X666000Y461862D03*
X670000Y469824D03*
Y477862D03*
X678000D03*
X670000Y482862D03*
X678000D03*
X681213Y495658D03*
X672699Y506907D03*
X664741Y506865D03*
X680488Y504784D03*
X665425Y537000D03*
X664454Y574896D03*
X665774Y571762D03*
X666192Y598660D03*
X679047Y678733D03*
X673287Y733156D03*
X674123Y736083D03*
X667101Y736071D03*
X672505Y766871D03*
X674552Y1342488D03*
Y1344988D03*
X665167Y1380836D03*
Y1376836D03*
X673671Y1431922D03*
X675272Y1434525D03*
X665486Y1452895D03*
X672856Y1484082D03*
Y1480682D03*
Y1497482D03*
Y1494082D03*
X678386Y1507965D03*
X677871Y1522079D03*
X678345Y1516994D03*
X677871Y1519579D03*
X673174Y1515806D03*
X675505Y1512606D03*
X678339Y1510960D03*
X677871Y1524579D03*
X678121Y1528516D03*
X665832Y1527425D03*
X672715Y1526626D03*
Y1530526D03*
X678350Y1567400D03*
X669524Y1560850D03*
X672163Y1560899D03*
X673729Y1556768D03*
X666978Y1560945D03*
X672810Y1571560D03*
X666610Y1571580D03*
X668133Y1625828D03*
X670839Y1620863D03*
X673960Y1633042D03*
X669648Y1640917D03*
X670803Y1654606D03*
X671068Y1650818D03*
X674908Y1644481D03*
X667971Y1654404D03*
X669178Y1646627D03*
X673548Y1669550D03*
X678117Y1662787D03*
X675497Y1687253D03*
X673359Y1674409D03*
X671001Y1696017D03*
X671798Y1704542D03*
X673113Y1716599D03*
X667701Y1705043D03*
X668058Y1720092D03*
X673113Y1727261D03*
X684611Y41857D03*
X682291Y46822D03*
X690476Y32684D03*
X692390Y46939D03*
X692466Y35950D03*
X687835Y37850D03*
X687345Y46940D03*
X687018Y58357D03*
X683369Y58157D03*
X692390Y72692D03*
X690028Y70142D03*
X687665Y73202D03*
X685781Y70022D03*
X680580Y79230D03*
X681054Y104668D03*
X686891Y115868D03*
X687000Y119500D03*
X685500Y124000D03*
X679316Y209861D03*
X680576Y207105D03*
X681333Y212326D03*
X679737Y217763D03*
X693621Y346169D03*
X680828Y363500D03*
X684800Y369362D03*
X680800D03*
X691484Y360643D03*
X691500Y382462D03*
X685200Y377820D03*
X690105Y401775D03*
X687500Y390680D03*
X684794Y402268D03*
X683500Y390862D03*
X679500D03*
X692996Y418358D03*
X694299Y413108D03*
X689269Y410420D03*
X687612Y471850D03*
X691572Y465214D03*
X684800Y477862D03*
X687472Y486994D03*
X684680Y485942D03*
X684800Y481862D03*
X680187Y491243D03*
X690452Y486984D03*
X687310Y500453D03*
X682915Y500568D03*
X683000Y521500D03*
X687310Y522141D03*
X694111Y537881D03*
X690718Y578913D03*
X694996Y575081D03*
X689574Y572866D03*
X681352Y681305D03*
X691417Y680382D03*
X685786Y680936D03*
X686509Y677440D03*
X688648Y767300D03*
Y771100D03*
X687961Y1314308D03*
Y1320308D03*
Y1323308D03*
Y1317308D03*
X684868Y1327117D03*
X682348D03*
Y1339617D03*
X683052Y1342548D03*
X684868Y1329617D03*
X682348D03*
X684868Y1332117D03*
X682348D03*
X684868Y1334617D03*
X682348D03*
X684868Y1337117D03*
Y1339617D03*
X682348Y1337117D03*
X683052Y1345048D03*
X681289Y1418291D03*
X683391Y1420531D03*
X685448Y1423137D03*
X691587Y1429515D03*
X689538Y1427467D03*
X684350Y1448911D03*
X692376Y1438326D03*
X691943Y1441626D03*
X687040Y1452300D03*
X684280Y1452260D03*
X684603Y1507851D03*
X681517Y1508034D03*
X687529Y1508173D03*
X690683Y1508058D03*
X693395D03*
X693532Y1510755D03*
X690820D03*
X687666Y1510870D03*
X687711Y1513612D03*
X690751Y1513750D03*
X693655Y1513818D03*
X693587Y1516470D03*
X690752Y1516516D03*
X683666Y1515189D03*
X680717Y1513292D03*
X684557Y1510685D03*
X681563Y1510708D03*
X693495Y1519305D03*
X679854Y1551492D03*
X679413Y1548843D03*
X680107Y1554330D03*
X681780Y1574280D03*
X684080Y1576500D03*
X686949Y1625144D03*
X689897Y1621781D03*
X692209Y1620037D03*
X691036Y1625508D03*
X686994Y1629077D03*
X693451Y1628733D03*
X686808Y1643500D03*
X685578Y1637479D03*
X683067Y1641758D03*
X686075Y1657082D03*
X679413Y1653251D03*
X685719Y1672391D03*
X685747Y1669303D03*
X693608Y1671081D03*
X685635Y1675310D03*
X691560Y1682047D03*
X693480Y1673940D03*
X692390Y1687594D03*
X705666Y48010D03*
X697678Y47132D03*
X697893Y35950D03*
X702481Y48327D03*
X698462Y60683D03*
X695220Y60455D03*
X704201Y72112D03*
X699476Y69982D03*
X701081Y72450D03*
X694752Y70212D03*
X696701Y72462D03*
X698711Y86035D03*
X696371Y78512D03*
X696728Y81552D03*
Y84052D03*
X706721Y100462D03*
X702721Y102162D03*
X701221Y104862D03*
X697721D03*
X695721Y102162D03*
X694221Y104862D03*
X699221Y102162D03*
X699398Y123668D03*
X704709Y125586D03*
X704771Y171188D03*
Y167788D03*
X703486Y345507D03*
X699813Y344798D03*
X706139Y345597D03*
X695500Y374362D03*
X699500D03*
X703500D03*
X707500D03*
X707943Y360643D03*
X707500Y368862D03*
X696391Y368617D03*
X703477Y369409D03*
X695500Y382362D03*
X700300Y382502D03*
X707500Y382362D03*
X700000Y386790D03*
X707500Y386862D03*
X703700Y386832D03*
X695500Y386862D03*
X699500Y390862D03*
X695500D03*
X707500D03*
X703500Y401290D03*
Y390862D03*
X708584Y404868D03*
X699431Y513344D03*
X703774Y513463D03*
X707664Y513375D03*
X703788Y521817D03*
X696020Y521844D03*
X699800Y521760D03*
X708500Y517362D03*
X708210Y537816D03*
X708500Y529862D03*
X704500D03*
X700790Y537732D03*
X704500Y537862D03*
X708500Y533862D03*
X696829Y533604D03*
X702657Y533695D03*
X697018Y537577D03*
X704500Y545862D03*
X696283Y546530D03*
X710429Y545752D03*
X708500Y555451D03*
X698996Y575081D03*
X704056D03*
X708056D03*
X704056Y583081D03*
X698996D03*
X702806Y613264D03*
X696928Y613207D03*
X706387Y621686D03*
X705158Y645357D03*
X703781Y641805D03*
X704965Y638767D03*
X707833Y655325D03*
X704549Y655238D03*
X701233Y655355D03*
X708418Y650389D03*
X694812Y680188D03*
X698756Y676388D03*
X694837Y676412D03*
X701386Y679683D03*
X703584Y676544D03*
X708012Y676836D03*
X705697Y679533D03*
X697571Y730453D03*
X704598Y732288D03*
X700205Y733211D03*
X702553Y735811D03*
X702206Y766871D03*
X697461Y1314008D03*
Y1320008D03*
Y1323008D03*
X702388Y1327127D03*
X699868D03*
X697461Y1317008D03*
X701771Y1342488D03*
X702388Y1337127D03*
Y1339627D03*
X699868Y1337127D03*
Y1339627D03*
X702388Y1329627D03*
X699868D03*
X702388Y1332127D03*
X699868D03*
X702388Y1334627D03*
X699868D03*
X701771Y1344988D03*
X705657Y1387027D03*
X701689Y1399545D03*
X697731Y1397513D03*
X706351Y1397588D03*
X705657Y1389568D03*
X695162Y1441350D03*
X696237Y1508149D03*
X699247Y1508062D03*
X699049Y1510892D03*
X696374Y1510846D03*
X696329Y1513818D03*
X696330Y1516584D03*
X699140Y1513772D03*
X707050Y1531700D03*
X709150Y1536250D03*
X703290Y1551700D03*
X707050Y1548400D03*
Y1541800D03*
X703290Y1545100D03*
X708500Y1560500D03*
X708994Y1568507D03*
X699500Y1559000D03*
X699610Y1568523D03*
Y1572523D03*
Y1576523D03*
X708600Y1572523D03*
X710420Y1585173D03*
X710550Y1576523D03*
X710080Y1581683D03*
X699610Y1584523D03*
X699500Y1596500D03*
Y1588500D03*
X709836Y1594721D03*
X710360Y1589296D03*
X699000Y1604500D03*
X699500Y1599500D03*
X709382Y1601210D03*
X699500Y1608500D03*
X709020Y1609101D03*
X699424Y1616627D03*
X695933Y1623460D03*
X709260Y1617903D03*
X701114Y1640345D03*
X702683Y1633715D03*
X703563Y1644116D03*
X702402Y1650469D03*
X700528Y1661468D03*
X697503Y1661331D03*
X703102Y1665554D03*
X714471Y46670D03*
X724621Y40062D03*
X719821Y45862D03*
X714322Y56286D03*
X721163Y58588D03*
X714096Y73686D03*
X712717Y68541D03*
X719416Y68738D03*
Y74036D03*
X725016Y86952D03*
X720016D03*
X715745Y86300D03*
X712725Y84714D03*
X712291Y106722D03*
X715934Y117488D03*
Y114588D03*
X712734Y117488D03*
Y114588D03*
X720434Y135088D03*
X717434D03*
X719934Y124488D03*
X723134D03*
X712341Y128093D03*
X710284Y169826D03*
X717021Y220862D03*
X714867Y344943D03*
X717712Y346103D03*
X715500Y374362D03*
X719500D03*
X723531Y368862D03*
X723500Y360862D03*
X711500Y374362D03*
X715500Y360862D03*
X719500Y368862D03*
X715500D03*
X711363Y369274D03*
X711500Y382362D03*
X719640Y386862D03*
X723632D03*
X711500D03*
X715500D03*
X722500Y383162D03*
X723500Y390862D03*
X719500D03*
X715500D03*
X711500D03*
X716500Y521862D03*
X711617Y513531D03*
X724500Y517362D03*
X716500D03*
X720400Y517440D03*
X720452Y513362D03*
X716716Y513368D03*
X720499Y533474D03*
X719841Y537348D03*
X712113Y537797D03*
X720500Y555862D03*
Y546211D03*
X712115Y541872D03*
X712409Y555413D03*
X710464Y557036D03*
X722201Y579306D03*
X723483Y574890D03*
X714583Y590792D03*
X716181Y585562D03*
X715037Y606428D03*
X716313Y610134D03*
X719710Y612831D03*
X720787Y627907D03*
X716721D03*
X713343Y633842D03*
X724000Y633906D03*
X725812Y654713D03*
X715371Y654726D03*
X711702Y646533D03*
X711295Y665117D03*
X718129Y666725D03*
X722129D03*
X712164Y676912D03*
X712120Y680287D03*
X717515Y679833D03*
X720563Y679886D03*
X720613Y677040D03*
X723814Y736782D03*
X718349Y767300D03*
Y771100D03*
X721339Y1314048D03*
X711839Y1314348D03*
X721339Y1323048D03*
Y1320048D03*
Y1317048D03*
X715828Y1327277D03*
X710488Y1327177D03*
X713008D03*
X711839Y1323348D03*
Y1320348D03*
Y1317348D03*
X713008Y1329877D03*
Y1332377D03*
Y1334877D03*
X715828Y1332877D03*
Y1330377D03*
X713008Y1337377D03*
Y1339877D03*
X715828Y1335377D03*
X710288Y1339677D03*
Y1337177D03*
X710221Y1342488D03*
X710288Y1334677D03*
Y1332177D03*
Y1329677D03*
X710221Y1344988D03*
X712419Y1398094D03*
X719861Y1400139D03*
X716373Y1398539D03*
X719111Y1397571D03*
X712419Y1400602D03*
X709430Y1394417D03*
X722877Y1390881D03*
X712099Y1416973D03*
X714599D03*
X717099D03*
X712099Y1414473D03*
X714599D03*
X717099D03*
X709599Y1416973D03*
Y1414473D03*
X717099Y1432773D03*
X712099D03*
X714599D03*
X717099Y1430273D03*
X712099D03*
X714599D03*
X709599Y1432773D03*
Y1427373D03*
Y1424873D03*
Y1430273D03*
Y1419873D03*
Y1422373D03*
X714259Y1447483D03*
X719471Y1467422D03*
X711671D03*
X714271D03*
X716871D03*
X720217Y1472287D03*
X717617D03*
X715017D03*
X720926Y1469814D03*
X718326D03*
X715726D03*
X713126D03*
X716067Y1474792D03*
X718667D03*
X721267D03*
X717358Y1477038D03*
X719958D03*
X714474Y1566333D03*
X724110Y1561825D03*
X714110Y1581475D03*
X714900Y1571273D03*
X721963Y1576932D03*
X719963Y1578932D03*
X721440Y1570963D03*
X719963Y1585790D03*
X721963Y1587790D03*
X723590Y1595323D03*
X718892Y1597152D03*
X714372Y1594679D03*
X723408Y1608740D03*
X720106Y1609542D03*
X717798Y1607335D03*
X713718Y1610235D03*
X717229Y1612376D03*
X718129Y1624330D03*
X722104Y1626253D03*
X715744Y1622842D03*
X722889Y1622491D03*
X711298Y1632534D03*
X718122Y1636332D03*
X718116Y1639129D03*
X713771Y1654927D03*
X722480Y1657616D03*
X719117Y1682722D03*
X723181Y1688825D03*
X740101Y41162D03*
X736621Y45262D03*
X733315Y40862D03*
X728721Y43562D03*
X726789Y60562D03*
X738590Y59868D03*
X730785Y58068D03*
X728285Y58135D03*
X724645Y58362D03*
X734769Y60757D03*
X725769Y69737D03*
X736864Y74943D03*
X731864D03*
X727200Y73210D03*
X729918Y90998D03*
X739824Y91052D03*
X734380Y80518D03*
X729380D03*
X736650Y102350D03*
X735771Y94988D03*
X730660Y108484D03*
X728734Y132088D03*
Y129288D03*
Y126388D03*
X735500Y143000D03*
X724147Y345291D03*
X729211Y346379D03*
X726431Y346384D03*
X738773Y346716D03*
X734463Y346712D03*
X735500Y368862D03*
X734166Y360782D03*
X739500Y368862D03*
X727564D03*
X731500Y360862D03*
X731406Y374331D03*
X731500Y368862D03*
Y386862D03*
X739553Y388270D03*
X735500Y386862D03*
X727500D03*
X735500Y390862D03*
X727500D03*
X735500Y399330D03*
X738672Y494444D03*
X728938Y517520D03*
X724500Y513362D03*
X732500D03*
X739185Y521394D03*
X728500Y521862D03*
X724500D03*
X728500Y513362D03*
X736609Y518426D03*
X728500Y529862D03*
X728576Y537476D03*
X736500Y537862D03*
X724336Y537527D03*
X724433Y530870D03*
X732500Y529862D03*
X736647Y529772D03*
X732580Y537193D03*
X724697Y535053D03*
X728652Y545862D03*
X728695Y550943D03*
X736670Y545864D03*
X740500Y545862D03*
X724684Y545864D03*
X724281Y553438D03*
X728714Y554190D03*
X732520Y545988D03*
X736528Y576480D03*
Y579615D03*
X727253Y610689D03*
X724246Y627939D03*
X736362Y636854D03*
X730770Y644218D03*
X733382Y633574D03*
X729489Y666547D03*
X734442Y675695D03*
X730837Y678940D03*
X738486Y679139D03*
X724931Y678364D03*
X735316Y736742D03*
X725712Y734135D03*
X729391D03*
X727576Y736756D03*
X727448Y766871D03*
X735739Y1314048D03*
Y1320048D03*
Y1317048D03*
X724788Y1327277D03*
X727501Y1327230D03*
X730021D03*
X735739Y1323048D03*
X727401Y1332430D03*
Y1329930D03*
Y1334930D03*
X724788Y1330377D03*
Y1332877D03*
X727401Y1339930D03*
Y1337430D03*
X724788Y1335377D03*
X730021Y1337230D03*
Y1339730D03*
Y1334730D03*
Y1329730D03*
Y1332230D03*
X730795Y1342444D03*
Y1344944D03*
X738439Y1387127D03*
X728198Y1388026D03*
Y1385126D03*
X738439Y1389668D03*
X727737Y1390881D03*
X725307D03*
X734767Y1396986D03*
Y1394086D03*
X732567Y1392586D03*
X732667Y1395586D03*
X730501Y1397216D03*
Y1394316D03*
X734767Y1391186D03*
X735418Y1426122D03*
Y1423122D03*
Y1420122D03*
X732418Y1426122D03*
Y1423122D03*
Y1420122D03*
X735453Y1525368D03*
X737551Y1524008D03*
X727325Y1563400D03*
X727571Y1558353D03*
X736782Y1555496D03*
X730782D03*
X733782D03*
X727571Y1555353D03*
X733782Y1567496D03*
X736782D03*
X730782D03*
X733782Y1558496D03*
Y1561496D03*
X736782Y1558496D03*
Y1561496D03*
X733782Y1564496D03*
X736782D03*
X730782Y1558496D03*
Y1561496D03*
Y1564496D03*
X726475Y1571293D03*
X723963Y1578932D03*
X730782Y1570496D03*
X736782D03*
X733782D03*
X723963Y1585790D03*
X726550Y1599358D03*
X730647Y1623629D03*
X727320Y1623698D03*
X736723Y1623938D03*
X731119Y1647997D03*
X735642Y1648537D03*
X730347Y1682902D03*
X725638Y1682890D03*
X732852Y1695701D03*
X738030Y1723903D03*
Y1726903D03*
X738108Y1721157D03*
X738075Y1718082D03*
X746101Y46262D03*
X745901Y40362D03*
X749478Y59902D03*
X746588Y59754D03*
X740817Y58503D03*
X747488Y71429D03*
X740537Y73564D03*
X750034Y89988D03*
X750701Y106642D03*
X754783Y96553D03*
X750034Y92888D03*
X741309Y108742D03*
X748034Y116288D03*
X748261Y112552D03*
X743050Y139182D03*
X751221Y137864D03*
X743547Y147703D03*
X748915Y158608D03*
X745031Y161463D03*
X748125Y170618D03*
X751575Y184252D03*
X746522Y308804D03*
X750717Y319907D03*
X747594Y319106D03*
X747696Y332772D03*
X751337Y343849D03*
X748752Y343582D03*
X745132Y344964D03*
X752926Y361021D03*
X747500Y368862D03*
X751500D03*
X743500D03*
Y374362D03*
X749389Y360816D03*
X755135Y368907D03*
X754813Y374362D03*
X739500D03*
X747500D03*
X747454Y386817D03*
X751652Y386862D03*
X743500Y386962D03*
X739652Y390862D03*
X743500D03*
X747500D03*
X751500D03*
X747629Y406163D03*
X753252Y495234D03*
X748381Y495244D03*
X752652Y504106D03*
X752500Y517362D03*
X744500Y513362D03*
X748661Y517060D03*
X740500Y513362D03*
X752500D03*
X748500D03*
X753951Y521801D03*
X748077Y521789D03*
X740500Y537862D03*
X752965Y537678D03*
X748143Y530269D03*
X744916Y530268D03*
X752500Y529862D03*
X748000Y537862D03*
X741851Y553544D03*
X745645Y545880D03*
X752500Y545862D03*
X745091Y553563D03*
X748500Y545862D03*
X752195Y554761D03*
X748482Y557085D03*
X751731Y557714D03*
X739128Y566639D03*
X741624Y580707D03*
X741200Y577470D03*
X749131Y570340D03*
X750062Y655415D03*
X753309Y655515D03*
X750074Y648739D03*
X753483Y648749D03*
X751885Y666724D03*
X753231Y678679D03*
X742579Y676093D03*
X746665Y678879D03*
X750168Y675833D03*
X748049Y767300D03*
Y771100D03*
X745439Y1314048D03*
X748188Y1327317D03*
X745491Y1327124D03*
X742971D03*
X745439Y1323048D03*
Y1320048D03*
Y1317048D03*
X745691Y1332424D03*
Y1329924D03*
Y1334924D03*
X748188Y1333017D03*
Y1330517D03*
X745691Y1339924D03*
Y1337424D03*
X748188Y1335517D03*
X742971Y1337124D03*
Y1339624D03*
Y1334624D03*
Y1329624D03*
Y1332124D03*
X739501Y1342244D03*
Y1344744D03*
X739932Y1398042D03*
X745201Y1398194D03*
X752643Y1400239D03*
X749155Y1398639D03*
X751893Y1397671D03*
X745201Y1400702D03*
X742212Y1394517D03*
X739611Y1458211D03*
X750418Y1468893D03*
X750968Y1482349D03*
X746111Y1504125D03*
X745984Y1501052D03*
X745001Y1516471D03*
X750205Y1512307D03*
X750155Y1516451D03*
X739900Y1523152D03*
X748782Y1555496D03*
X742782D03*
X739782D03*
X745782D03*
X739782Y1558496D03*
Y1561496D03*
Y1564496D03*
X745782Y1558496D03*
X742782D03*
X745782Y1561496D03*
X742782D03*
X745782Y1564496D03*
X742782D03*
X739782Y1567496D03*
X742782D03*
X748782Y1558496D03*
Y1561496D03*
Y1564496D03*
X747110Y1575863D03*
X747150Y1583247D03*
X747110Y1579863D03*
X739782Y1570496D03*
X742782D03*
X747160Y1587773D03*
X749167Y1591967D03*
X754635Y1592571D03*
X743664Y1626945D03*
X753770Y1636083D03*
X751521Y1656008D03*
X739880Y1648046D03*
X742792Y1647982D03*
X745075Y1665675D03*
X754030Y1669256D03*
X748254Y1674771D03*
X752187Y1682994D03*
X748413Y1679367D03*
X746766Y1696036D03*
X740328Y1698376D03*
X747289Y1693063D03*
X752187Y1691058D03*
X741030Y1723903D03*
Y1726903D03*
X741160Y1721150D03*
X741025Y1718195D03*
X757721Y62132D03*
X760221D03*
X762721D03*
X755621Y51602D03*
X758621D03*
X757721Y64632D03*
X760221D03*
X763221Y65132D03*
X757188Y91829D03*
X757694Y98108D03*
Y100653D03*
X760193Y106500D03*
X757576Y112575D03*
X756000Y145500D03*
X754825Y163397D03*
X756303Y158417D03*
X765950Y190669D03*
X765000Y186500D03*
X754737Y185469D03*
X757629Y239295D03*
X761067Y280355D03*
X763384Y279231D03*
X763508Y284404D03*
X763463Y281840D03*
X760614Y284100D03*
X754759Y281007D03*
X758510Y298620D03*
X760462Y295662D03*
X757937Y303908D03*
X768130Y335363D03*
X758245Y343763D03*
X764331Y374401D03*
X756347Y360851D03*
X764983Y368052D03*
X766304Y372862D03*
X768304Y374362D03*
X759652D03*
X755500Y386862D03*
X759500D03*
X763500D03*
X767500D03*
X759500Y390791D03*
X755500Y390862D03*
X759500Y402098D03*
X767500Y401470D03*
Y390862D03*
X763500D03*
X757258Y408763D03*
X765975Y414414D03*
X769648Y430511D03*
X770530Y423460D03*
X768301Y438223D03*
X770918Y442510D03*
X770042Y446829D03*
X770590Y470940D03*
X762800Y493654D03*
X764500Y521862D03*
X756500Y513340D03*
X764500D03*
X756800Y517050D03*
X760500Y521189D03*
X764600Y517022D03*
X756186Y529888D03*
X764500Y529862D03*
X760500Y529845D03*
X757860Y537859D03*
X760660Y537862D03*
X756500Y545862D03*
X764500D03*
X759568Y545867D03*
X768340Y563678D03*
X765809Y563410D03*
X758103Y556873D03*
X765041Y565867D03*
X762530Y565340D03*
X757745Y655353D03*
X755765Y666904D03*
X762656Y667835D03*
X756936Y676319D03*
X768565Y677573D03*
X760529Y677715D03*
X764401Y676968D03*
X762396Y732915D03*
X754532Y735859D03*
X760425Y736233D03*
X764568Y736183D03*
X761608Y766871D03*
X759839Y1313948D03*
Y1319948D03*
X760204Y1327314D03*
X762754D03*
X759839Y1316948D03*
X757638Y1327317D03*
X759839Y1322948D03*
X760204Y1332514D03*
Y1330014D03*
Y1335014D03*
X757638Y1333017D03*
Y1330517D03*
X760194Y1340024D03*
Y1337524D03*
X757638Y1335517D03*
X762844Y1337324D03*
Y1339824D03*
X762754Y1334814D03*
Y1329814D03*
Y1332314D03*
X762261Y1343424D03*
Y1345924D03*
X760980Y1385146D03*
Y1388046D03*
X758089Y1390981D03*
X760519D03*
X755659D03*
X767549Y1391286D03*
Y1397086D03*
Y1394186D03*
X765349Y1392686D03*
X765449Y1395686D03*
X763283Y1397316D03*
Y1394416D03*
X758163Y1490789D03*
Y1498663D03*
Y1494726D03*
Y1502600D03*
Y1506538D03*
Y1522286D03*
Y1510474D03*
X757826Y1514412D03*
X758056Y1518349D03*
X760650Y1570633D03*
Y1578733D03*
Y1574733D03*
X757610Y1576023D03*
X766212Y1568043D03*
X757650Y1580023D03*
X766950Y1581233D03*
X757610Y1584023D03*
X767750Y1584108D03*
X757610Y1589023D03*
X760650Y1587733D03*
X760521Y1595500D03*
X759723Y1626161D03*
X755261Y1628208D03*
X758030Y1668583D03*
X754839Y1678069D03*
X768463Y1687769D03*
X757161Y1696424D03*
X768733Y1694485D03*
X781441Y118637D03*
X782819Y149471D03*
X780159Y146961D03*
X772270Y153728D03*
X771427Y158026D03*
X782712Y260466D03*
X777408Y256648D03*
X777421Y277962D03*
X779884Y281705D03*
X769790Y296231D03*
X777468Y296315D03*
X769861Y302462D03*
X782641Y310888D03*
X779681Y313053D03*
X770190Y312563D03*
X779121Y303410D03*
Y308755D03*
X780046Y328268D03*
X772119Y333537D03*
X771964Y339716D03*
X781812Y341863D03*
X779118Y341749D03*
X769000Y364000D03*
X776500Y371000D03*
X784500Y367500D03*
X771512Y386862D03*
X775388Y390862D03*
X770000Y380787D03*
X777612Y403505D03*
X771512Y390862D03*
X780295Y403538D03*
X784498Y396353D03*
X782700Y415284D03*
X773181Y415197D03*
X773233Y409154D03*
X783256Y409340D03*
X770159Y410257D03*
X783770Y422454D03*
X772610Y434690D03*
X780877Y427344D03*
X771718Y426804D03*
X780877Y423344D03*
X783821Y431534D03*
X780877Y431368D03*
X772677Y451374D03*
X780577Y435564D03*
X780877Y443344D03*
Y447344D03*
X780977Y459524D03*
X780877Y463344D03*
Y455344D03*
X783377Y451344D03*
X780877Y475344D03*
X780759Y479344D03*
X783877Y475344D03*
X772427D03*
X783759Y479344D03*
X780877Y483344D03*
X772390Y491047D03*
X772427Y487344D03*
X783358Y495344D03*
X783351Y499221D03*
X771039Y511292D03*
X775100Y502504D03*
X772427Y495344D03*
X777166Y504477D03*
X774998Y511306D03*
X774964Y514204D03*
X772100Y532700D03*
X777200Y530250D03*
X772000Y529862D03*
X781699Y536425D03*
X772000Y545862D03*
X776345Y545733D03*
X777754Y558740D03*
X773463Y563455D03*
X778747Y572269D03*
X779448Y632498D03*
X772459Y655290D03*
X771553Y677963D03*
X777750Y767300D03*
Y771100D03*
X783280Y1296009D03*
X778030Y1296259D03*
X780530D03*
X783280Y1298509D03*
X785520Y1292160D03*
X769439Y1313948D03*
X783280Y1301009D03*
X769439Y1319948D03*
Y1322948D03*
Y1316948D03*
X770881Y1343344D03*
X782115Y1334173D03*
X770881Y1345844D03*
X774646Y1516441D03*
X772906Y1522901D03*
X774616Y1520361D03*
X778850Y1556133D03*
X781850D03*
Y1559133D03*
Y1562133D03*
Y1565133D03*
X778850Y1559133D03*
Y1562133D03*
Y1565133D03*
X771450Y1577333D03*
X781850Y1568133D03*
Y1571133D03*
X778850Y1568133D03*
Y1571133D03*
X771550Y1587133D03*
X774420Y1587284D03*
X785181Y120947D03*
X792681D03*
X790181D03*
X787681D03*
X783941Y118637D03*
X786441D03*
X788941D03*
X785529Y270459D03*
X798205Y279146D03*
X794058Y301569D03*
X793221Y296062D03*
X793897Y309026D03*
X793855Y305316D03*
X798493Y301377D03*
X795921Y312662D03*
X787500Y328362D03*
X799226Y328467D03*
X791726D03*
X783726D03*
X785674Y342279D03*
X788806Y342236D03*
X791403Y342262D03*
X793951Y342224D03*
X795685Y357498D03*
X792302Y357537D03*
X798312Y372571D03*
X796021Y395924D03*
X797000Y404000D03*
X786571Y403455D03*
X785923Y419194D03*
X787000Y407500D03*
X796283Y415344D03*
Y419344D03*
X786877Y427344D03*
X796283Y423344D03*
Y431344D03*
X783877Y427344D03*
X796283D03*
X786999Y435476D03*
X797252Y443344D03*
X786877D03*
X796333Y435344D03*
X786203Y447054D03*
X783877Y435444D03*
X797197Y447344D03*
X786887Y451344D03*
X797252D03*
X797322Y463344D03*
X786825Y459518D03*
X786755Y455524D03*
X797252Y455344D03*
X797326Y479344D03*
X786877Y471344D03*
X797463Y476159D03*
X786877Y475344D03*
X786440Y480769D03*
X797405Y487464D03*
X797326Y483344D03*
X787092Y490681D03*
X786358Y483566D03*
X786102Y507536D03*
X787446Y495344D03*
X787279Y499238D03*
X790503Y501826D03*
X799450Y511801D03*
X800674Y504130D03*
X789125Y529425D03*
X800500Y540500D03*
X794357Y559996D03*
X785919Y559660D03*
X792782Y565323D03*
X791723Y574946D03*
X799742Y628983D03*
X789135Y617097D03*
X783653Y631671D03*
X787591Y631785D03*
X788537Y734410D03*
X793131Y734310D03*
X784543Y734510D03*
X791308Y766871D03*
X789020Y1292160D03*
X792520D03*
X796020D03*
X794273Y1354600D03*
Y1357600D03*
Y1364500D03*
Y1361500D03*
X784669Y1462178D03*
X796955Y1487468D03*
X788710Y1488821D03*
X784277Y1504569D03*
Y1500632D03*
Y1508506D03*
Y1512443D03*
X791867Y1524254D03*
X784850Y1556133D03*
X796850D03*
X790850D03*
X787850D03*
X793850D03*
X784850Y1559133D03*
Y1562133D03*
Y1565133D03*
X796850Y1559133D03*
Y1562133D03*
Y1565133D03*
X787850Y1559133D03*
Y1562133D03*
Y1565133D03*
X793850Y1559133D03*
X790850D03*
X793850Y1562133D03*
X790850D03*
X793850Y1565133D03*
X790850D03*
X799150Y1581379D03*
X784850Y1568133D03*
Y1571133D03*
X787850Y1568133D03*
Y1571133D03*
X793850Y1568133D03*
X790850D03*
X793850Y1571133D03*
X790850D03*
X796650Y1583347D03*
X803302Y265848D03*
X812867Y278860D03*
X810139Y274098D03*
X804330Y281380D03*
X801341Y279141D03*
X799935Y286823D03*
X799113Y297733D03*
X803893Y301969D03*
X805871Y304812D03*
X806461Y310610D03*
X808617Y330102D03*
X806117D03*
X812070Y341590D03*
X803410Y341572D03*
X803500Y366000D03*
X802660Y381020D03*
X802462Y387756D03*
X807564Y403805D03*
X811224Y395974D03*
X803412Y403978D03*
X813148Y403908D03*
X805425Y395502D03*
X813252Y427060D03*
X802270Y435372D03*
X802459Y443218D03*
X813208Y435344D03*
X812895Y449802D03*
X813114Y443344D03*
X802533Y449802D03*
X812983Y463578D03*
X813114Y459344D03*
X801552Y463318D03*
X802752Y459344D03*
X813114Y455344D03*
X812983Y471344D03*
Y476159D03*
X801874Y471344D03*
X802752Y480159D03*
X812983D03*
X813000Y484862D03*
X801762Y495344D03*
X802752Y487344D03*
X801753Y491344D03*
X813187Y498362D03*
X813114Y495344D03*
X802250Y500504D03*
X801857Y508031D03*
X805940Y534500D03*
X805341Y578059D03*
X805199Y620347D03*
X804863Y626789D03*
X805150Y623843D03*
X807451Y767299D03*
X807127Y770958D03*
X799280Y1296009D03*
X802030Y1296259D03*
X804530D03*
X807601Y1299241D03*
X799280Y1298509D03*
Y1301009D03*
X801614Y1339062D03*
X811771Y1355488D03*
X799071Y1350088D03*
X807866Y1369177D03*
X805366Y1367093D03*
X802866D03*
X807866Y1366677D03*
X808714Y1490376D03*
Y1487376D03*
Y1506784D03*
Y1519784D03*
Y1509784D03*
Y1516784D03*
X802150Y1570633D03*
Y1578633D03*
Y1582833D03*
X810150Y1574633D03*
X813150Y1579410D03*
Y1570633D03*
X810050Y1584033D03*
X802150Y1594633D03*
X810850Y1587733D03*
X810150Y1590633D03*
X813049D03*
X802700Y1587183D03*
X810150Y1602633D03*
Y1598633D03*
X802150Y1606633D03*
X819321Y56961D03*
X823115Y115223D03*
X820901Y147112D03*
X814571Y145952D03*
X814532Y139851D03*
X822635Y165468D03*
X825332Y166862D03*
X813676Y266065D03*
X823067Y273225D03*
X823038Y276301D03*
X819828Y288063D03*
X827621Y302962D03*
X822689Y305148D03*
X826915Y311842D03*
X822252Y309973D03*
X816232Y341584D03*
X818677Y356405D03*
X826765Y356334D03*
X817780Y366905D03*
X823778Y376378D03*
X818157Y381020D03*
X816991Y395337D03*
X820018Y403710D03*
X816281Y403814D03*
X828286Y401567D03*
X824653Y405347D03*
X817497Y415344D03*
X827341Y419344D03*
X817497D03*
X827341Y415344D03*
X817497Y427060D03*
X826474Y431344D03*
X816239Y435344D03*
X817497Y431060D03*
X826474Y435344D03*
X816117Y443552D03*
X816236Y439279D03*
X816109Y449802D03*
X822878Y446425D03*
X816109Y455344D03*
X816000Y463578D03*
X816170Y458524D03*
X826912Y475989D03*
X816109Y471344D03*
X816409Y467568D03*
X817393Y491594D03*
X830212Y483892D03*
X826472Y483896D03*
X827000Y489055D03*
X817996Y496219D03*
X828259Y501027D03*
X824380Y517595D03*
X827237Y550771D03*
X817849Y550871D03*
X820620Y550846D03*
X824366Y552444D03*
X827832Y554269D03*
X814489Y558082D03*
X825200Y580300D03*
X815287Y580401D03*
X820617Y641273D03*
X816732Y629198D03*
X815753Y644219D03*
X817900Y649012D03*
X822579Y760169D03*
X822218Y756979D03*
X822794Y767511D03*
X825390Y770020D03*
X822794Y777511D03*
X816550Y766871D03*
X822625Y763529D03*
X822794Y772511D03*
Y775011D03*
X825061Y764884D03*
X822864Y783262D03*
X822772Y788359D03*
X822790Y785838D03*
X822883Y780334D03*
X822982Y791245D03*
X822555Y807409D03*
X822794Y797511D03*
Y800011D03*
Y795011D03*
X822494Y802941D03*
X823927Y907676D03*
X823958Y936140D03*
X826958D03*
X823958Y939140D03*
X826958D03*
X827088Y933387D03*
X824036Y933394D03*
X826953Y930432D03*
X824003Y930319D03*
X828109Y1234504D03*
X826728Y1246315D03*
X824444Y1249420D03*
X828246Y1266501D03*
X824714Y1490376D03*
Y1487376D03*
X816690Y1490376D03*
Y1487376D03*
X824714Y1500376D03*
Y1497376D03*
Y1506784D03*
X816717Y1500388D03*
X816729Y1497364D03*
X816693Y1506784D03*
X824714Y1519784D03*
Y1509784D03*
Y1516784D03*
X816706Y1519820D03*
X816693Y1516784D03*
X816694Y1509796D03*
X824714Y1529784D03*
Y1526784D03*
X816714Y1529784D03*
Y1526784D03*
X823850Y1556133D03*
X820850D03*
X826850D03*
X820850Y1565133D03*
Y1562133D03*
Y1559133D03*
X826850Y1565133D03*
X823850D03*
X826850Y1562133D03*
Y1559133D03*
X823850Y1562133D03*
Y1559133D03*
X820850Y1571133D03*
Y1568133D03*
X826850Y1571133D03*
Y1568133D03*
X823850Y1571133D03*
Y1568133D03*
X816150Y1587284D03*
X828601Y61752D03*
X836780Y68008D03*
X839899Y87248D03*
X841585Y94181D03*
X837251Y93221D03*
X839361Y114862D03*
X835115Y115223D03*
X845221Y135862D03*
Y129362D03*
X829115Y147123D03*
X838221Y163862D03*
X835221D03*
X842721Y181362D03*
X837161Y213207D03*
X844527Y204968D03*
X838821Y206872D03*
X837161Y218212D03*
X837501Y229642D03*
X836305Y268624D03*
X836181Y275686D03*
X830418Y311865D03*
X837754Y335345D03*
X829800Y331013D03*
X840457Y335368D03*
X842257Y350376D03*
X829344Y356224D03*
X833219Y375992D03*
X840357Y382813D03*
X833097Y393000D03*
X837912Y401545D03*
X834426Y401504D03*
X833000Y409500D03*
X838500D03*
X837847Y405347D03*
X833807Y423257D03*
X841809Y423219D03*
X838000Y423362D03*
X829106Y439279D03*
X842825Y448739D03*
X828979Y449802D03*
X834106Y439279D03*
X828714Y443552D03*
X833800Y444700D03*
X828751Y455344D03*
Y463578D03*
X834251Y455578D03*
X828751Y459344D03*
X832224Y450328D03*
X831381Y455167D03*
X833751Y463578D03*
X842825Y452739D03*
X828751Y471344D03*
Y467568D03*
X838575Y477554D03*
X839200Y467900D03*
X830046Y476031D03*
X838561Y484071D03*
X841854Y504972D03*
X833000Y503500D03*
X831798Y515314D03*
X838342Y514610D03*
X839061Y555808D03*
X841660Y558200D03*
X835519Y580056D03*
X831018Y583076D03*
X835059Y660940D03*
X837391Y659820D03*
X831505Y897291D03*
X831582Y905153D03*
X832347Y1251703D03*
X844250Y1266759D03*
X832274Y1277301D03*
X832342Y1274626D03*
X833756Y1330156D03*
X834017Y1336252D03*
X833963Y1339464D03*
X838963Y1345974D03*
X833853Y1345833D03*
X841039Y1358082D03*
X839244Y1352094D03*
X841472Y1365050D03*
X835850Y1556133D03*
X829850D03*
X832850D03*
X838850D03*
X832850Y1565133D03*
X835850D03*
X832850Y1562133D03*
X835850D03*
X832850Y1559133D03*
X835850D03*
X829850Y1565133D03*
Y1562133D03*
Y1559133D03*
X838850Y1565133D03*
Y1562133D03*
Y1559133D03*
X841150Y1581379D03*
X832850Y1571133D03*
X835850D03*
X832850Y1568133D03*
X835850D03*
X829850Y1571133D03*
Y1568133D03*
X838650Y1583347D03*
X850016Y87341D03*
X843856Y87711D03*
X847473Y94754D03*
X854221Y135862D03*
Y129362D03*
X854201Y143062D03*
X848745Y160137D03*
X845721Y181362D03*
X856213Y191545D03*
X855859Y212425D03*
X855934Y215375D03*
X847581Y232222D03*
X853621Y269057D03*
X853829Y262057D03*
X846189Y281419D03*
X856244Y286447D03*
X843504Y287602D03*
X855481Y299692D03*
X860071Y304850D03*
X843308Y335550D03*
X857187Y342210D03*
X848030Y338461D03*
X850155Y335042D03*
X852303Y337488D03*
X852177Y341882D03*
X848425Y378089D03*
X854552Y381000D03*
X854190Y404035D03*
X855722Y416606D03*
X846000Y418862D03*
X854239Y412911D03*
X851517Y411745D03*
X846000Y423362D03*
X845986Y429413D03*
X857942Y448575D03*
X845100Y440100D03*
X857887Y459847D03*
X848500Y452128D03*
X847686Y475915D03*
X847303Y485788D03*
X846104Y494661D03*
X847518Y490905D03*
X846411Y482128D03*
X849772Y494585D03*
X852209Y507211D03*
X855497Y507205D03*
X849351Y499070D03*
X848097Y503315D03*
X855837Y519713D03*
X847941Y538325D03*
X845094Y535110D03*
X844741Y543864D03*
X843655Y555683D03*
X847435Y555496D03*
X856647Y616786D03*
X854484Y647436D03*
X848999Y644995D03*
X846931Y1291468D03*
X846895Y1295981D03*
X845801Y1287776D03*
X851500Y1302000D03*
X851400Y1305499D03*
X852811Y1313450D03*
X850684Y1310000D03*
X852955Y1320320D03*
X856500Y1321500D03*
X853100Y1331688D03*
X856500Y1330500D03*
X852780Y1338365D03*
X856500Y1339500D03*
Y1348500D03*
X844150Y1578633D03*
Y1570633D03*
Y1582833D03*
X852150Y1574633D03*
X855150Y1579410D03*
Y1570633D03*
X852050Y1584033D03*
X844150Y1594633D03*
X852850Y1587733D03*
X852150Y1590633D03*
X855049D03*
X844700Y1587183D03*
X852150Y1602633D03*
Y1598633D03*
X844150Y1606633D03*
X858630Y60293D03*
X863343Y90021D03*
X865912Y89252D03*
X870892Y131868D03*
X871145Y163862D03*
X875170Y185113D03*
X867529Y231788D03*
X863104Y273103D03*
X868104D03*
X867701Y267537D03*
X863230Y280001D03*
X866619Y286801D03*
X870672Y295485D03*
X870008Y302273D03*
X872508D03*
X871099Y323000D03*
X864342Y330858D03*
X860942D03*
X860587Y342210D03*
X860372Y375195D03*
X866168Y374774D03*
X871190Y382230D03*
X858925Y398537D03*
X864826Y411557D03*
X870220Y430424D03*
X870826Y423423D03*
X870064Y427703D03*
X859500Y429362D03*
X863420D03*
X859469Y425293D03*
X860541Y446089D03*
X860328Y475162D03*
X858288Y467048D03*
X860280Y488636D03*
X860299Y491620D03*
X864361Y493001D03*
X860508Y497772D03*
X862987Y507305D03*
X860341Y503154D03*
X860658Y515961D03*
X867356Y558714D03*
X867733Y575522D03*
X864590Y642420D03*
X870590D03*
X866727Y650739D03*
X866549Y748027D03*
X869275Y750472D03*
X873175D03*
X868496Y776516D03*
X868539Y790882D03*
X870591Y785437D03*
X865466Y790581D03*
Y785581D03*
Y788081D03*
Y783081D03*
X865394Y801244D03*
X865466Y793081D03*
Y795581D03*
Y798081D03*
X865569Y806045D03*
Y808545D03*
X863369Y827461D03*
X863344Y824713D03*
X863372Y833469D03*
Y830718D03*
X867651Y836820D03*
X867646Y833388D03*
X863671Y839062D03*
X865601Y841219D03*
X865109Y850795D03*
X864768Y844815D03*
X864140Y856052D03*
X864020Y859972D03*
X864106Y863534D03*
X864003Y866609D03*
X866005Y941554D03*
X863055Y941441D03*
X863010Y947262D03*
X866010D03*
X863010Y950262D03*
X866010D03*
X866140Y944509D03*
X863088Y944516D03*
X862044Y1249687D03*
X866294Y1255903D03*
X874989Y1410441D03*
X863745Y1444560D03*
X871214Y1466542D03*
X865850Y1556133D03*
X871850D03*
X862850D03*
X868850D03*
X865850Y1565133D03*
Y1562133D03*
Y1559133D03*
X862850Y1565133D03*
Y1562133D03*
Y1559133D03*
X868850Y1565133D03*
X871850D03*
X868850Y1562133D03*
X871850D03*
X868850Y1559133D03*
X871850D03*
X865850Y1571133D03*
Y1568133D03*
X862850Y1571133D03*
Y1568133D03*
X868850Y1571133D03*
X871850D03*
X868850Y1568133D03*
X871850D03*
X858150Y1587284D03*
X876696Y176862D03*
Y171362D03*
X887521D03*
Y176862D03*
X889351Y195489D03*
X878328Y183169D03*
X878221Y187449D03*
X887130Y183169D03*
X884986Y198829D03*
X881354Y267407D03*
X884004Y278712D03*
Y274482D03*
X885764Y284361D03*
X877448Y284825D03*
X884004Y271332D03*
X874244Y287047D03*
X873172Y295485D03*
X888000Y293000D03*
X877640Y315789D03*
X873884Y447991D03*
Y450491D03*
X885916Y653912D03*
X883731Y651690D03*
X884410Y794332D03*
X883633Y790336D03*
X883776Y786814D03*
X877459Y802356D03*
X875412Y797350D03*
X882582Y1075083D03*
X879582D03*
X876582D03*
X873582D03*
X882582Y1061983D03*
X879582D03*
X876582D03*
Y1071533D03*
Y1068533D03*
Y1065533D03*
X873582D03*
Y1068533D03*
Y1071533D03*
Y1061983D03*
X886707Y1229920D03*
Y1232920D03*
X881807Y1238920D03*
X876923Y1239520D03*
X886707Y1235920D03*
X881694Y1229763D03*
Y1232763D03*
Y1235763D03*
X876907Y1235586D03*
Y1232586D03*
Y1229586D03*
X881807Y1241920D03*
X877936Y1312336D03*
X883379Y1417881D03*
X875039Y1407246D03*
X886362Y1428973D03*
X884399Y1431507D03*
X879424Y1425001D03*
X883279Y1421726D03*
X883562Y1440356D03*
X881987Y1449608D03*
X887519Y1444625D03*
X877226Y1441585D03*
X887117Y1436735D03*
X877850Y1556133D03*
X874850D03*
X880850D03*
X874850Y1565133D03*
X877850D03*
X880850D03*
X874850Y1562133D03*
X877850D03*
X880850D03*
X874850Y1559133D03*
X877850D03*
X880850D03*
X886150Y1578633D03*
Y1570633D03*
Y1582833D03*
X883150Y1581379D03*
X874850Y1571133D03*
X877850D03*
X874850Y1568133D03*
X877850D03*
X886150Y1594633D03*
X880650Y1583347D03*
X886700Y1587183D03*
X886150Y1606633D03*
X891621Y207162D03*
X888930Y206823D03*
X891621Y209662D03*
X888930Y209323D03*
X896621Y207162D03*
X894121D03*
Y209662D03*
X896621D03*
X892376Y466430D03*
X899000Y481038D03*
X888372Y547518D03*
X902376Y590172D03*
X900323Y604377D03*
X900301Y828248D03*
Y831221D03*
X899500Y853000D03*
X901000Y909000D03*
X901842Y936863D03*
X903925Y948500D03*
X889273Y1134470D03*
X902382Y1137558D03*
X891996Y1149707D03*
X900280Y1150769D03*
X902482Y1140558D03*
X888247Y1219520D03*
Y1222520D03*
X891247D03*
Y1219520D03*
X888247Y1225520D03*
X896974Y1232869D03*
Y1235869D03*
X896907Y1238920D03*
X896974Y1229869D03*
X891247Y1225520D03*
X896907Y1241920D03*
X892000Y1307500D03*
X888854Y1337936D03*
X890620Y1342990D03*
X900885Y1435041D03*
X900808Y1437798D03*
X902377Y1456465D03*
X904850Y1556133D03*
X894150Y1574633D03*
X897150Y1579410D03*
Y1570633D03*
X894050Y1584033D03*
X894150Y1590633D03*
X894850Y1587733D03*
X897049Y1590633D03*
X900150Y1587284D03*
X894150Y1602633D03*
Y1598633D03*
X917387Y184114D03*
X908621Y188899D03*
X910267Y242658D03*
X910093Y246015D03*
X916268Y269859D03*
X909023Y294734D03*
X910752Y286141D03*
X913512Y486743D03*
X903340Y505105D03*
X917582Y549564D03*
X909747Y579695D03*
X911980Y585280D03*
X910731Y590251D03*
X905526Y594657D03*
X910535Y619251D03*
X906706Y614062D03*
X909747Y628426D03*
X915334Y639166D03*
X908823Y655116D03*
X906274Y654921D03*
X909320Y663930D03*
X907207Y667646D03*
X906345Y742414D03*
X904535Y744639D03*
X906387Y821221D03*
Y815721D03*
X906313Y825095D03*
X903149Y825094D03*
X917000Y853000D03*
X907000Y899777D03*
X913000Y909000D03*
X917000D03*
Y918500D03*
X905000D03*
X915575Y948500D03*
X910000Y954500D03*
X912425Y948500D03*
X907075D03*
X910000Y957500D03*
X912500Y963309D03*
X907500D03*
X909000Y974000D03*
Y982000D03*
X911041Y979459D03*
X909000Y977491D03*
X919779Y1155658D03*
X915053Y1219520D03*
Y1222520D03*
X912053D03*
Y1219520D03*
Y1225520D03*
X915053D03*
X910707Y1229920D03*
Y1232920D03*
X905007Y1238920D03*
X910707Y1235920D03*
X905008Y1229940D03*
Y1232940D03*
Y1235940D03*
X905007Y1241920D03*
X917112Y1266300D03*
X917127Y1275251D03*
X917396Y1271025D03*
X917158Y1279451D03*
X917341Y1283775D03*
X916895Y1292330D03*
X916945Y1296713D03*
X917034Y1288235D03*
X912500Y1310000D03*
X914333Y1322700D03*
X914462Y1329351D03*
X914355Y1340726D03*
X914276Y1347550D03*
X913270Y1440429D03*
X910041Y1440536D03*
X907031Y1457231D03*
X909473Y1448779D03*
X910850Y1556133D03*
X907850D03*
X916850D03*
X913850D03*
X907850Y1559133D03*
Y1562133D03*
X910850Y1559133D03*
Y1562133D03*
X907850Y1565133D03*
X910850D03*
X904850Y1559133D03*
Y1562133D03*
Y1565133D03*
X913850Y1559133D03*
Y1562133D03*
Y1565133D03*
X916850Y1559133D03*
Y1562133D03*
Y1565133D03*
X907850Y1568133D03*
Y1571133D03*
X910850Y1568133D03*
Y1571133D03*
X904850Y1568133D03*
Y1571133D03*
X913850Y1568133D03*
Y1571133D03*
X916850Y1568133D03*
Y1571133D03*
X915991Y1667328D03*
X922128Y182486D03*
X923386Y193563D03*
X932129Y244103D03*
X922341Y263875D03*
X923103Y362852D03*
X924724Y372211D03*
X919294Y374503D03*
X921318Y372475D03*
X920018Y362877D03*
X921430Y507156D03*
X921367Y503407D03*
X924430Y507156D03*
X924367Y503407D03*
X922591Y496671D03*
X926730Y540897D03*
X921318Y549357D03*
X920031Y577846D03*
X926449Y577806D03*
X930406Y577308D03*
X923747Y584945D03*
X920989Y614132D03*
X925643Y616620D03*
X920989Y617692D03*
X924987Y622523D03*
X932000Y850500D03*
X920234Y843349D03*
X927777Y843416D03*
X930575Y864075D03*
X918500Y860075D03*
X920897Y881879D03*
X929603Y879000D03*
X920000Y895500D03*
X923000D03*
X925500Y907500D03*
X921000Y921925D03*
X925500Y916500D03*
X929500D03*
X932500Y941500D03*
X919500D03*
X928500D03*
X923500D03*
X926000Y949500D03*
Y946500D03*
X919272Y986782D03*
X920107Y1235920D03*
Y1232920D03*
Y1238920D03*
Y1229920D03*
Y1241920D03*
X924500Y1306000D03*
Y1302000D03*
X918000Y1312500D03*
Y1321500D03*
X925459Y1315352D03*
X925500Y1319000D03*
X922000Y1324000D03*
Y1328000D03*
X931326Y1328467D03*
X931216Y1323050D03*
X918000Y1330500D03*
Y1339500D03*
X922000Y1342000D03*
X925500Y1333000D03*
Y1337000D03*
X922000Y1346000D03*
X922850Y1556133D03*
X919850D03*
X922850Y1559133D03*
Y1562133D03*
Y1565133D03*
X919850Y1559133D03*
Y1562133D03*
Y1565133D03*
X925650Y1581379D03*
X919850Y1568133D03*
Y1571133D03*
X922650Y1583347D03*
X921289Y1666337D03*
X927798Y1660762D03*
X945721Y173389D03*
X943221D03*
Y176389D03*
X945721D03*
X935551Y173329D03*
X938161Y173389D03*
Y176389D03*
X935591Y176049D03*
X940721Y173389D03*
Y176389D03*
X939271Y191419D03*
X935771D03*
X944520Y182094D03*
X936454Y184015D03*
X937267Y189010D03*
X945120Y193264D03*
X938570Y233152D03*
X945380Y233962D03*
X949181Y280131D03*
X939938Y386423D03*
X933390Y386405D03*
X944112Y386593D03*
X941764Y420403D03*
X944264D03*
X933390Y559943D03*
X939613Y562031D03*
X937310Y580755D03*
X941764Y587884D03*
X944264D03*
X935766Y587692D03*
X939511Y597073D03*
X935746Y611573D03*
X935783Y631192D03*
X937580Y655946D03*
X945602Y664653D03*
X934539Y664648D03*
X934339Y668533D03*
X941478Y668648D03*
X939216Y664767D03*
X948644Y811190D03*
X938000Y862620D03*
X943000Y862823D03*
X934925Y891425D03*
X945075Y891500D03*
X938500Y907500D03*
X946500Y915988D03*
X938500Y916500D03*
X934500D03*
X942500Y916340D03*
X942631Y943162D03*
X936960Y942898D03*
X935368Y939182D03*
X944515Y939850D03*
X940000Y973500D03*
Y986500D03*
Y982500D03*
Y977500D03*
X937148Y1134343D03*
X933234Y1145058D03*
X936393Y1148087D03*
X947305Y1150769D03*
X943101Y1219520D03*
Y1222520D03*
X946101D03*
Y1219520D03*
X943101Y1225520D03*
X946101D03*
X945691Y1229920D03*
Y1232920D03*
X940791Y1238920D03*
X935907Y1239520D03*
X945691Y1235920D03*
X940678Y1229763D03*
Y1232763D03*
Y1235763D03*
X935891Y1235586D03*
Y1232586D03*
Y1229586D03*
X940791Y1241920D03*
X940994Y1265636D03*
X941011Y1269499D03*
X941500Y1278059D03*
X941033Y1282115D03*
X946730Y1293219D03*
Y1290719D03*
X940919Y1290152D03*
X940937Y1294191D03*
X941083Y1286156D03*
X947135Y1287403D03*
X945872Y1304541D03*
Y1301500D03*
X945617Y1309500D03*
X935028Y1313769D03*
X935300Y1317525D03*
X939071Y1448219D03*
X949216Y1448337D03*
X944105Y1448317D03*
X946402Y1491204D03*
X943902D03*
X936402D03*
X938902D03*
X941402D03*
X933778D03*
X946402Y1501204D03*
Y1498704D03*
Y1496204D03*
Y1493704D03*
X943902D03*
Y1496204D03*
Y1498704D03*
Y1501204D03*
X936402Y1493704D03*
Y1496204D03*
Y1498704D03*
Y1501204D03*
X938902Y1493704D03*
Y1496204D03*
Y1498704D03*
Y1501204D03*
X941402Y1493704D03*
Y1496204D03*
Y1498704D03*
Y1501204D03*
X933778Y1493704D03*
Y1496204D03*
Y1498704D03*
Y1501204D03*
X936150Y1582233D03*
Y1578233D03*
Y1590233D03*
Y1586233D03*
X943798Y1660762D03*
X948401Y176499D03*
X961407Y205125D03*
X950950Y284662D03*
X947821Y386567D03*
X958158Y449020D03*
X958049Y453912D03*
X958101Y457846D03*
X958255Y465811D03*
X959033Y487289D03*
X957380Y515233D03*
X960054Y516982D03*
X962035Y518988D03*
X954757Y593045D03*
X948156Y593912D03*
X952497Y614080D03*
X951102Y628662D03*
X954362Y633314D03*
Y630061D03*
X954259Y657371D03*
X958299Y659886D03*
X954361Y660215D03*
X957462Y668700D03*
X951886Y804495D03*
X951895Y808163D03*
X951466Y816400D03*
X961592Y821737D03*
X949000Y850500D03*
X951000Y855425D03*
X958000Y865500D03*
Y862000D03*
X949500Y870500D03*
Y886500D03*
X953925Y900500D03*
X951169Y910425D03*
X957075Y906500D03*
X960925D03*
X954500Y915988D03*
X950500Y916150D03*
X948500Y937000D03*
X949407Y1137558D03*
X949507Y1140558D03*
X955958Y1232869D03*
Y1235869D03*
X955891Y1238920D03*
X955958Y1229869D03*
X955891Y1241920D03*
X964669Y1271000D03*
X963500Y1275000D03*
X955000Y1283000D03*
Y1287000D03*
X947650Y1314500D03*
Y1319000D03*
Y1323500D03*
Y1328000D03*
Y1337000D03*
Y1332500D03*
Y1341500D03*
Y1346000D03*
X960313Y1362654D03*
X958306Y1448056D03*
X954541Y1448307D03*
X961566Y1448341D03*
X953902Y1491204D03*
X951402D03*
X948902D03*
X956402D03*
X958902D03*
X961402D03*
X953902Y1501204D03*
Y1498704D03*
Y1496204D03*
Y1493704D03*
X951402Y1501204D03*
Y1498704D03*
Y1496204D03*
Y1493704D03*
X948902Y1501204D03*
Y1498704D03*
Y1496204D03*
Y1493704D03*
X956402D03*
X958902D03*
X961402D03*
X963402Y1501204D03*
X958402D03*
X959584Y1550824D03*
X949195Y1655145D03*
X951798Y1660762D03*
X975691Y161220D03*
X962673Y170263D03*
Y167763D03*
X967943Y204813D03*
X971943D03*
X975749Y202049D03*
X977221Y205399D03*
X964807Y205125D03*
X973997Y320848D03*
X966278Y556736D03*
X964114Y554704D03*
X976528Y801041D03*
Y803541D03*
Y806041D03*
Y808541D03*
X963500Y854719D03*
X973562Y859767D03*
X964075Y900500D03*
X966804Y1155658D03*
X969907Y1219520D03*
Y1222520D03*
X966907D03*
Y1219520D03*
Y1225520D03*
X969907D03*
X969691Y1229920D03*
Y1232920D03*
X963991Y1238920D03*
X969691Y1235920D03*
X963992Y1229940D03*
Y1232940D03*
Y1235940D03*
X979091Y1229920D03*
X963991Y1241920D03*
X964000Y1267000D03*
X966441Y1278145D03*
X972408Y1312557D03*
X973650Y1431424D03*
X969785Y1447987D03*
X967002Y1448013D03*
X964503Y1448097D03*
X969519Y1452784D03*
X973255Y1456714D03*
X975703Y1451367D03*
X967268Y1491204D03*
X969768D03*
X972268D03*
X974768D03*
X977268D03*
X963902D03*
X967268Y1501204D03*
Y1498704D03*
Y1496204D03*
Y1493704D03*
X969768D03*
Y1496204D03*
Y1498704D03*
Y1501204D03*
X972268Y1493704D03*
Y1496204D03*
Y1498704D03*
Y1501204D03*
X974768Y1493704D03*
Y1496204D03*
Y1498704D03*
Y1501204D03*
X977268Y1493704D03*
Y1496204D03*
Y1498704D03*
Y1501204D03*
X963902Y1493704D03*
X962584Y1550824D03*
X990579Y155248D03*
X981112Y161204D03*
X988751Y167541D03*
X986447Y158209D03*
X989605Y175400D03*
X985922Y171861D03*
X985445Y185389D03*
X986021Y195099D03*
X979849Y202049D03*
X983879Y202162D03*
X990221Y199699D03*
X987321Y198599D03*
Y202099D03*
X990221Y206699D03*
Y203199D03*
X987321Y205599D03*
X980406Y218283D03*
X980377Y215740D03*
X978269Y264929D03*
X982455Y260781D03*
Y271443D03*
X978827Y303412D03*
X984509Y303623D03*
X989582Y303563D03*
X988460Y358405D03*
X993460D03*
X984272Y349293D03*
X980346Y353527D03*
X981019Y349387D03*
X992460Y370659D03*
X985668Y389311D03*
X980690Y387784D03*
X984605Y408480D03*
X987581Y408332D03*
X988190Y424626D03*
X983358Y449026D03*
X991664Y446372D03*
X993650Y465315D03*
X988650D03*
X991270Y470212D03*
X990292Y494420D03*
X988125Y485193D03*
X986790Y480140D03*
X987440Y504742D03*
X982806Y498606D03*
X986056Y516014D03*
X994056Y521014D03*
Y516014D03*
Y526074D03*
Y531074D03*
X992125Y1061434D03*
X989125D03*
X986125D03*
X983125D03*
X992125Y1064984D03*
Y1067984D03*
X989125D03*
Y1064984D03*
X992125Y1074534D03*
Y1070984D03*
X989125D03*
Y1074534D03*
X986125D03*
X983125D03*
X979091Y1235920D03*
Y1232920D03*
Y1238920D03*
Y1241920D03*
X985396Y1268154D03*
X982665Y1265474D03*
X978318Y1263128D03*
X988242Y1273193D03*
X979228Y1297918D03*
X982000Y1307500D03*
X978026Y1459998D03*
X980779Y1451545D03*
X990634Y1491204D03*
X979768D03*
X982268D03*
X984768D03*
X987268D03*
X990634Y1493704D03*
Y1496204D03*
Y1498704D03*
Y1501204D03*
X979768Y1493704D03*
X982268D03*
X984768D03*
X987268D03*
X986768Y1501204D03*
X981768D03*
X991196Y1550840D03*
X1006221Y164799D03*
X1002721D03*
X1005307Y155043D03*
X995181Y157689D03*
X999580Y154895D03*
X994257D03*
X996416Y176579D03*
X1002921Y178799D03*
X1002827Y172479D03*
X999221Y189299D03*
X1002721D03*
X1006161Y189019D03*
X1008918Y192994D03*
X1008121Y203525D03*
X1000611Y215039D03*
X1005641Y214969D03*
X1001196Y223898D03*
X1008707Y230423D03*
X997300Y234876D03*
X1006468Y301857D03*
X1003460Y358405D03*
X998460D03*
X994409Y349813D03*
X1000460Y369535D03*
X996889Y374156D03*
X1007080Y367087D03*
X999320Y394480D03*
X1006763Y396206D03*
X1003651Y433426D03*
X998859Y437141D03*
X998359Y451675D03*
X994900Y446192D03*
X998359Y462675D03*
Y457175D03*
X1003909Y454662D03*
Y460162D03*
X998359Y479175D03*
Y468175D03*
Y473675D03*
X996320Y470364D03*
X998359Y484675D03*
X1007077Y484937D03*
X998326Y499675D03*
X995530Y500034D03*
X1006206Y510304D03*
X1002056Y521014D03*
Y516014D03*
Y526074D03*
Y531074D03*
X1004527Y541924D03*
Y553224D03*
X1005270Y625710D03*
X1003090Y1037329D03*
X999350Y1310500D03*
Y1315000D03*
Y1319420D03*
Y1323840D03*
Y1328260D03*
Y1332740D03*
Y1341580D03*
Y1337160D03*
Y1346000D03*
X995500Y1368000D03*
X998000Y1365500D03*
X995000Y1362000D03*
X1000634Y1491204D03*
X998134D03*
X995634D03*
X993134D03*
X1003134D03*
X1005634D03*
X993134Y1496204D03*
Y1493704D03*
X1003134D03*
X1005634D03*
X1000634Y1501204D03*
Y1498704D03*
Y1496204D03*
Y1493704D03*
X998134Y1501204D03*
Y1498704D03*
Y1496204D03*
Y1493704D03*
X995634Y1501204D03*
Y1498704D03*
Y1496204D03*
Y1493704D03*
X993134Y1501204D03*
Y1498704D03*
X1005134Y1501204D03*
X994196Y1550840D03*
X1009721Y164799D03*
X1013221D03*
X1014301Y179699D03*
X1017201D03*
X1019901Y179799D03*
X1011991Y189019D03*
X1014901Y189299D03*
X1017701Y189059D03*
X1011120Y198114D03*
X1020521Y194499D03*
X1011068Y207667D03*
X1021440Y226423D03*
X1019356Y222423D03*
X1010909Y213708D03*
X1011721Y233699D03*
X1019531Y230423D03*
X1018220Y243638D03*
X1015220D03*
X1009220D03*
X1014828Y268427D03*
Y258970D03*
X1013396Y280806D03*
X1011423Y282889D03*
X1023110Y287311D03*
X1017835Y291236D03*
X1023000Y298311D03*
X1016764Y350082D03*
X1010252Y363440D03*
X1009815Y404896D03*
X1020748Y420902D03*
Y425902D03*
X1023420Y462921D03*
X1017220Y464155D03*
X1023515Y454397D03*
X1019205Y457687D03*
X1023420Y468039D03*
X1017350Y472155D03*
X1022874Y474545D03*
X1019210Y480155D03*
X1013306Y518146D03*
Y532501D03*
X1017718Y541201D03*
X1019161Y554757D03*
X1024161D03*
X1017961Y545074D03*
X1009611Y550074D03*
Y545074D03*
X1021425Y568614D03*
X1012925Y558000D03*
X1011602Y568473D03*
X1016000Y563107D03*
X1019261Y571324D03*
X1007587Y761546D03*
Y772480D03*
Y775880D03*
Y764946D03*
Y783482D03*
Y786882D03*
Y794484D03*
Y797884D03*
X1016000Y1303000D03*
X1009905Y1305500D03*
X1009896Y1301500D03*
X1013605Y1316050D03*
X1013529Y1318950D03*
X1012500Y1322500D03*
Y1328500D03*
Y1341580D03*
X1013500Y1332740D03*
Y1337160D03*
X1016000Y1361000D03*
X1012500Y1347500D03*
X1021500Y1491204D03*
X1019000D03*
X1016500D03*
X1014000D03*
X1008134D03*
X1010634D03*
X1021500Y1501204D03*
Y1498704D03*
Y1496204D03*
Y1493704D03*
X1019000Y1501204D03*
Y1498704D03*
Y1496204D03*
Y1493704D03*
X1016500Y1501204D03*
Y1498704D03*
Y1496204D03*
Y1493704D03*
X1014000D03*
Y1496204D03*
Y1498704D03*
Y1501204D03*
X1008134Y1493704D03*
X1010634D03*
X1010134Y1501204D03*
X1022796Y1550840D03*
X1022801Y179799D03*
X1027690Y237902D03*
X1024220Y243638D03*
X1033590Y298311D03*
Y287311D03*
X1029200Y351614D03*
X1022674Y357848D03*
X1028146Y355960D03*
X1034214Y351601D03*
X1029601Y394387D03*
X1034855Y411704D03*
X1034409Y429618D03*
X1024443Y424051D03*
X1039015Y444404D03*
X1034899D03*
X1025830Y449022D03*
X1023320Y451112D03*
X1035860Y485976D03*
X1027504Y485637D03*
X1024509Y500168D03*
X1024546Y511254D03*
X1037254Y521014D03*
X1036708Y514883D03*
X1037254Y526074D03*
X1025631Y540104D03*
X1036021Y534990D03*
X1030000Y554500D03*
X1034412Y567416D03*
X1031000Y568500D03*
X1028500Y563000D03*
X1024000D03*
X1029431Y587342D03*
X1032055Y587260D03*
X1028540Y621000D03*
X1035269Y735474D03*
X1032736Y735320D03*
X1030190Y735023D03*
X1025493Y761819D03*
X1035026Y756009D03*
X1036427Y770532D03*
X1038867Y774960D03*
X1025493Y765719D03*
X1033236Y1279287D03*
X1033184Y1275996D03*
X1036411Y1275658D03*
X1036463Y1278949D03*
X1024000Y1491204D03*
X1026500D03*
X1029000D03*
X1031500D03*
X1034000D03*
X1024000Y1501204D03*
Y1498704D03*
Y1496204D03*
Y1493704D03*
X1026500D03*
X1029000D03*
X1031500D03*
X1034000D03*
X1033500Y1501204D03*
X1028500D03*
X1025796Y1550840D03*
X1046384Y269814D03*
X1049451Y266747D03*
X1040060Y313528D03*
X1051873Y305482D03*
X1049573Y406586D03*
X1042015Y444404D03*
X1047515D03*
X1043377Y452740D03*
X1040836Y510894D03*
X1045254Y516014D03*
Y534074D03*
Y526074D03*
X1043991Y540979D03*
X1047335Y549574D03*
X1047200Y543090D03*
X1037301Y539685D03*
X1039407Y547723D03*
X1039000Y555000D03*
X1039718Y563268D03*
X1042628Y556845D03*
X1050956Y591090D03*
X1040626Y668441D03*
X1042389Y733426D03*
X1044056Y736188D03*
X1040915Y766870D03*
X1037566Y1047135D03*
X1037895Y1251517D03*
X1039546Y1275474D03*
X1039598Y1278765D03*
X1042855Y1275552D03*
X1042649Y1279152D03*
X1047366Y1491204D03*
X1044866D03*
X1037366D03*
X1042366D03*
X1039866D03*
X1049866D03*
X1047366Y1498704D03*
Y1496204D03*
Y1493704D03*
X1044866Y1496204D03*
Y1493704D03*
X1037366D03*
Y1496204D03*
Y1498704D03*
X1047366Y1501204D03*
X1044866D03*
Y1498704D03*
X1042366Y1501204D03*
Y1498704D03*
Y1496204D03*
Y1493704D03*
X1039866Y1501204D03*
Y1498704D03*
Y1496204D03*
Y1493704D03*
X1037366Y1501204D03*
X1049866Y1493704D03*
X1051866Y1501204D03*
X1053290Y1652082D03*
X1045545Y1663089D03*
X1066231Y165078D03*
Y167578D03*
X1062704Y270875D03*
X1056941Y259176D03*
X1054613Y261586D03*
X1062923Y295053D03*
X1063356Y318297D03*
X1055934Y388988D03*
X1068143Y380188D03*
X1055934Y381988D03*
X1052505Y406576D03*
X1057798Y427059D03*
Y429618D03*
X1062642Y444859D03*
X1062640Y449155D03*
X1062741Y457959D03*
X1057276Y458155D03*
X1062173Y479655D03*
X1062873Y490180D03*
X1055905Y492537D03*
X1062250Y484672D03*
X1056960Y482262D03*
X1057450Y509242D03*
X1058231Y523238D03*
X1060719Y512359D03*
Y516059D03*
X1061817Y736362D03*
X1065154Y736282D03*
X1057057Y767299D03*
Y771099D03*
X1055171Y1307203D03*
Y1311203D03*
X1058143Y1433809D03*
X1065732Y1491204D03*
X1063232D03*
X1060732D03*
X1052366D03*
X1054866D03*
X1057366D03*
X1065732Y1501204D03*
Y1498704D03*
Y1496204D03*
Y1493704D03*
X1063232Y1501204D03*
Y1498704D03*
Y1496204D03*
Y1493704D03*
X1060732D03*
Y1496204D03*
Y1498704D03*
Y1501204D03*
X1052366Y1493704D03*
X1054866D03*
X1057366D03*
X1056866Y1501204D03*
X1057396Y1550840D03*
X1054396D03*
X1071698Y270702D03*
X1078823Y269400D03*
X1071656Y366726D03*
X1078400Y391226D03*
X1074654Y380188D03*
X1078400Y383226D03*
X1074249Y387795D03*
X1082866Y403068D03*
X1074736Y396929D03*
X1072135Y396908D03*
X1072738Y411322D03*
Y416763D03*
Y421922D03*
X1072673Y428791D03*
X1077873Y463444D03*
X1080453Y457959D03*
X1071470Y475525D03*
X1080640Y467000D03*
X1080574Y471500D03*
X1071667D03*
Y467000D03*
X1080416Y482772D03*
X1080420Y487782D03*
X1071710Y483655D03*
Y488782D03*
X1081730Y509172D03*
X1078499Y648202D03*
X1072232Y667749D03*
X1068378Y736795D03*
X1070616Y766870D03*
X1076903Y1300361D03*
Y1302861D03*
X1079403D03*
Y1300361D03*
X1074403Y1302861D03*
Y1300361D03*
X1076903Y1305361D03*
X1079403D03*
X1074403D03*
Y1307861D03*
Y1310361D03*
Y1312861D03*
X1079403Y1307861D03*
Y1310361D03*
Y1312861D03*
X1076903D03*
Y1310361D03*
Y1307861D03*
X1079403Y1315361D03*
X1076903D03*
Y1317861D03*
X1079403D03*
X1074403D03*
Y1315361D03*
X1069839Y1368999D03*
Y1371540D03*
X1076601Y1382574D03*
X1071332Y1379914D03*
X1076601Y1380066D03*
X1080555Y1380511D03*
X1073612Y1376389D03*
X1081005Y1425458D03*
X1071117Y1445005D03*
X1077031Y1451498D03*
X1070312Y1452028D03*
X1073307Y1451931D03*
X1070732Y1491204D03*
X1068232D03*
X1073232D03*
X1075732D03*
X1078232D03*
X1080732D03*
X1070732Y1501204D03*
Y1498704D03*
Y1496204D03*
Y1493704D03*
X1068232Y1501204D03*
Y1498704D03*
Y1496204D03*
Y1493704D03*
X1073232D03*
X1075732D03*
X1078232D03*
X1080732D03*
X1080232Y1501204D03*
X1075232D03*
X1072134Y1647920D03*
X1081011Y1685499D03*
X1078011D03*
X1081011Y1682499D03*
X1078011D03*
X1077172Y1676686D03*
X1077881Y1688252D03*
X1080933Y1688245D03*
X1078016Y1691207D03*
X1080966Y1691320D03*
X1087421Y149716D03*
X1086714Y353515D03*
X1090086Y370417D03*
X1090061Y428019D03*
X1087963Y440605D03*
Y446105D03*
X1084840Y438234D03*
Y443515D03*
X1087963Y462605D03*
Y457105D03*
X1087940Y452110D03*
X1084840Y460005D03*
X1085851Y465978D03*
X1087963Y468105D03*
X1095448Y479426D03*
X1084000Y477500D03*
X1090000D03*
X1087963Y484605D03*
Y494641D03*
Y489641D03*
X1083434Y481500D03*
X1085730Y509362D03*
X1091730D03*
X1095730D03*
X1082622Y520652D03*
X1082438Y524033D03*
X1085438D03*
X1085622Y520652D03*
X1083281Y651601D03*
X1091270Y668286D03*
X1086758Y767299D03*
Y771099D03*
X1090203Y1307861D03*
Y1310361D03*
Y1312861D03*
X1092703D03*
Y1310361D03*
Y1307861D03*
Y1300361D03*
Y1302861D03*
X1090203D03*
Y1300361D03*
X1095203Y1302861D03*
Y1300361D03*
X1092703Y1305361D03*
X1090203D03*
X1095203D03*
Y1307861D03*
Y1310361D03*
Y1312861D03*
X1090203Y1315361D03*
X1092703D03*
Y1317861D03*
X1090203D03*
X1095203D03*
Y1315361D03*
X1087059Y1372853D03*
X1089489D03*
X1091919D03*
X1092889Y1367278D03*
Y1370178D03*
X1084043Y1382111D03*
X1083293Y1379543D03*
X1094683Y1379188D03*
Y1376288D03*
X1091598Y1491204D03*
X1089098D03*
X1086598D03*
X1084098D03*
X1091598Y1501204D03*
Y1498704D03*
Y1496204D03*
Y1493704D03*
X1089098Y1501204D03*
Y1498704D03*
Y1496204D03*
Y1493704D03*
X1086598Y1501204D03*
Y1498704D03*
Y1496204D03*
Y1493704D03*
X1084098D03*
Y1498704D03*
Y1501204D03*
Y1496204D03*
X1089934Y1550784D03*
X1092934D03*
X1097000Y1629500D03*
X1096500Y1639000D03*
X1096768Y1635080D03*
X1090958Y1646528D03*
Y1649928D03*
X1084629Y1673002D03*
X1087141Y1688914D03*
X1092980Y1699179D03*
X1089030Y1717841D03*
Y1722841D03*
X1099500Y318000D03*
X1111001Y361272D03*
X1107300Y456944D03*
X1111076Y464388D03*
X1108076Y646774D03*
X1104443Y646983D03*
X1100316Y766870D03*
X1109503Y1302861D03*
X1107003D03*
Y1300361D03*
X1109503Y1305361D03*
X1107003D03*
Y1307861D03*
Y1310361D03*
Y1312861D03*
X1109503Y1307861D03*
Y1310361D03*
Y1312861D03*
Y1300361D03*
Y1315361D03*
Y1317861D03*
X1107003D03*
Y1315361D03*
X1102439Y1368999D03*
Y1371540D03*
X1098949Y1373158D03*
X1109201Y1382574D03*
X1103932Y1379914D03*
X1109201Y1380066D03*
X1106212Y1376389D03*
X1098949Y1378958D03*
X1096849Y1377558D03*
X1098949Y1376058D03*
X1096749Y1374558D03*
X1099098Y1501204D03*
X1102248Y1496186D03*
X1106700Y1526591D03*
X1112529Y1547661D03*
X1111701Y1558640D03*
X1107181Y1615917D03*
X1109811D03*
X1098549Y1625749D03*
X1100961Y1622543D03*
X1109000Y1671107D03*
X1105148Y1696029D03*
X1099108Y1691229D03*
X1100998Y1715841D03*
Y1725991D03*
X1119676Y54132D03*
X1124834Y56805D03*
X1124270Y404640D03*
X1121628Y401915D03*
X1121077Y511498D03*
X1125077D03*
X1126387Y615658D03*
X1118435Y625307D03*
X1114467Y640802D03*
X1120321Y635832D03*
X1116540Y651070D03*
X1112190Y651962D03*
X1116459Y767299D03*
Y771099D03*
X1112003Y1302861D03*
Y1300361D03*
Y1305361D03*
X1122803Y1307861D03*
X1125303D03*
Y1310361D03*
Y1312861D03*
X1122803D03*
Y1310361D03*
X1112003Y1312861D03*
Y1310361D03*
Y1307861D03*
X1125303Y1300361D03*
Y1302861D03*
X1122803D03*
Y1300361D03*
X1125303Y1305361D03*
X1122803D03*
X1125303Y1315361D03*
X1122803D03*
X1112003D03*
Y1317861D03*
X1125303D03*
X1122803D03*
X1124519Y1372853D03*
X1119659D03*
X1122089D03*
X1125469Y1367108D03*
Y1370008D03*
X1116643Y1382111D03*
X1113155Y1380511D03*
X1115893Y1379543D03*
X1124375Y1423488D03*
X1124415Y1426168D03*
Y1428668D03*
Y1431168D03*
Y1433668D03*
X1115098Y1468871D03*
Y1472271D03*
X1124875Y1490042D03*
X1125498Y1487292D03*
X1116917Y1506823D03*
X1119912Y1506936D03*
X1116917Y1509898D03*
X1119912Y1509891D03*
Y1515644D03*
X1116917D03*
X1119912Y1512644D03*
X1116917D03*
X1114617Y1526318D03*
X1113887Y1543447D03*
X1119459Y1556343D03*
X1118133Y1587998D03*
Y1591398D03*
X1115027Y1598788D03*
X1117247Y1604554D03*
X1113847D03*
X1124532Y1634915D03*
X1114286Y1630507D03*
X1117136Y1630441D03*
X1113490Y1651862D03*
X1112500Y1671107D03*
X1125784Y1662705D03*
X1124394Y1658967D03*
X1120595D03*
X1126000Y1672419D03*
X1122610Y1677976D03*
X1124091Y1683983D03*
X1114414Y1698859D03*
X1114394Y1695936D03*
X1119361Y1713734D03*
X1113948Y1711244D03*
X1126902Y60805D03*
X1142144Y63186D03*
X1132340Y468202D03*
Y471702D03*
X1141267Y500296D03*
X1134567Y513870D03*
X1139360Y516031D03*
X1129387Y615658D03*
X1138387D03*
X1132855Y609373D03*
X1135387Y615658D03*
X1130017Y766870D03*
X1127803Y1302861D03*
Y1300361D03*
Y1305361D03*
Y1307861D03*
Y1310361D03*
Y1312861D03*
X1139703Y1302861D03*
Y1300361D03*
Y1305361D03*
Y1307861D03*
Y1310361D03*
Y1312861D03*
X1127803Y1317861D03*
Y1315361D03*
X1139703Y1317861D03*
Y1315361D03*
X1135139Y1368999D03*
Y1371540D03*
X1131549Y1373158D03*
X1136632Y1379914D03*
X1138912Y1376389D03*
X1127283Y1379188D03*
X1129449Y1377558D03*
X1127283Y1376288D03*
X1129349Y1374558D03*
X1131549Y1378958D03*
Y1376058D03*
X1129965Y1403877D03*
X1127465D03*
X1129965Y1401377D03*
X1127465D03*
X1132465Y1403877D03*
Y1401377D03*
X1129925Y1398737D03*
X1127425D03*
X1134925D03*
X1132425D03*
X1137425D03*
X1137465Y1401377D03*
X1134965D03*
Y1403877D03*
X1137465D03*
X1137275Y1424138D03*
X1134775D03*
X1132275D03*
X1126875Y1423488D03*
X1129775Y1424138D03*
X1140175Y1423488D03*
X1140215Y1428668D03*
Y1426168D03*
X1134815Y1433668D03*
X1137315D03*
X1140215D03*
Y1431168D03*
X1132315Y1433668D03*
X1137315Y1426818D03*
X1134815D03*
X1137345Y1431058D03*
X1134845D03*
X1132315Y1426818D03*
X1132345Y1431058D03*
X1126915Y1428668D03*
Y1426168D03*
X1129815Y1433668D03*
X1126915D03*
Y1431168D03*
X1129815Y1426818D03*
X1129845Y1431058D03*
X1131478Y1485427D03*
X1134183Y1483926D03*
X1126951Y1484646D03*
X1140960Y1489434D03*
Y1491934D03*
X1141045Y1534952D03*
Y1537452D03*
Y1544952D03*
Y1542452D03*
Y1539952D03*
X1135033Y1556112D03*
X1142639Y1562789D03*
X1133765Y1568952D03*
X1140655Y1569256D03*
X1137755Y1569543D03*
X1138480Y1576364D03*
X1140422Y1595455D03*
X1139037Y1611383D03*
X1131824Y1600593D03*
Y1603993D03*
X1140325Y1598697D03*
X1139037Y1614153D03*
X1139142Y1618859D03*
X1139188Y1621603D03*
X1132981Y1634531D03*
X1141084Y1646672D03*
Y1643272D03*
X1137542Y1647925D03*
X1134207Y1669230D03*
X1129184Y1662705D03*
X1132406Y1658967D03*
X1136575Y1676239D03*
X1141356Y1676542D03*
X1133206Y1675383D03*
X1132176Y1690038D03*
X1142643Y74738D03*
X1151679Y72258D03*
X1150118Y207344D03*
X1155268D03*
Y212344D03*
X1150118D03*
X1155890Y478812D03*
X1150577Y478840D03*
X1144663Y492319D03*
Y500319D03*
X1151036Y501627D03*
X1143060Y516476D03*
X1154145Y583339D03*
Y586339D03*
X1146160Y767299D03*
Y771099D03*
X1155282Y766806D03*
X1142203Y1300361D03*
Y1302861D03*
X1144703D03*
Y1300361D03*
X1142203Y1305361D03*
X1144703D03*
X1155503Y1312861D03*
Y1310361D03*
Y1307861D03*
X1142203D03*
Y1310361D03*
Y1312861D03*
X1144703D03*
Y1310361D03*
Y1307861D03*
X1155503Y1302861D03*
Y1300361D03*
Y1305361D03*
Y1315361D03*
X1142203D03*
X1144703D03*
X1142203Y1317861D03*
X1144703D03*
X1155503D03*
X1152359Y1372853D03*
X1154789D03*
X1141901Y1382574D03*
Y1380066D03*
X1149343Y1382111D03*
X1145855Y1380511D03*
X1148593Y1379543D03*
X1142675Y1423488D03*
X1145715Y1423555D03*
X1145755Y1426235D03*
Y1428735D03*
Y1431235D03*
Y1433735D03*
X1142715Y1426168D03*
Y1428668D03*
Y1431168D03*
Y1433668D03*
X1150718Y1462792D03*
X1153724Y1462695D03*
X1154824Y1471134D03*
X1145960Y1491934D03*
X1148460D03*
X1150960D03*
X1153460D03*
X1155960D03*
X1145960Y1489434D03*
X1148460D03*
X1150960D03*
X1153460D03*
X1155960D03*
X1143460D03*
Y1491934D03*
X1153545Y1534952D03*
X1151045D03*
X1148545D03*
X1146045D03*
X1143545D03*
X1153545Y1537452D03*
X1151045D03*
X1148545D03*
X1146045D03*
X1143545D03*
X1151045Y1544952D03*
X1148545D03*
X1146045D03*
X1143545D03*
X1153545D03*
X1143545Y1542452D03*
X1146045D03*
X1148545D03*
X1151045D03*
X1153545D03*
Y1539952D03*
X1151045D03*
X1148545D03*
X1146045D03*
X1143545D03*
X1155253Y1559176D03*
X1147814Y1562823D03*
X1154336Y1555979D03*
X1149467Y1568988D03*
X1142917Y1583314D03*
Y1586714D03*
X1155180Y1655534D03*
X1146501Y1655608D03*
Y1652208D03*
X1158343Y1658514D03*
X1152198Y1669629D03*
X1151985Y1666685D03*
X1151707Y1663655D03*
X1152114Y1672517D03*
X1154500Y1677000D03*
X1142033Y1682412D03*
X1152211Y1682373D03*
X1162086Y76509D03*
X1162144Y487630D03*
X1158764Y489516D03*
X1162067Y570050D03*
X1166131Y580602D03*
X1157038Y583298D03*
Y586298D03*
X1166026Y669006D03*
X1159718Y766870D03*
X1158003Y1307861D03*
Y1310361D03*
Y1312861D03*
Y1300361D03*
Y1302861D03*
Y1305361D03*
X1160503Y1302861D03*
Y1300361D03*
Y1305361D03*
Y1307861D03*
Y1310361D03*
Y1312861D03*
X1158003Y1315361D03*
Y1317861D03*
X1160503D03*
Y1315361D03*
X1168039Y1368999D03*
Y1371540D03*
X1157219Y1372853D03*
X1158059Y1367018D03*
Y1369918D03*
X1164249Y1373158D03*
X1169532Y1379914D03*
X1164249Y1376058D03*
X1159983Y1376288D03*
X1162049Y1374558D03*
X1164249Y1378958D03*
X1159983Y1379188D03*
X1162149Y1377558D03*
X1160163Y1445627D03*
X1163422Y1445000D03*
X1166350Y1454234D03*
X1160750Y1463250D03*
X1164300Y1463300D03*
X1159283Y1471132D03*
X1158460Y1491934D03*
Y1489434D03*
X1169061Y1543800D03*
X1170061Y1551040D03*
X1163485Y1546195D03*
X1161492Y1551175D03*
X1164528Y1565578D03*
X1170404Y1556331D03*
Y1559731D03*
X1166873Y1561431D03*
X1157255Y1556000D03*
X1170539Y1595621D03*
X1168023Y1586251D03*
X1170539Y1588751D03*
X1168023D03*
X1170539Y1586251D03*
Y1583751D03*
Y1600621D03*
Y1598121D03*
X1170339Y1603121D03*
X1165806Y1658934D03*
X1159688Y1665427D03*
X1169098Y1666278D03*
X1159703Y1673000D03*
X1159500Y1679000D03*
Y1682500D03*
X1184194Y57015D03*
Y61515D03*
X1185913Y93634D03*
X1174031Y403519D03*
X1181000Y402500D03*
X1175181Y447841D03*
Y442341D03*
X1185952Y444202D03*
Y436202D03*
X1178340Y447734D03*
Y442234D03*
X1176000Y436500D03*
X1180000Y436000D03*
X1175181Y458841D03*
Y464341D03*
Y453341D03*
X1185952Y452202D03*
X1178340Y458734D03*
X1178254Y453142D03*
X1178340Y461615D03*
X1175181Y469841D03*
X1186040Y481691D03*
X1178340Y467165D03*
X1175181Y481691D03*
X1182950Y577030D03*
X1178000Y572602D03*
X1182594Y587759D03*
X1178000Y592673D03*
X1183811Y640682D03*
X1182256Y632368D03*
X1182713Y733815D03*
X1175860Y767299D03*
Y771099D03*
X1184960Y766870D03*
X1172603Y1302861D03*
Y1300361D03*
Y1305361D03*
Y1307861D03*
Y1310361D03*
Y1312861D03*
X1175103Y1300361D03*
Y1302861D03*
X1177603D03*
Y1300361D03*
X1175103Y1305361D03*
X1177603D03*
X1175103Y1307861D03*
Y1310361D03*
Y1312861D03*
X1177603D03*
Y1310361D03*
Y1307861D03*
X1175103Y1315361D03*
X1177603D03*
X1172603Y1317861D03*
Y1315361D03*
X1175103Y1317861D03*
X1177603D03*
X1185259Y1372853D03*
X1174801Y1382574D03*
Y1380066D03*
X1182243Y1382111D03*
X1178755Y1380511D03*
X1181493Y1379543D03*
X1171812Y1376389D03*
X1184900Y1428500D03*
X1183000Y1422900D03*
X1184175Y1435600D03*
X1176500Y1457071D03*
X1180200Y1457100D03*
X1178039Y1595621D03*
X1175539D03*
X1173039D03*
X1180923Y1588751D03*
Y1586251D03*
X1173039Y1588751D03*
X1175539D03*
X1178039D03*
Y1586251D03*
X1175539D03*
X1173039D03*
X1178039Y1583751D03*
X1175539D03*
X1173039D03*
X1178039Y1600621D03*
X1175539D03*
X1173039D03*
X1178039Y1598121D03*
X1175539D03*
X1173039D03*
X1175339Y1603121D03*
X1172839D03*
X1177839D03*
X1184362Y1670254D03*
X1181385Y1670312D03*
X1175726Y1686726D03*
X1195488Y93550D03*
X1190587Y99694D03*
X1199756Y128748D03*
X1189727Y164987D03*
Y160987D03*
X1200037Y177187D03*
X1200012Y181187D03*
X1186821Y185430D03*
Y181930D03*
X1195767Y460202D03*
Y470392D03*
Y465272D03*
X1193040Y481691D03*
X1191087Y573809D03*
X1199370Y578154D03*
X1195236Y581407D03*
X1188267Y571807D03*
X1199392Y590500D03*
X1195336Y586606D03*
X1200923Y601734D03*
Y606134D03*
X1199539Y638492D03*
X1197039D03*
X1194539D03*
X1192039D03*
X1195108Y668148D03*
X1198456Y668138D03*
X1190903Y1307861D03*
Y1310361D03*
Y1312861D03*
X1188403D03*
Y1310361D03*
Y1307861D03*
Y1302861D03*
Y1300361D03*
Y1305361D03*
X1190903Y1300361D03*
Y1302861D03*
X1193403D03*
Y1300361D03*
X1190903Y1305361D03*
X1193403D03*
Y1307861D03*
Y1310361D03*
Y1312861D03*
X1190903Y1315361D03*
X1188403D03*
Y1317861D03*
X1190903D03*
X1193403D03*
Y1315361D03*
X1200839Y1368999D03*
Y1371540D03*
X1190119Y1372853D03*
X1191049Y1367188D03*
Y1370088D03*
X1187689Y1372853D03*
X1197149Y1373158D03*
X1192883Y1379188D03*
X1195049Y1377558D03*
X1197149Y1378958D03*
X1192883Y1376288D03*
X1194949Y1374558D03*
X1197149Y1376058D03*
X1194296Y1396500D03*
X1194000Y1401000D03*
Y1414500D03*
X1203242Y1417440D03*
X1194366Y1405500D03*
X1193929Y1410000D03*
X1202548Y1407453D03*
X1202857Y1412454D03*
X1191000Y1425900D03*
X1198800Y1421500D03*
X1202411Y1427410D03*
X1194000Y1424000D03*
X1203117Y1422452D03*
X1202475Y1432468D03*
X1188000Y1419800D03*
X1194000Y1437500D03*
X1203040D03*
X1194000Y1442500D03*
Y1447500D03*
X1188960Y1609135D03*
X1186455Y1608390D03*
Y1602590D03*
Y1605490D03*
X1190174Y1615418D03*
X1190616Y1670641D03*
X1190314Y1661630D03*
X1199299Y1675517D03*
X1197746Y1680914D03*
X1199272Y1683025D03*
X1189263Y1682551D03*
X1190830Y1675710D03*
X1197612Y1703334D03*
X1192612D03*
X1199612Y1691366D03*
X1189462Y1700334D03*
X1194478Y1699936D03*
X1189407Y1717518D03*
X1205929Y86872D03*
X1206580Y94846D03*
X1208431Y133866D03*
Y128748D03*
X1214094Y258633D03*
Y269008D03*
Y282948D03*
Y287948D03*
X1205625Y313758D03*
X1210698Y313671D03*
X1207447Y341381D03*
X1202508Y341424D03*
X1212700Y475712D03*
X1206590Y481403D03*
X1203269Y481237D03*
X1212051Y559827D03*
X1208733Y585986D03*
X1205900Y582443D03*
X1206191Y588400D03*
X1205679Y594148D03*
X1209796Y668115D03*
X1204334Y668138D03*
X1205630Y766600D03*
X1207903Y1300361D03*
Y1302861D03*
X1210403D03*
Y1300361D03*
X1207903Y1305361D03*
X1210403D03*
X1207903Y1307861D03*
Y1310361D03*
Y1312861D03*
X1210403D03*
Y1310361D03*
Y1307861D03*
X1205403Y1302861D03*
Y1300361D03*
Y1305361D03*
Y1307861D03*
Y1310361D03*
Y1312861D03*
X1207903Y1315361D03*
X1210403D03*
X1205403Y1317861D03*
Y1315361D03*
X1207903Y1317861D03*
X1210403D03*
X1202332Y1379914D03*
X1207601Y1380066D03*
X1215043Y1382111D03*
X1211555Y1380511D03*
X1214293Y1379543D03*
X1207601Y1382574D03*
X1204612Y1376389D03*
X1211000Y1392125D03*
X1211075Y1395200D03*
X1210100Y1436500D03*
X1213000Y1435000D03*
X1210400Y1440000D03*
X1214900Y1439800D03*
X1202697Y1673059D03*
X1205604Y1685400D03*
Y1682200D03*
Y1679000D03*
Y1675800D03*
X1212954Y1703343D03*
X1214954Y1691375D03*
X1204804Y1700343D03*
X1207954Y1703343D03*
X1207770Y1706861D03*
Y1720861D03*
X1205638Y1732766D03*
X1227803Y94210D03*
X1221411Y134230D03*
X1221512Y128239D03*
X1220931Y131307D03*
X1222094Y258633D03*
X1230094D03*
Y269008D03*
X1222094D03*
X1230094Y287948D03*
Y282948D03*
X1222094D03*
Y297066D03*
Y292066D03*
Y314216D03*
Y305216D03*
X1226094Y314216D03*
X1218430Y421012D03*
X1219325Y438151D03*
X1216300Y475682D03*
X1228372Y688501D03*
X1221203Y1312861D03*
Y1310361D03*
Y1307861D03*
X1223703D03*
Y1310361D03*
Y1312861D03*
Y1300361D03*
Y1302861D03*
Y1305361D03*
X1221203Y1302861D03*
Y1300361D03*
Y1305361D03*
Y1315361D03*
X1223703D03*
Y1317861D03*
X1221203D03*
X1222919Y1372853D03*
X1220489D03*
X1223889Y1367188D03*
Y1370088D03*
X1218059Y1372853D03*
X1229949Y1373158D03*
X1228800Y1391300D03*
X1225683Y1379188D03*
X1227849Y1377558D03*
X1225683Y1376288D03*
X1227749Y1374558D03*
X1229949Y1378958D03*
Y1376058D03*
X1227000Y1401300D03*
X1219650Y1392050D03*
X1219500Y1398900D03*
X1224200Y1393500D03*
X1227000Y1404500D03*
X1219500Y1436000D03*
X1221837Y1438800D03*
X1229661Y1442000D03*
X1226200Y1444300D03*
X1222700Y1446300D03*
X1220200Y1449100D03*
X1219738Y1713861D03*
Y1708861D03*
X1216738Y1717011D03*
X1219738Y1722861D03*
Y1727861D03*
X1216738Y1731011D03*
X1238769Y75320D03*
X1233668Y132739D03*
Y128239D03*
X1247834Y159844D03*
X1238094Y258633D03*
X1246094Y269008D03*
X1238094D03*
X1234000Y385500D03*
X1233468Y419742D03*
X1242429Y431255D03*
Y427255D03*
Y435255D03*
X1236879Y449755D03*
X1242429Y439255D03*
X1232081Y460580D03*
X1242692Y483435D03*
X1236100Y773844D03*
X1233084Y772582D03*
X1235215Y777213D03*
X1231397Y769667D03*
X1243207Y779428D03*
X1241057Y782278D03*
X1244986Y787578D03*
X1244127Y784598D03*
X1238257Y779728D03*
X1243294Y1269197D03*
Y1266697D03*
Y1261697D03*
Y1264197D03*
X1243308Y1271754D03*
X1238830Y1322853D03*
Y1325394D03*
X1240323Y1333768D03*
X1245592Y1333920D03*
Y1336428D03*
X1242603Y1330243D03*
X1239800Y1389500D03*
X1235400Y1391200D03*
X1238500Y1400900D03*
X1234900Y1404400D03*
X1233700Y1395600D03*
X1238200Y1395500D03*
X1244300Y1403500D03*
X1235679Y1418908D03*
X1239242Y1418462D03*
X1238731Y1422362D03*
X1239550Y1437050D03*
X1249152Y72895D03*
X1253152Y84895D03*
X1255661Y90470D03*
X1253152Y95525D03*
X1259472Y92864D03*
X1252693Y124739D03*
X1249431Y137739D03*
X1249065Y241594D03*
Y236594D03*
Y251594D03*
Y246594D03*
X1246094Y258633D03*
X1254094D03*
X1262094Y269008D03*
X1254094D03*
X1262094Y282948D03*
X1254094D03*
X1262094Y287948D03*
X1250285Y303307D03*
X1259659Y389456D03*
X1260107Y399125D03*
X1260227Y415128D03*
X1256137Y459182D03*
Y453872D03*
X1245752Y470733D03*
X1250975Y474945D03*
X1248130Y783354D03*
X1251177Y784488D03*
X1254981Y787578D03*
X1256447Y798828D03*
X1259297Y798784D03*
X1251177Y794878D03*
X1257527Y808938D03*
X1260427Y809008D03*
X1259194Y1251697D03*
Y1246697D03*
Y1254197D03*
Y1249197D03*
X1248294Y1259197D03*
Y1256697D03*
X1245794Y1259197D03*
X1259194Y1269215D03*
Y1261715D03*
Y1264215D03*
Y1266715D03*
X1245894Y1269215D03*
X1248394D03*
X1245894Y1261715D03*
Y1264215D03*
Y1266715D03*
X1248394D03*
Y1264215D03*
Y1261715D03*
X1259194Y1256697D03*
Y1259197D03*
X1248308Y1271754D03*
X1245808D03*
X1259108D03*
X1256050Y1326707D03*
X1258480D03*
X1253034Y1335965D03*
X1249546Y1334365D03*
X1252284Y1333397D03*
X1249600Y1403425D03*
X1257594Y1417000D03*
X1253100Y1413500D03*
X1256224Y1430075D03*
X1256600Y1434500D03*
X1275981Y85114D03*
X1263472Y92864D03*
X1269146Y121022D03*
X1263146D03*
X1267037Y180565D03*
Y175030D03*
X1268941Y206017D03*
X1269360Y219632D03*
X1261969Y219505D03*
X1262094Y258633D03*
X1270094D03*
Y269008D03*
Y282948D03*
Y292066D03*
X1268174Y395125D03*
X1275585Y393597D03*
X1269840Y411128D03*
X1270483Y433148D03*
Y435648D03*
X1265227Y454372D03*
X1262457Y798814D03*
X1266677Y802988D03*
X1266568Y809078D03*
X1275177Y808963D03*
X1263647Y809118D03*
X1271177Y808963D03*
X1261694Y1251697D03*
X1264194D03*
Y1246697D03*
X1261694D03*
Y1254197D03*
X1264194D03*
X1261694Y1249197D03*
X1264194D03*
X1261694Y1269215D03*
Y1266715D03*
Y1264215D03*
Y1261715D03*
X1264194Y1269197D03*
Y1256697D03*
Y1259197D03*
Y1261697D03*
X1261694Y1256697D03*
Y1259197D03*
X1264194Y1264197D03*
Y1266697D03*
X1264108Y1271754D03*
X1261608D03*
X1271726Y1322825D03*
Y1325366D03*
X1260910Y1326707D03*
X1262050Y1320878D03*
Y1323778D03*
X1267940Y1327012D03*
X1265740Y1328412D03*
X1273219Y1333740D03*
X1275499Y1330215D03*
X1267940Y1332812D03*
Y1329912D03*
X1265840Y1331412D03*
X1263674Y1330142D03*
Y1333042D03*
X1271042Y1418748D03*
X1266996Y1423617D03*
X1262310Y1428303D03*
X1275195Y1552250D03*
X1275170Y1579519D03*
X1269310Y1583170D03*
X1287486Y134165D03*
X1278050Y152912D03*
X1278137Y166051D03*
X1278211Y161030D03*
Y156030D03*
X1278137Y180565D03*
Y176051D03*
Y171551D03*
Y184987D03*
X1279447Y213292D03*
X1286094Y258633D03*
X1278094D03*
Y269008D03*
X1286094D03*
X1278094Y282948D03*
X1286094D03*
X1278094Y287948D03*
X1286094Y292066D03*
X1290127Y401125D03*
Y410635D03*
X1289352Y418550D03*
Y421950D03*
X1281190Y1254112D03*
X1276190D03*
X1278690D03*
X1281190Y1249112D03*
Y1251612D03*
X1276190D03*
X1278690D03*
X1276190Y1249112D03*
X1278690D03*
X1281190Y1246612D03*
X1276190D03*
X1278690D03*
X1276190Y1269112D03*
Y1266612D03*
X1281190Y1259112D03*
Y1256612D03*
X1276190D03*
Y1259112D03*
Y1261612D03*
Y1264112D03*
X1278690Y1256612D03*
Y1259112D03*
X1278790Y1269130D03*
X1281290D03*
X1278790Y1261630D03*
Y1264130D03*
Y1266630D03*
X1281290D03*
Y1264130D03*
Y1261630D03*
X1281204Y1271669D03*
X1278704D03*
X1276204D03*
X1288946Y1326679D03*
X1278488Y1333892D03*
X1285930Y1335937D03*
X1282442Y1334337D03*
X1285180Y1333369D03*
X1278488Y1336400D03*
X1287600Y1423100D03*
Y1427600D03*
X1276500Y1432000D03*
X1279525D03*
X1287700Y1431700D03*
X1287961Y1542469D03*
X1287372Y1552845D03*
X1287647Y1545220D03*
Y1549120D03*
X1277017Y1544953D03*
Y1547453D03*
Y1549953D03*
X1281470Y1552845D03*
X1281347Y1549120D03*
Y1545220D03*
X1284497Y1549120D03*
Y1545220D03*
X1284510Y1554436D03*
X1277702D03*
X1289919Y1582295D03*
Y1574795D03*
Y1579795D03*
Y1577295D03*
X1287419Y1582295D03*
Y1579795D03*
X1284919D03*
Y1582295D03*
X1282419D03*
Y1579795D03*
X1299196Y76209D03*
X1305685Y74748D03*
X1296200Y66911D03*
X1305091Y123680D03*
Y127830D03*
Y131750D03*
X1301582Y166051D03*
X1301743Y162055D03*
X1301582Y171551D03*
Y184051D03*
X1302094Y258633D03*
X1294094D03*
Y269008D03*
X1302094D03*
X1294094Y287948D03*
Y282948D03*
X1302094D03*
Y292066D03*
X1302069Y303184D03*
X1299026Y389355D03*
X1302226D03*
X1295519Y389561D03*
X1304347Y523237D03*
X1302160Y524916D03*
X1304566Y525743D03*
X1301642Y537299D03*
X1293581Y542716D03*
X1294938Y561331D03*
X1300400Y599413D03*
X1297400D03*
X1298000Y657500D03*
X1303250Y655149D03*
X1295000Y655200D03*
X1292297Y657206D03*
X1302500Y664500D03*
X1305100Y662100D03*
X1301900Y660699D03*
X1294590Y1254112D03*
X1297090D03*
X1292090D03*
Y1249112D03*
X1294590D03*
X1297090D03*
X1292090Y1251612D03*
X1294590D03*
X1297090D03*
X1292090Y1246612D03*
X1297090D03*
X1294590D03*
X1292090Y1269130D03*
X1294590D03*
X1292090Y1261630D03*
Y1264130D03*
Y1266630D03*
X1294590D03*
Y1264130D03*
Y1261630D03*
X1297090Y1269112D03*
Y1256612D03*
Y1259112D03*
Y1261612D03*
X1294590Y1256612D03*
Y1259112D03*
X1297090Y1264112D03*
Y1266612D03*
X1292090Y1256612D03*
Y1259112D03*
X1297004Y1271669D03*
X1292004D03*
X1294504D03*
X1304630Y1322768D03*
Y1325309D03*
X1293806Y1326679D03*
X1291376D03*
X1294956Y1320934D03*
Y1323834D03*
X1300836Y1326984D03*
X1298636Y1328384D03*
X1296570Y1330114D03*
Y1333014D03*
X1298736Y1331384D03*
X1300836Y1329884D03*
Y1332784D03*
X1296000Y1427700D03*
X1301900D03*
X1295700Y1421800D03*
X1300800D03*
X1291700Y1431700D03*
X1302390Y1530430D03*
X1297490Y1526910D03*
X1297620Y1529534D03*
X1291897Y1545076D03*
X1290461Y1542469D03*
X1291897Y1547576D03*
X1302915Y1563596D03*
X1298466Y1556331D03*
Y1559731D03*
X1292419Y1582295D03*
Y1579795D03*
Y1574795D03*
Y1577295D03*
X1294919D03*
Y1574795D03*
X1294387Y1571682D03*
X1291887D03*
X1301789Y1574795D03*
X1304289D03*
X1301789Y1577295D03*
X1304289D03*
Y1579795D03*
X1301789D03*
X1304289Y1582295D03*
X1301789D03*
X1299289Y1574795D03*
Y1582295D03*
Y1579795D03*
Y1577295D03*
X1295877Y1581199D03*
X1298382Y1584844D03*
X1295877Y1584099D03*
X1293459Y1584844D03*
X1320020Y66979D03*
X1308110Y66911D03*
X1307857Y103353D03*
X1313951Y104739D03*
X1311045D03*
X1313011Y135820D03*
Y139845D03*
X1306300Y203917D03*
X1318094Y258633D03*
X1310094D03*
Y269008D03*
X1318094D03*
X1310094Y287948D03*
Y282948D03*
X1318094D03*
X1305426Y389355D03*
X1308926Y524111D03*
X1306815Y522726D03*
X1307117Y525897D03*
X1309870Y552788D03*
X1309776Y559831D03*
X1317266Y597213D03*
X1310544Y613100D03*
X1313544Y610100D03*
X1310544D03*
X1313544Y607100D03*
X1310544D03*
X1313544Y604100D03*
X1310544D03*
X1307544Y610100D03*
Y613100D03*
Y604100D03*
Y607100D03*
X1317266Y600213D03*
X1309166Y601713D03*
X1308776Y599181D03*
X1313544Y613100D03*
X1310544Y616100D03*
X1313544D03*
X1307544D03*
X1308800Y619200D03*
Y622200D03*
Y625200D03*
X1318300D03*
Y622200D03*
Y619200D03*
X1307700Y664600D03*
X1309600Y667700D03*
X1315657Y1199532D03*
Y1196132D03*
X1311715Y1221042D03*
X1318776Y1219566D03*
X1311594Y1251612D03*
X1309094D03*
X1311594Y1254112D03*
X1309094D03*
X1311594Y1246612D03*
X1309094D03*
X1311594Y1249112D03*
X1309094D03*
X1314094Y1246612D03*
Y1251612D03*
Y1249112D03*
Y1254112D03*
X1309090Y1269169D03*
Y1266669D03*
Y1261669D03*
Y1264169D03*
X1314194Y1269130D03*
Y1266630D03*
Y1264130D03*
Y1261630D03*
X1311694Y1269130D03*
Y1261630D03*
Y1264130D03*
Y1266630D03*
X1311594Y1259112D03*
Y1256612D03*
X1309094Y1259112D03*
Y1256612D03*
X1314094D03*
Y1259112D03*
X1309090Y1271669D03*
X1311590D03*
X1314090D03*
X1306123Y1333683D03*
X1311392Y1333835D03*
X1318834Y1335880D03*
X1315346Y1334280D03*
X1318084Y1333312D03*
X1311392Y1336343D03*
X1308403Y1330158D03*
X1308900Y1525510D03*
X1306789Y1574795D03*
Y1582295D03*
Y1579795D03*
Y1577295D03*
X1310914Y1577299D03*
X1331930Y66945D03*
X1327541Y105227D03*
X1337399Y98084D03*
X1333399D03*
X1334094Y258633D03*
X1326094D03*
Y269008D03*
X1334094D03*
Y287948D03*
X1326094Y282948D03*
X1334094D03*
X1326094Y292066D03*
X1328427Y349452D03*
X1329585Y561806D03*
X1325366Y597213D03*
Y600213D03*
X1321300Y619200D03*
Y622200D03*
Y625200D03*
X1326636Y656800D03*
X1322420Y656867D03*
X1332812Y856383D03*
X1325543Y871161D03*
X1329244D03*
X1334301Y867765D03*
X1328992Y1209788D03*
X1327029Y1206788D03*
X1331202Y1206478D03*
X1323169Y1208995D03*
X1333977Y1222158D03*
X1325137Y1210653D03*
X1324901Y1216419D03*
X1322141Y1217365D03*
X1327494Y1246612D03*
Y1251612D03*
Y1249112D03*
Y1254112D03*
X1324994Y1246612D03*
Y1251612D03*
Y1249112D03*
Y1254112D03*
X1329994Y1246612D03*
Y1251612D03*
Y1249112D03*
Y1254112D03*
X1324994Y1269130D03*
Y1261630D03*
Y1264130D03*
Y1266630D03*
X1327494Y1269130D03*
Y1266630D03*
Y1264130D03*
Y1261630D03*
Y1259112D03*
Y1256612D03*
X1324994Y1259112D03*
Y1256612D03*
X1329994Y1259112D03*
Y1256612D03*
Y1266612D03*
Y1264112D03*
Y1261612D03*
Y1269112D03*
X1327490Y1271669D03*
X1324990D03*
X1329990D03*
X1326710Y1326622D03*
X1324280D03*
X1321850D03*
X1327876Y1320934D03*
Y1323834D03*
X1333740Y1326927D03*
X1331540Y1328327D03*
X1333740Y1329827D03*
Y1332727D03*
X1331640Y1331327D03*
X1329474Y1330057D03*
Y1332957D03*
X1322539Y1411278D03*
X1322499Y1413788D03*
X1325499D03*
X1325539Y1411278D03*
Y1416446D03*
X1322539D03*
X1328539Y1411278D03*
X1328499Y1413788D03*
X1328539Y1416446D03*
X1331509Y1416486D03*
X1334509D03*
X1331509Y1408818D03*
X1334509Y1411318D03*
X1334469Y1413828D03*
X1334509Y1408818D03*
X1331469Y1413828D03*
X1331509Y1411318D03*
X1325579Y1418976D03*
X1322579D03*
X1325609Y1421496D03*
X1322609D03*
X1328579Y1418976D03*
X1328609Y1421496D03*
X1331579Y1421536D03*
X1331549Y1419016D03*
X1334579Y1421536D03*
X1334549Y1419016D03*
X1343840Y66911D03*
X1341399Y98084D03*
X1348199D03*
X1342094Y258633D03*
Y269008D03*
X1350094D03*
Y287948D03*
X1342094Y282948D03*
X1350094D03*
X1342094Y292066D03*
X1340257Y677765D03*
Y675111D03*
X1336812Y856383D03*
X1341301Y867765D03*
X1337801D03*
X1341301Y871265D03*
X1344801D03*
X1348301D03*
X1340948Y1177681D03*
X1342507Y1187848D03*
X1340948Y1181681D03*
X1349012Y1204971D03*
X1342036Y1206429D03*
Y1203029D03*
X1346063Y1217729D03*
Y1214329D03*
X1341590Y1254169D03*
Y1251669D03*
Y1249169D03*
Y1246669D03*
X1344090Y1254169D03*
Y1251669D03*
Y1249169D03*
Y1246669D03*
X1346590Y1254169D03*
Y1249169D03*
Y1251669D03*
Y1246669D03*
X1341690Y1269269D03*
Y1264269D03*
Y1266769D03*
Y1261769D03*
X1341590Y1256669D03*
Y1259169D03*
X1344190Y1269187D03*
X1346690D03*
X1344190Y1261687D03*
Y1264187D03*
Y1266687D03*
X1346690D03*
Y1264187D03*
Y1261687D03*
X1344090Y1256669D03*
Y1259169D03*
X1346590D03*
Y1256669D03*
X1341690Y1271769D03*
X1346690D03*
X1344190D03*
X1337430Y1322968D03*
Y1325509D03*
X1338923Y1333883D03*
X1344192Y1334035D03*
X1348146Y1334480D03*
X1344192Y1336543D03*
X1341203Y1330358D03*
X1340556Y1383674D03*
Y1386674D03*
X1337556D03*
Y1383674D03*
X1346556Y1386674D03*
Y1383674D03*
X1343556Y1386674D03*
Y1383674D03*
X1349556D03*
Y1386674D03*
X1337555Y1389658D03*
X1343712Y1389804D03*
X1348712D03*
X1346212D03*
X1341212D03*
X1348823Y1409626D03*
X1348853Y1413866D03*
X1346323Y1409626D03*
X1346353Y1413866D03*
X1343823Y1409626D03*
X1343853Y1413866D03*
X1346509Y1416486D03*
X1349509D03*
X1343509D03*
X1341323Y1409626D03*
X1341353Y1413866D03*
X1337509Y1416486D03*
Y1411318D03*
X1337469Y1413828D03*
X1337509Y1408818D03*
X1340509Y1416486D03*
X1349579Y1421536D03*
X1349549Y1419016D03*
X1346579Y1421536D03*
X1346549Y1419016D03*
X1343549D03*
X1343579Y1421536D03*
X1337579D03*
X1337549Y1419016D03*
X1340579Y1421536D03*
X1340549Y1419016D03*
X1355750Y66886D03*
X1360109Y98050D03*
X1352199D03*
X1364369Y120380D03*
X1358094Y258633D03*
X1350094D03*
X1358094Y269008D03*
X1366094D03*
Y287948D03*
X1358094Y282948D03*
X1366094D03*
X1358094Y292066D03*
X1363857Y626579D03*
X1361427D03*
X1354397Y623374D03*
Y626274D03*
X1356597Y624874D03*
X1358663Y623144D03*
X1356497Y621874D03*
X1354397Y620474D03*
X1358663Y620244D03*
X1360964Y629514D03*
Y632414D03*
X1358461Y684151D03*
Y686651D03*
X1360961Y684073D03*
Y686573D03*
X1363461D03*
Y684073D03*
X1363435Y681573D03*
X1358435D03*
X1360935D03*
X1358461Y694151D03*
X1363461D03*
X1360961D03*
X1358461Y689151D03*
Y691651D03*
X1363461Y696651D03*
X1360961D03*
X1363461Y699151D03*
X1360961Y691573D03*
X1363461D03*
X1360961Y689073D03*
X1363461D03*
X1362523Y1015473D03*
Y1022559D03*
Y1019016D03*
X1355222Y1200561D03*
X1361285Y1206718D03*
X1355641Y1210674D03*
X1362810Y1211071D03*
X1357490Y1254169D03*
Y1249169D03*
Y1251669D03*
Y1246669D03*
X1359990Y1254169D03*
X1362490D03*
X1359990Y1249169D03*
X1362490D03*
X1359990Y1251669D03*
X1362490D03*
Y1246669D03*
X1359990D03*
Y1269187D03*
Y1266687D03*
Y1264187D03*
Y1261687D03*
X1357490Y1269187D03*
Y1261687D03*
Y1264187D03*
Y1266687D03*
Y1256669D03*
Y1259169D03*
X1362490Y1269269D03*
Y1261769D03*
Y1266769D03*
Y1264269D03*
Y1256669D03*
Y1259169D03*
X1359990Y1256669D03*
Y1259169D03*
X1357490Y1271769D03*
X1362490D03*
X1359990D03*
X1359510Y1326822D03*
X1360724Y1321184D03*
Y1324084D03*
X1357080Y1326822D03*
X1354650D03*
X1364340Y1328527D03*
X1351634Y1336080D03*
X1350884Y1333512D03*
X1364440Y1337527D03*
Y1331527D03*
Y1334527D03*
X1362274Y1330257D03*
Y1333157D03*
Y1336057D03*
X1352226Y1386804D03*
Y1383804D03*
X1352225Y1389788D03*
X1358509Y1416486D03*
Y1413818D03*
Y1411318D03*
Y1408818D03*
X1352509Y1416486D03*
Y1411318D03*
Y1413818D03*
Y1408818D03*
X1355509Y1416486D03*
Y1411318D03*
Y1413818D03*
Y1408818D03*
X1352579Y1421536D03*
X1352549Y1419016D03*
X1355549D03*
X1367950Y66886D03*
X1377682Y87587D03*
X1368109Y98000D03*
X1366094Y258633D03*
X1373862Y485552D03*
Y511052D03*
X1381457Y511050D03*
X1376757Y619497D03*
X1369303Y617321D03*
X1372791Y618921D03*
X1370053Y619889D03*
X1376745Y616858D03*
X1379734Y623043D03*
X1366287Y626579D03*
X1376761Y686573D03*
Y684073D03*
X1374261D03*
Y686573D03*
X1374245Y681573D03*
X1376745D03*
X1376761Y694151D03*
X1374261D03*
X1376761Y696651D03*
X1374261D03*
X1376761Y699151D03*
X1374261D03*
X1376761Y701651D03*
X1374261D03*
X1376761Y691573D03*
Y689073D03*
X1374261Y691573D03*
Y689073D03*
X1376761Y706651D03*
Y704151D03*
X1374261Y706651D03*
Y704151D03*
X1377483Y1015473D03*
X1370003D03*
X1377483Y1022559D03*
Y1019016D03*
X1370003Y1022559D03*
Y1019016D03*
X1370685Y1223032D03*
Y1226432D03*
X1374476Y1266143D03*
X1376976D03*
X1379476D03*
X1374476Y1268643D03*
X1376976D03*
X1379476D03*
X1374476Y1273643D03*
Y1271143D03*
X1374576Y1283743D03*
Y1281243D03*
X1374476Y1276143D03*
Y1278643D03*
X1376976Y1273643D03*
Y1271143D03*
X1379476Y1273643D03*
Y1271143D03*
X1377076Y1281161D03*
Y1283661D03*
X1379576D03*
Y1281161D03*
X1376976Y1276143D03*
Y1278643D03*
X1379476D03*
Y1276143D03*
X1379576Y1288661D03*
X1377076Y1286161D03*
X1379576D03*
X1377076Y1288661D03*
X1379576Y1291243D03*
X1377076D03*
X1374576Y1288743D03*
Y1286243D03*
Y1291243D03*
X1370012Y1342299D03*
X1371505Y1353214D03*
X1376774Y1353366D03*
X1370012Y1344840D03*
X1376774Y1355874D03*
X1373785Y1349689D03*
X1382045Y1700038D03*
X1379804Y1733118D03*
X1383715Y236594D03*
Y241594D03*
X1381457Y485550D03*
X1382014Y619518D03*
X1383507Y627892D03*
Y630433D03*
X1387097Y656274D03*
X1389297Y657774D03*
X1391363Y656044D03*
X1387097Y653374D03*
X1389197Y654774D03*
X1391363Y653144D03*
X1394127Y659479D03*
X1387097Y659174D03*
X1393664Y662384D03*
Y665284D03*
X1393343Y716971D03*
X1390807Y717053D03*
X1390817Y714471D03*
X1393317D03*
X1393343Y719471D03*
X1390807Y719553D03*
X1393367Y727023D03*
Y729523D03*
X1393343Y724471D03*
Y721971D03*
X1390807Y722053D03*
Y724553D03*
X1390853Y727053D03*
X1391460Y1009764D03*
Y1006024D03*
Y1013504D03*
Y1020985D03*
Y1024725D03*
Y1028465D03*
Y1017244D03*
X1390376Y1268643D03*
X1392876D03*
Y1283661D03*
Y1281161D03*
X1390376D03*
Y1283661D03*
Y1273643D03*
Y1271143D03*
Y1276143D03*
Y1278643D03*
X1392876Y1273643D03*
Y1271143D03*
Y1276143D03*
Y1278643D03*
Y1288661D03*
Y1286161D03*
X1390376Y1288661D03*
Y1286161D03*
Y1291243D03*
X1392876D03*
X1393306Y1340515D03*
Y1343415D03*
X1384216Y1355411D03*
X1380728Y1353811D03*
X1383466Y1352843D03*
X1392092Y1346153D03*
X1389662D03*
X1387232D03*
X1385068Y1664907D03*
X1390738Y1664938D03*
X1392068Y1676875D03*
X1381918D03*
X1391750Y1697747D03*
X1382045Y1704038D03*
X1390045Y1712038D03*
X1390179Y1733118D03*
X1404917Y116911D03*
X1395302Y251136D03*
Y256136D03*
X1411000Y460362D03*
X1406500Y458362D03*
X1400500Y458377D03*
X1409445Y652266D03*
X1402003Y650221D03*
X1405491Y651821D03*
X1402753Y652789D03*
X1409445Y649758D03*
X1398987Y659479D03*
X1396557D03*
X1409143Y716971D03*
X1395843D03*
X1406643D03*
X1409127Y714471D03*
X1395817D03*
X1406627D03*
X1409143Y719471D03*
X1395843D03*
X1406643D03*
X1395867Y732023D03*
Y727023D03*
Y729523D03*
X1406667Y727023D03*
X1409167Y732023D03*
Y729523D03*
X1406667Y732023D03*
Y729523D03*
X1409167Y727023D03*
X1409143Y724471D03*
Y721971D03*
X1395843Y724471D03*
Y721971D03*
X1406643Y724471D03*
Y721971D03*
X1409167Y739523D03*
Y734523D03*
Y737023D03*
X1406667Y734523D03*
Y737023D03*
Y739523D03*
X1401015Y1014744D03*
X1399953Y1005799D03*
X1403693D03*
X1407433D03*
X1401015Y1023012D03*
Y1018878D03*
X1407433Y1032430D03*
X1403693D03*
X1395060Y1032205D03*
X1399953Y1032430D03*
X1395376Y1268643D03*
Y1273643D03*
Y1271143D03*
Y1281243D03*
Y1283743D03*
Y1276143D03*
Y1278643D03*
Y1288743D03*
Y1286243D03*
Y1291243D03*
X1399122Y1352258D03*
X1394856Y1352488D03*
X1399122Y1346458D03*
Y1349358D03*
X1396922Y1347858D03*
X1394856Y1349588D03*
X1397022Y1350858D03*
X1405811Y1430021D03*
X1409532Y1552845D03*
X1409409Y1549120D03*
Y1545220D03*
X1403257Y1552250D03*
X1405079Y1549953D03*
Y1544953D03*
Y1547453D03*
X1405764Y1554436D03*
X1403232Y1579519D03*
X1397030Y1594060D03*
X1409286Y1605796D03*
X1406666Y1616332D03*
X1400029Y1615796D03*
X1406447Y1619572D03*
X1396783Y1617170D03*
X1408023Y1638705D03*
X1398058Y1628651D03*
X1408208D03*
X1406814Y1652439D03*
X1399599Y1657583D03*
X1398883Y1680341D03*
X1410750Y244583D03*
X1417000Y460362D03*
X1419335Y533958D03*
X1414714Y653008D03*
X1412434Y655943D03*
X1416207Y663333D03*
Y660792D03*
X1421797Y687354D03*
X1423963Y685724D03*
X1419697Y685954D03*
X1421897Y690354D03*
X1423963Y688624D03*
X1419697Y688854D03*
Y691754D03*
X1423417Y747051D03*
X1423407Y757133D03*
Y749633D03*
Y752133D03*
Y754633D03*
X1416301Y970340D03*
Y977840D03*
Y985340D03*
X1414576Y989765D03*
X1414501Y993765D03*
Y997765D03*
X1410858Y1014744D03*
X1418653Y1005799D03*
X1414913D03*
X1411173D03*
X1414501Y1001765D03*
X1419716Y1014744D03*
X1422394Y1005799D03*
X1410858Y1023012D03*
X1419716D03*
X1410858Y1018878D03*
X1419716D03*
X1422394Y1032430D03*
X1419026Y1038765D03*
Y1042765D03*
X1414913Y1032430D03*
X1418653D03*
X1411173D03*
X1417301Y1051540D03*
X1418982Y1175144D03*
X1414165Y1289564D03*
X1414172Y1286188D03*
X1415434Y1552845D03*
X1415709Y1545220D03*
Y1549120D03*
X1418523Y1542469D03*
X1419959Y1545076D03*
Y1547576D03*
X1416023Y1542469D03*
X1412559Y1549120D03*
Y1545220D03*
X1412572Y1554436D03*
X1417981Y1568680D03*
X1423531Y1574795D03*
Y1582295D03*
Y1579795D03*
Y1577295D03*
X1424621Y1571911D03*
Y1569411D03*
X1416862Y1582871D03*
X1419811Y1599084D03*
X1416709Y1592819D03*
X1413836Y1586944D03*
X1412467Y1602234D03*
X1419914Y1602777D03*
X1418000Y1607500D03*
X1422154Y1626270D03*
X1423722Y1616780D03*
X1419622Y1616000D03*
X1422266Y1628947D03*
X1411113Y1637767D03*
X1421890Y1635500D03*
X1418755Y1654999D03*
X1410315Y1646967D03*
X1424315D03*
X1434262Y52892D03*
X1438262D03*
X1431262Y61392D03*
X1439049Y107443D03*
X1429169Y107313D03*
X1431300Y538800D03*
X1435400Y536200D03*
X1431400Y533400D03*
X1435400Y530800D03*
X1434603Y682801D03*
X1438091Y684401D03*
X1435353Y685369D03*
X1431617Y692359D03*
X1429187D03*
X1426757D03*
X1426264Y694954D03*
Y697854D03*
X1439227Y747051D03*
X1425917D03*
X1428417D03*
X1428407Y762133D03*
Y759633D03*
X1425907D03*
X1439257Y762133D03*
Y759633D03*
X1425943Y757051D03*
X1428443D03*
X1425943Y749551D03*
Y752051D03*
Y754551D03*
X1428443D03*
Y752051D03*
Y749551D03*
X1439243Y757051D03*
Y749551D03*
Y752051D03*
Y754551D03*
X1439257Y764633D03*
Y769633D03*
Y767133D03*
X1429952Y1014744D03*
X1433614Y1005799D03*
X1426134D03*
X1429874D03*
X1429952Y1023012D03*
Y1018878D03*
X1426134Y1032430D03*
X1433614D03*
X1429874D03*
X1435160Y1516590D03*
Y1513190D03*
Y1534990D03*
Y1538390D03*
X1434235Y1550240D03*
X1433235Y1543800D03*
X1430735D03*
X1431735Y1550240D03*
X1434578Y1556331D03*
Y1559731D03*
X1430213Y1553652D03*
X1427713D03*
X1426031Y1582295D03*
X1431031Y1574795D03*
Y1577295D03*
X1426031Y1579795D03*
Y1577295D03*
Y1574795D03*
X1428531D03*
Y1577295D03*
Y1579795D03*
Y1582295D03*
X1430431Y1570595D03*
X1427931D03*
X1437901Y1579795D03*
Y1577295D03*
Y1574795D03*
Y1582295D03*
X1435401D03*
Y1579795D03*
Y1577295D03*
Y1574795D03*
X1431989Y1581199D03*
X1434494Y1584844D03*
X1431989Y1584099D03*
X1429571Y1584844D03*
X1430244Y1609966D03*
X1438565Y1612583D03*
X1434316Y1616909D03*
X1430238Y1617137D03*
X1437594Y1616845D03*
X1426899Y1616990D03*
X1429072Y1643655D03*
X1433911Y1649037D03*
X1433618Y1659331D03*
X1433157Y1651977D03*
X1436311Y1665948D03*
X1438078Y1669992D03*
X1439316Y1675080D03*
X1435904Y1694335D03*
X1443049Y107443D03*
X1448549Y114643D03*
X1446040Y120218D03*
X1452040Y113018D03*
X1440871Y152166D03*
X1454769Y163842D03*
X1444769D03*
Y174217D03*
X1453974Y174414D03*
X1449769Y174217D03*
X1439769D03*
Y182217D03*
X1449769D03*
X1456500Y457000D03*
X1441053Y560535D03*
X1441898Y576755D03*
X1452708Y610954D03*
Y607954D03*
X1449708Y610954D03*
X1446708D03*
Y607954D03*
X1449708D03*
X1440708Y610954D03*
X1443708D03*
X1440708Y607954D03*
X1443708D03*
X1452708Y613954D03*
X1446708Y616954D03*
Y619954D03*
X1440708D03*
Y616954D03*
X1443708D03*
Y619954D03*
X1449708Y613954D03*
X1446708D03*
X1440708D03*
X1443708D03*
X1446708Y622954D03*
X1440708D03*
X1443708D03*
X1452938Y617364D03*
X1450438D03*
X1452898Y621844D03*
X1450398D03*
X1448996Y645270D03*
Y647770D03*
X1451496Y645270D03*
X1453996D03*
Y647770D03*
X1451496D03*
X1449046Y650370D03*
X1454046D03*
X1451546D03*
X1446426D03*
X1443926D03*
X1443876Y645270D03*
Y647770D03*
X1446376Y645270D03*
Y647770D03*
X1447314Y684998D03*
X1442091Y684846D03*
X1442045Y682338D03*
X1448807Y695913D03*
Y693372D03*
X1445034Y688523D03*
X1452615Y705531D03*
X1441727Y747051D03*
X1444257Y757133D03*
Y759633D03*
Y762133D03*
X1441757Y759633D03*
Y762133D03*
X1441743Y757051D03*
Y754551D03*
Y752051D03*
Y749551D03*
X1444257Y772133D03*
Y764633D03*
Y769633D03*
Y767133D03*
X1441757Y772133D03*
Y764633D03*
Y769633D03*
Y767133D03*
X1442107Y1013504D03*
Y1009764D03*
Y1006024D03*
Y1020985D03*
Y1024725D03*
Y1028465D03*
Y1017244D03*
Y1032205D03*
X1451498Y1485895D03*
X1448098D03*
X1444798Y1495595D03*
X1441398D03*
X1439850Y1541470D03*
X1440401Y1574795D03*
Y1582295D03*
Y1579795D03*
Y1577295D03*
X1442901Y1582295D03*
Y1579795D03*
Y1577295D03*
Y1574795D03*
X1447026Y1577299D03*
X1448061Y1593055D03*
X1451000Y1601000D03*
X1446000Y1600500D03*
X1450500Y1614500D03*
Y1624000D03*
X1445500Y1614500D03*
X1441000D03*
X1440027Y1667945D03*
X1455579Y1665701D03*
X1453553Y1686892D03*
X1445079Y1686678D03*
X1449070Y1686722D03*
X1448000Y1676000D03*
X1464830Y59054D03*
X1466681Y78590D03*
X1454549Y107443D03*
X1455667Y125733D03*
X1463017Y139518D03*
X1456226Y152166D03*
X1462682Y450372D03*
X1456982Y437362D03*
X1466609Y458608D03*
X1465395Y487582D03*
X1465832Y530656D03*
X1463647Y544977D03*
X1464257Y560977D03*
Y557498D03*
X1462497Y555021D03*
X1464257Y568977D03*
Y572977D03*
Y580977D03*
Y576977D03*
X1467708Y610954D03*
Y607954D03*
X1464708Y610954D03*
Y607954D03*
X1458708Y610954D03*
X1455708D03*
X1461708D03*
Y607954D03*
X1455708D03*
X1458708D03*
X1467708Y616954D03*
Y619954D03*
Y613954D03*
X1461708Y616954D03*
Y619954D03*
X1464708Y616954D03*
Y619954D03*
Y613954D03*
X1458708D03*
X1455708D03*
X1461708D03*
X1467708Y622954D03*
X1461708D03*
X1464708D03*
X1455438Y617364D03*
X1457938D03*
X1455398Y621844D03*
X1457898D03*
X1456496Y645270D03*
X1459396D03*
X1456496Y647770D03*
X1459396D03*
X1456546Y650370D03*
X1459446D03*
X1467521Y702378D03*
X1454715Y700931D03*
X1468271Y704946D03*
X1462045Y711826D03*
X1464475D03*
X1459615D03*
X1456881Y708201D03*
Y705301D03*
X1454715Y706931D03*
Y703931D03*
X1454815Y709931D03*
X1458777Y714194D03*
Y717094D03*
X1456335Y771710D03*
Y766628D03*
X1458861Y776628D03*
X1461361D03*
X1458861Y769128D03*
Y771628D03*
Y774128D03*
X1461361D03*
Y771628D03*
Y769128D03*
X1461335Y766628D03*
X1458835D03*
X1456335Y776710D03*
Y774210D03*
Y769210D03*
X1461371Y791696D03*
Y789196D03*
X1458871Y779196D03*
X1461371D03*
X1458871Y784196D03*
Y781696D03*
Y786696D03*
X1461371Y784196D03*
Y786696D03*
Y781696D03*
X1456371Y779210D03*
Y781710D03*
Y784210D03*
X1456945Y1015473D03*
X1464526D03*
X1456945Y1019016D03*
Y1022559D03*
X1464526Y1019016D03*
Y1022559D03*
X1464898Y1505295D03*
X1461498D03*
X1468198Y1495595D03*
X1468102Y1670817D03*
X1458795Y1687083D03*
X1457940Y1675710D03*
X1463038Y1687060D03*
X1466111Y1685098D03*
X1472129Y56083D03*
X1483820Y132405D03*
X1471395Y487582D03*
X1473947Y492169D03*
X1472647Y539478D03*
X1475257Y530656D03*
X1473444Y555208D03*
X1473408Y547948D03*
X1478147Y547728D03*
X1478257Y543977D03*
X1481257Y544977D03*
X1482044Y542517D03*
X1472257Y551241D03*
X1472757Y561264D03*
X1473362Y558380D03*
X1472257Y564977D03*
X1481898Y585476D03*
X1484347Y580388D03*
X1478258Y588108D03*
Y584142D03*
X1474963Y701915D03*
X1480232Y704575D03*
X1475009Y704488D03*
X1481725Y715490D03*
X1471009Y703978D03*
X1481725Y712949D03*
X1477952Y708100D03*
X1477171Y774196D03*
Y771696D03*
Y769196D03*
Y776696D03*
X1474661Y776628D03*
Y774128D03*
Y771628D03*
Y769128D03*
X1472161Y776628D03*
Y769128D03*
Y771628D03*
Y774128D03*
X1472145Y766628D03*
X1474645D03*
X1477145D03*
X1477171Y791696D03*
X1474671D03*
X1472171D03*
X1477171Y786696D03*
X1474671D03*
X1477171Y781696D03*
X1474671D03*
X1472171Y789196D03*
Y779196D03*
Y784196D03*
Y786696D03*
Y781696D03*
X1477171Y789196D03*
X1474671D03*
X1477171Y779196D03*
X1474671D03*
X1477171Y784196D03*
X1474671D03*
X1481177Y803488D03*
X1469950Y813232D03*
X1473728Y813552D03*
X1480677Y813488D03*
X1484177Y812988D03*
X1474177Y816872D03*
X1471526Y1015473D03*
Y1019016D03*
Y1022559D03*
X1478298Y1485895D03*
X1474898D03*
X1471598Y1495595D03*
X1482798Y1685982D03*
X1469588Y1673342D03*
X1486000Y1686000D03*
X1470500Y1685500D03*
X1494891Y121171D03*
X1488647Y134562D03*
X1497386Y464980D03*
X1495682Y473302D03*
X1484395Y487582D03*
X1492514Y539657D03*
X1484416Y541658D03*
X1488510Y542816D03*
X1490602Y544755D03*
X1497310Y543960D03*
X1494967Y541898D03*
X1487660Y585748D03*
X1491677Y583588D03*
X1490677Y580688D03*
X1492789Y576602D03*
X1495236Y612838D03*
X1495486Y599938D03*
X1497986Y602438D03*
Y599938D03*
X1495236Y605338D03*
X1495486Y602438D03*
X1495236Y607838D03*
Y610338D03*
X1492636Y605258D03*
Y607758D03*
Y610258D03*
Y612758D03*
X1497986Y612838D03*
Y605338D03*
Y607838D03*
Y610338D03*
X1495486Y615988D03*
Y618488D03*
X1497986Y615988D03*
Y618488D03*
X1492886Y618408D03*
Y615908D03*
X1497587Y711636D03*
X1495157D03*
X1492727D03*
X1489963Y705301D03*
X1487797Y706931D03*
X1487897Y709931D03*
X1489963Y708201D03*
X1485697Y708431D03*
Y705531D03*
Y711331D03*
X1492264Y714544D03*
Y717444D03*
X1491943Y776628D03*
X1494443D03*
X1491943Y769128D03*
Y771628D03*
Y774128D03*
X1494443D03*
Y771628D03*
Y769128D03*
X1494417Y766628D03*
X1491917D03*
X1489417Y776710D03*
Y774210D03*
Y769210D03*
Y771710D03*
Y766628D03*
X1494487Y779210D03*
Y784210D03*
Y786710D03*
Y781710D03*
X1491987Y779210D03*
Y784210D03*
Y786710D03*
Y781710D03*
X1489487Y779210D03*
Y784210D03*
Y786710D03*
Y781710D03*
X1500500Y809063D03*
X1496532Y803513D03*
X1485177Y803488D03*
X1489177Y812988D03*
X1487923Y816770D03*
X1490973Y825557D03*
X1498177Y829359D03*
X1495670Y826073D03*
X1486761Y826279D03*
X1493260Y1167390D03*
X1496960D03*
X1491698Y1505295D03*
X1488298D03*
X1498398Y1495595D03*
X1494998D03*
X1488875Y1677385D03*
X1503785Y464815D03*
X1505974Y470636D03*
X1511917Y483878D03*
X1499752Y488424D03*
X1502085Y545432D03*
X1507109Y550059D03*
X1507644Y554372D03*
X1507468Y564357D03*
X1506337Y561677D03*
X1502757Y570977D03*
X1508281Y559390D03*
X1509757Y575477D03*
X1501821Y577664D03*
X1502986Y602438D03*
Y599938D03*
X1500486Y602438D03*
Y599938D03*
X1502486Y605338D03*
Y607838D03*
Y610338D03*
Y612838D03*
X1500486Y615988D03*
Y618488D03*
X1502986Y615988D03*
Y618488D03*
X1500603Y702378D03*
X1508045Y701915D03*
X1513314Y704575D03*
X1508045Y704423D03*
X1504091Y703978D03*
X1501353Y704946D03*
X1511034Y708100D03*
X1510287Y771710D03*
Y769210D03*
Y774210D03*
Y776710D03*
X1507743Y776628D03*
Y774128D03*
Y771628D03*
Y769128D03*
X1505243Y776628D03*
Y769128D03*
Y771628D03*
Y774128D03*
X1505227Y766628D03*
X1507727D03*
X1510227D03*
X1507787Y786710D03*
Y781710D03*
X1505287Y779210D03*
Y784210D03*
Y786710D03*
Y781710D03*
X1510287Y779210D03*
Y784210D03*
Y786710D03*
Y781710D03*
X1507787Y779210D03*
Y784210D03*
X1508177Y803488D03*
X1501500Y799948D03*
X1510261Y814611D03*
X1500422Y814180D03*
X1512523Y809679D03*
X1502177Y817013D03*
X1512539Y812920D03*
X1505016Y817107D03*
X1501636Y828796D03*
X1499469Y860322D03*
Y863322D03*
X1504362Y1167390D03*
X1508063D03*
X1505098Y1485895D03*
X1501698D03*
X1515854Y119810D03*
X1517708Y216505D03*
X1527392Y238017D03*
X1519120Y479215D03*
X1515936Y484412D03*
X1516757Y537477D03*
X1516257Y547977D03*
X1516336Y551977D03*
X1519457Y556338D03*
X1519317Y561977D03*
X1527853Y560264D03*
X1524777Y605488D03*
Y607988D03*
X1527277Y605488D03*
Y607988D03*
X1524777Y610588D03*
X1527277D03*
X1524777Y613088D03*
X1527277D03*
X1524777Y615618D03*
X1527277D03*
X1524777Y618118D03*
X1527277D03*
X1514807Y715490D03*
Y712949D03*
X1525527Y711636D03*
X1527957D03*
X1522763Y708201D03*
Y705301D03*
X1518497Y705531D03*
X1520597Y706931D03*
X1518497Y708431D03*
X1520697Y709931D03*
X1518497Y711331D03*
X1525064Y714544D03*
Y717444D03*
X1522217Y771710D03*
X1527217Y766628D03*
X1522217Y769210D03*
X1524717Y766628D03*
X1522217D03*
Y774210D03*
Y776710D03*
X1524743Y776628D03*
X1527243D03*
X1524743Y769128D03*
Y771628D03*
Y774128D03*
X1527243D03*
Y771628D03*
Y769128D03*
X1527217Y779210D03*
Y784210D03*
Y786710D03*
Y781710D03*
X1524717Y779210D03*
X1522217D03*
X1524717Y784210D03*
Y786710D03*
X1522217Y784210D03*
Y786710D03*
X1524717Y781710D03*
X1522217D03*
X1517431Y811466D03*
X1521003Y1169488D03*
X1521217Y1190088D03*
X1524425Y1185241D03*
X1528498Y1485895D03*
X1518498Y1505295D03*
X1525198Y1495595D03*
X1515098Y1505295D03*
X1521798Y1495595D03*
X1538342Y28406D03*
X1540342Y48720D03*
X1537450Y226293D03*
X1533160Y231250D03*
X1536538Y296819D03*
X1536422Y292816D03*
X1536542Y308819D03*
X1534584Y467067D03*
X1539693Y543613D03*
X1532824Y555981D03*
X1539693Y558943D03*
X1532730Y562949D03*
X1534565Y564945D03*
X1533403Y702378D03*
X1540845Y701915D03*
Y704423D03*
X1536891Y703978D03*
X1534153Y704946D03*
X1543834Y708100D03*
X1530387Y711636D03*
X1538027Y766628D03*
X1540527D03*
X1540543Y776628D03*
Y774128D03*
Y771628D03*
Y769128D03*
X1538043Y776628D03*
Y769128D03*
Y771628D03*
Y774128D03*
X1538027Y784710D03*
Y779210D03*
X1540527D03*
X1538027Y781710D03*
X1540527D03*
X1539972Y807319D03*
X1529306Y1177468D03*
X1540801Y1178265D03*
X1537301D03*
X1539301Y1175765D03*
X1532896Y1234836D03*
X1542747Y1253602D03*
X1538587Y1245065D03*
X1543772Y1241016D03*
X1543519Y1248205D03*
X1536916Y1240844D03*
X1531898Y1485895D03*
X1541898D03*
X1543582Y1524562D03*
X1541191Y1544953D03*
Y1547453D03*
Y1549953D03*
X1539369Y1552250D03*
X1541876Y1554436D03*
X1539344Y1579519D03*
X1552674Y26477D03*
X1556379Y19541D03*
X1549274Y26477D03*
X1554360Y207251D03*
X1556960Y287478D03*
X1551900Y287288D03*
X1544489Y288816D03*
X1546789Y287116D03*
X1548772Y291916D03*
X1553154Y479063D03*
X1558198Y486791D03*
X1551779Y530698D03*
X1546149Y541169D03*
X1545987Y562012D03*
X1553657Y678965D03*
X1553827Y687991D03*
X1556027Y680391D03*
X1555893Y686261D03*
Y683361D03*
X1553657Y681965D03*
X1553727Y684991D03*
X1558657Y689696D03*
X1558194Y695501D03*
Y692501D03*
X1546114Y704575D03*
X1547607Y715490D03*
Y712949D03*
X1556708Y747282D03*
X1556688Y744688D03*
X1556708Y749782D03*
Y754782D03*
Y752282D03*
Y757282D03*
Y762282D03*
Y759782D03*
Y764782D03*
Y769782D03*
Y767282D03*
X1556121Y798542D03*
X1551124Y801289D03*
X1551961Y807269D03*
X1556361D03*
X1547561D03*
X1551113Y1238088D03*
X1548360Y1234750D03*
X1550517Y1232905D03*
X1545627Y1254068D03*
X1545480Y1245090D03*
X1544911Y1260654D03*
X1543980Y1258312D03*
X1554692Y1269688D03*
X1557559Y1269095D03*
X1557510Y1280291D03*
X1554377Y1278763D03*
X1560454Y1279004D03*
X1553226Y1288814D03*
X1553548Y1284991D03*
X1556515Y1292232D03*
X1555222Y1302757D03*
X1547195Y1478165D03*
X1547216Y1480812D03*
X1545298Y1485895D03*
X1545473Y1522117D03*
X1547548Y1520070D03*
X1552668Y1513682D03*
Y1517082D03*
Y1530482D03*
Y1527082D03*
X1551821Y1549120D03*
Y1545220D03*
X1551546Y1552845D03*
X1556071Y1547576D03*
X1554635Y1542469D03*
X1552135D03*
X1556071Y1545076D03*
X1545644Y1552845D03*
X1545521Y1549120D03*
Y1545220D03*
X1548671Y1549120D03*
Y1545220D03*
X1548684Y1554436D03*
X1554093Y1582295D03*
Y1574795D03*
Y1579795D03*
Y1577295D03*
X1551593Y1582295D03*
Y1579795D03*
X1556593Y1582295D03*
Y1579795D03*
Y1574795D03*
Y1577295D03*
X1549093Y1579795D03*
Y1582295D03*
X1546593D03*
Y1579795D03*
X1558560Y1571682D03*
X1556060D03*
X1557633Y1584844D03*
X1566847Y26477D03*
X1559779Y19541D03*
X1570552D03*
X1563447Y26477D03*
X1572502Y254250D03*
X1572549Y257491D03*
X1566442Y294816D03*
X1564506Y310334D03*
Y313734D03*
X1571516Y319099D03*
X1568070Y497847D03*
X1573070D03*
X1570570D03*
X1570068Y534095D03*
X1573326Y543351D03*
X1573487Y546996D03*
X1572436Y578933D03*
X1568446Y582733D03*
X1572436Y582433D03*
X1564946Y582733D03*
X1561246Y580393D03*
X1572436Y574022D03*
X1568936Y585933D03*
Y589433D03*
X1565436Y585933D03*
Y589433D03*
X1562016Y584283D03*
Y587783D03*
X1572436Y589433D03*
Y585933D03*
X1566533Y680438D03*
X1570021Y682038D03*
X1567283Y683006D03*
X1563517Y689696D03*
X1561087D03*
X1572514Y747188D03*
X1561714D03*
X1559214D03*
X1561688Y744688D03*
X1559188D03*
X1572498D03*
X1572588Y757282D03*
Y759782D03*
X1561708Y757282D03*
X1559208D03*
X1561708Y759782D03*
X1559208D03*
X1561708Y762282D03*
X1559208D03*
X1572514Y752188D03*
Y749688D03*
Y754688D03*
X1561714Y749688D03*
Y752188D03*
X1559214D03*
Y749688D03*
X1561714Y754688D03*
X1559214D03*
X1561708Y769782D03*
X1559208D03*
X1561708Y767282D03*
X1559208D03*
X1561708Y764782D03*
X1559208D03*
X1570583Y800104D03*
X1572668Y806778D03*
X1567737Y1271411D03*
X1561927Y1269901D03*
X1559181Y1287165D03*
X1568100Y1290418D03*
X1567000Y1293446D03*
X1562820Y1309360D03*
X1568456Y1311533D03*
X1572416Y1303160D03*
X1564268Y1338440D03*
X1562937Y1341609D03*
X1572331Y1348205D03*
X1566901Y1347726D03*
X1564758Y1367834D03*
X1572906Y1366759D03*
X1563967Y1363205D03*
X1572860Y1495595D03*
X1569460D03*
X1563222Y1516590D03*
Y1513190D03*
Y1534990D03*
Y1538390D03*
X1567089Y1563596D03*
X1562640Y1556331D03*
Y1559731D03*
X1559093Y1577295D03*
Y1574795D03*
X1565963D03*
X1568463D03*
X1565963Y1577295D03*
X1568463D03*
Y1579795D03*
X1565963D03*
X1568463Y1582295D03*
X1565963D03*
X1570963Y1574795D03*
Y1582295D03*
Y1579795D03*
Y1577295D03*
X1563463Y1574795D03*
Y1582295D03*
Y1579795D03*
Y1577295D03*
X1560051Y1581199D03*
X1574966Y1577038D03*
X1562556Y1584844D03*
X1560051Y1584099D03*
X1588125Y19541D03*
X1581020Y26477D03*
X1573952Y19541D03*
X1584725D03*
X1577620Y26477D03*
X1586291Y303596D03*
X1586621Y484304D03*
X1580519Y497650D03*
X1575570Y497847D03*
X1584397Y655622D03*
X1586497Y651222D03*
X1586597Y654222D03*
X1584397Y652722D03*
Y649822D03*
X1573975Y679975D03*
X1579244Y682635D03*
X1573975Y682483D03*
X1576964Y686160D03*
X1580737Y693550D03*
Y691009D03*
X1577588Y747282D03*
X1575014Y747188D03*
X1577498Y744688D03*
X1574998D03*
X1575088Y757282D03*
X1577588Y749782D03*
Y754782D03*
Y752282D03*
X1575014Y749688D03*
Y752188D03*
Y754688D03*
X1578690Y1283310D03*
X1585290Y1285098D03*
X1574168Y1283300D03*
X1577077Y1270937D03*
X1580577D03*
X1584068Y1271198D03*
X1580010Y1296100D03*
X1574560Y1296410D03*
X1580520Y1289900D03*
X1586167Y1295478D03*
X1575024Y1306373D03*
X1586557Y1304509D03*
X1578336Y1359253D03*
X1578411Y1348623D03*
X1578020Y1344773D03*
X1584156Y1381419D03*
X1586000Y1387641D03*
X1590723Y1381589D03*
X1579560Y1485895D03*
X1576160D03*
X1602299Y19541D03*
X1595194Y26477D03*
X1598899Y19541D03*
X1591794Y26477D03*
X1603970Y222956D03*
X1593303Y234250D03*
Y239250D03*
X1598303Y234250D03*
X1596462Y229790D03*
X1593658Y252010D03*
X1593303Y244250D03*
X1593349Y248160D03*
X1597481Y271991D03*
X1600918Y521688D03*
X1604890Y531226D03*
X1596299Y536344D03*
X1599303Y646669D03*
X1602791Y648269D03*
X1600053Y649237D03*
X1596287Y655927D03*
X1591427D03*
X1593857D03*
X1588663Y649592D03*
Y652492D03*
X1590964Y661741D03*
Y658741D03*
X1594844Y713419D03*
Y715919D03*
X1592344D03*
Y713419D03*
X1594818Y710919D03*
X1594844Y718419D03*
X1592344D03*
X1594844Y720919D03*
X1592344D03*
X1594688Y723512D03*
Y726012D03*
Y728512D03*
Y731012D03*
X1592188Y723512D03*
Y726012D03*
Y728512D03*
Y731012D03*
X1594688Y736012D03*
X1592188D03*
X1594688Y733512D03*
X1592188D03*
X1594900Y780112D03*
X1598467Y1267539D03*
X1588832Y1269083D03*
X1597177Y1282288D03*
X1594152Y1282578D03*
X1598883Y1270766D03*
X1590827Y1271378D03*
X1593397Y1271458D03*
X1596273Y1271472D03*
X1591005Y1288892D03*
X1596363Y1286296D03*
X1590921Y1309276D03*
X1599241Y1306622D03*
X1589845Y1305289D03*
X1599007Y1309762D03*
X1597621Y1365384D03*
X1595438Y1370603D03*
X1592788Y1388318D03*
X1597234Y1382689D03*
X1600531Y1404710D03*
X1597992Y1433183D03*
X1595716Y1431861D03*
X1602782Y1435920D03*
X1600442Y1434535D03*
X1602960Y1485895D03*
X1592960Y1505295D03*
X1599660Y1495595D03*
X1589560Y1505295D03*
X1596260Y1495595D03*
X1615020Y183050D03*
X1619909Y298742D03*
Y293742D03*
X1612144Y418552D03*
X1614701Y422587D03*
X1616464Y457509D03*
X1616250Y465042D03*
X1609166Y527300D03*
X1611775D03*
X1609166Y524700D03*
X1611775D03*
X1613169Y531819D03*
X1604991Y536344D03*
X1616084Y549105D03*
X1616198Y556364D03*
X1618859Y542820D03*
X1618356Y612137D03*
Y609137D03*
X1618434Y605753D03*
X1609044Y600986D03*
X1617397Y630822D03*
Y636622D03*
Y633722D03*
X1606745Y646206D03*
X1612014Y648866D03*
X1606745Y648714D03*
X1613507Y657240D03*
X1609734Y652391D03*
X1613507Y659781D03*
X1605644Y715919D03*
Y713419D03*
X1608144D03*
Y715919D03*
X1605628Y710919D03*
X1608128D03*
X1610628D03*
X1610718Y713513D03*
Y716013D03*
X1605644Y718419D03*
Y720919D03*
X1608144Y718419D03*
Y720919D03*
X1610718Y721013D03*
Y718513D03*
X1608118Y723512D03*
X1605618D03*
X1608118Y726012D03*
X1605618D03*
X1610618Y723512D03*
X1605618Y728512D03*
X1617200Y766870D03*
X1607267Y1271978D03*
X1604137Y1271358D03*
X1605801Y1286168D03*
X1608901Y1285887D03*
X1605360Y1294595D03*
X1608652Y1303338D03*
X1608341Y1313269D03*
X1608418Y1333589D03*
Y1331089D03*
X1614767Y1443512D03*
X1605648Y1437305D03*
X1606360Y1485895D03*
X1616360Y1505295D03*
X1622329Y28261D03*
X1631060Y26477D03*
X1627660D03*
X1623189Y48720D03*
X1631200Y164110D03*
X1631455Y167875D03*
X1627152Y168920D03*
X1629597Y227157D03*
X1627156Y238303D03*
X1627986Y282728D03*
X1627909Y286742D03*
Y298742D03*
Y294742D03*
Y290742D03*
X1619909Y303596D03*
X1627909Y302742D03*
X1621680Y366920D03*
X1625000Y383399D03*
X1631657Y392925D03*
X1632012Y603015D03*
X1621512D03*
X1625012D03*
X1628512D03*
X1632303Y627669D03*
X1633053Y630237D03*
X1626857Y636927D03*
X1629287D03*
X1624427D03*
X1621663Y630592D03*
X1619597Y635222D03*
X1621663Y633492D03*
X1619497Y632222D03*
X1623964Y642741D03*
Y639741D03*
X1627643Y694419D03*
Y696919D03*
Y699419D03*
X1625143D03*
Y696919D03*
Y694419D03*
X1627643Y701919D03*
X1625143D03*
X1627617Y691919D03*
X1625117D03*
Y709512D03*
Y704512D03*
Y707012D03*
Y712012D03*
X1627617Y709512D03*
Y704512D03*
Y707012D03*
Y712012D03*
X1628046Y763765D03*
X1626928Y1260917D03*
X1629428D03*
X1631928D03*
X1626333Y1311091D03*
Y1308091D03*
X1627174Y1420450D03*
X1625285Y1433384D03*
X1635281Y1422450D03*
X1627217Y1428366D03*
X1622697Y1440797D03*
X1625170Y1444016D03*
X1635227Y1436528D03*
X1633160Y1485895D03*
X1629760D03*
X1619760Y1505295D03*
X1626460Y1495595D03*
X1623060D03*
X1645233Y26477D03*
X1638165Y19541D03*
X1641833Y26477D03*
X1634765Y19541D03*
X1636047Y224597D03*
Y229912D03*
X1647310Y408922D03*
Y411422D03*
X1635697Y561253D03*
X1635944Y609510D03*
Y612510D03*
X1636022Y606126D03*
X1647158Y618971D03*
X1639745Y627206D03*
X1646507Y640781D03*
X1645014Y629866D03*
X1639745Y629714D03*
X1635791Y629269D03*
X1646507Y638240D03*
X1642734Y633391D03*
X1638443Y699419D03*
Y696919D03*
Y694419D03*
Y701919D03*
X1640943Y694419D03*
Y696919D03*
Y699419D03*
Y701919D03*
X1643517Y702013D03*
Y699513D03*
Y694513D03*
Y697013D03*
X1643427Y691919D03*
X1640927D03*
X1638427D03*
X1640877Y706972D03*
Y709472D03*
X1638377D03*
Y704472D03*
Y706972D03*
X1640877Y704472D03*
X1643377Y709510D03*
Y704510D03*
Y707010D03*
X1640877Y711972D03*
X1638377D03*
X1643377Y712010D03*
X1635088Y767205D03*
Y771005D03*
X1644188Y766870D03*
X1634428Y1260917D03*
X1645163Y1276184D03*
X1641677Y1341488D03*
Y1344488D03*
X1641087Y1396118D03*
X1641065Y1403393D03*
X1644001Y1408069D03*
X1646483Y1412741D03*
X1641065Y1406393D03*
X1635619Y1430536D03*
X1639834Y1434478D03*
X1636167Y1446746D03*
X1642400Y1439674D03*
X1645979Y1437950D03*
X1650400Y1437820D03*
X1641167Y1446746D03*
X1646560Y1505295D03*
X1643160D03*
X1646879Y1681738D03*
X1645029Y1715609D03*
Y1710609D03*
X1648029Y1708609D03*
Y1723759D03*
X1645029Y1725759D03*
Y1730759D03*
X1652338Y19541D03*
X1648938D03*
X1652525Y146762D03*
Y151762D03*
Y161762D03*
X1650023Y221842D03*
X1654419Y224597D03*
X1659419D03*
X1650023Y227157D03*
X1654419Y229912D03*
X1661928Y230172D03*
X1650020Y408952D03*
Y411452D03*
X1654110Y434177D03*
X1657545Y434506D03*
X1650035Y434750D03*
X1657194Y599956D03*
X1651194D03*
X1660194Y609450D03*
X1654194D03*
X1660194Y599956D03*
X1657194Y609450D03*
X1654194Y599956D03*
X1651194Y609450D03*
X1654147Y616523D03*
X1662377Y696300D03*
Y693300D03*
X1651072Y1314137D03*
X1660572Y1313837D03*
X1660635Y1329166D03*
X1651072Y1323137D03*
Y1320137D03*
Y1317137D03*
X1660572Y1322837D03*
Y1319837D03*
X1660635Y1326466D03*
X1660572Y1316837D03*
X1658015Y1328966D03*
X1658115Y1326466D03*
X1660635Y1331666D03*
Y1334166D03*
Y1339166D03*
Y1336666D03*
X1650177Y1341488D03*
X1658277Y1341888D03*
X1658015Y1336466D03*
Y1338966D03*
Y1331466D03*
Y1333966D03*
X1650177Y1344488D03*
X1658677D03*
X1653390Y1386316D03*
Y1388857D03*
X1649197Y1396743D03*
X1654883Y1397231D03*
X1660152Y1397383D03*
X1664106Y1397828D03*
X1660152Y1399891D03*
X1657163Y1393706D03*
X1661807Y1416948D03*
X1663777Y1421568D03*
X1662487Y1424178D03*
X1658089Y1437444D03*
X1649380Y1446713D03*
X1659960Y1485895D03*
X1656560D03*
X1653260Y1495595D03*
X1649860D03*
X1659975Y1592929D03*
X1656101Y1671720D03*
X1651101Y1671833D03*
X1653930Y1660640D03*
X1656180Y1659220D03*
X1656849Y1664949D03*
X1651698Y1665045D03*
X1661125Y1690751D03*
X1656101Y1701094D03*
X1656997Y1718759D03*
Y1733909D03*
X1675194Y26477D03*
X1671794D03*
X1673100Y121762D03*
Y136762D03*
Y131762D03*
X1673403Y199997D03*
X1664335Y210191D03*
X1663310Y215488D03*
X1664789Y767265D03*
Y771065D03*
X1673889Y766870D03*
X1674972Y1313837D03*
X1675134Y1329219D03*
X1675234Y1326519D03*
X1674972Y1316837D03*
X1672623Y1326476D03*
X1663437Y1326526D03*
X1674972Y1319837D03*
Y1322837D03*
X1677754Y1326519D03*
Y1329019D03*
X1663437Y1334726D03*
X1672623Y1334676D03*
X1663437Y1329726D03*
X1672623Y1332176D03*
X1663437Y1332226D03*
X1672623Y1329676D03*
X1675134Y1331719D03*
Y1334219D03*
Y1336719D03*
Y1339219D03*
X1677754Y1339019D03*
Y1336519D03*
Y1331519D03*
Y1334019D03*
X1675931Y1384335D03*
Y1387235D03*
X1667594Y1399428D03*
X1666844Y1396860D03*
X1675470Y1390170D03*
X1673040D03*
X1670610D03*
X1672501Y1416678D03*
X1675641Y1432891D03*
X1672401Y1423365D03*
X1664237Y1426278D03*
X1671079Y1435069D03*
X1663239Y1428592D03*
X1670147Y1444311D03*
X1673360Y1485895D03*
X1669960D03*
X1676685Y1537893D03*
X1671034Y1549734D03*
Y1552234D03*
X1668703Y1550898D03*
X1671034Y1546934D03*
X1668827Y1553551D03*
X1671034Y1557234D03*
Y1554734D03*
X1673706Y1560425D03*
X1671006Y1576744D03*
Y1574244D03*
Y1571744D03*
X1668826Y1575498D03*
Y1572998D03*
X1676176Y1580650D03*
X1674923Y1582973D03*
X1677556Y1656405D03*
X1674356D03*
X1671156D03*
X1666168Y1667688D03*
X1670202Y1663150D03*
X1675290Y1663157D03*
X1674338Y1677832D03*
X1671902Y1676267D03*
X1669377Y1675241D03*
X1670773Y1688827D03*
X1680029Y1710609D03*
Y1715609D03*
X1672500Y1708927D03*
X1675360Y1721252D03*
X1689367Y26477D03*
X1682299Y19541D03*
X1685967Y26477D03*
X1678899Y19541D03*
X1695100Y121762D03*
X1683275Y120762D03*
X1695100Y136762D03*
Y131762D03*
X1684925D03*
Y136762D03*
Y123762D03*
Y126762D03*
Y145762D03*
X1695100Y146762D03*
X1684925Y141762D03*
X1695100Y156762D03*
Y161762D03*
Y166762D03*
X1684925Y157762D03*
Y166762D03*
X1678809Y206451D03*
X1682433Y220857D03*
X1682408Y228337D03*
X1689000Y234000D03*
X1692429Y403985D03*
X1694050Y416643D03*
X1690208Y421855D03*
X1690140Y434160D03*
X1692450Y436772D03*
X1692974Y553115D03*
X1685890Y708610D03*
X1684672Y1313837D03*
X1690697Y1329066D03*
Y1326566D03*
X1684672Y1322837D03*
Y1319837D03*
Y1316837D03*
X1690697Y1336566D03*
Y1334066D03*
Y1331566D03*
X1679028Y1341733D03*
X1687234Y1341533D03*
Y1344033D03*
X1679028Y1344233D03*
X1690697Y1339066D03*
X1686172Y1386416D03*
Y1388957D03*
X1687665Y1397331D03*
X1692934Y1397483D03*
Y1399991D03*
X1689945Y1393806D03*
X1682500Y1390475D03*
X1680300Y1391875D03*
X1682500Y1396275D03*
X1680400Y1394875D03*
X1678234Y1393605D03*
Y1396505D03*
X1682500Y1393375D03*
X1683741Y1443075D03*
X1681538Y1451522D03*
X1689062Y1451496D03*
X1687783Y1472068D03*
X1680730Y1517082D03*
Y1513682D03*
Y1530482D03*
Y1527082D03*
X1685745Y1552579D03*
X1686219Y1549994D03*
X1685745Y1555079D03*
Y1557579D03*
X1685995Y1561516D03*
X1680589Y1559626D03*
Y1563526D03*
X1690353Y1591494D03*
X1680695Y1656307D03*
X1686675Y1659287D03*
X1692415Y1663740D03*
X1685500Y1663599D03*
X1680367Y1663367D03*
X1691952Y1698947D03*
X1689184Y1702095D03*
X1683029Y1708609D03*
X1680877Y1723593D03*
X1692218Y1717539D03*
X1685383Y1729559D03*
X1707186Y15708D03*
X1696472Y19541D03*
X1693072D03*
X1703583Y26505D03*
X1700183D03*
X1703536Y50649D03*
X1700136D03*
X1695100Y126762D03*
Y141762D03*
Y151762D03*
X1705120Y143610D03*
X1693000Y234000D03*
X1698220Y369652D03*
X1699809Y403985D03*
X1695579D03*
X1702959Y404243D03*
X1697161Y406602D03*
X1706500Y415862D03*
Y413362D03*
X1707780Y410738D03*
X1695455Y422287D03*
X1707568Y420370D03*
X1701124Y423802D03*
X1707544Y431745D03*
X1704974Y553115D03*
X1700974D03*
X1696974D03*
X1693490Y620672D03*
X1697530Y636369D03*
X1701661Y644554D03*
X1705561D03*
X1699500Y654738D03*
Y673738D03*
X1694490Y767265D03*
Y771065D03*
X1708049Y766870D03*
X1699072Y1313737D03*
X1696047Y1326576D03*
X1705383D03*
X1693417Y1329266D03*
X1693217Y1326566D03*
X1699072Y1322737D03*
Y1319737D03*
Y1316737D03*
X1693417Y1334266D03*
Y1331766D03*
X1705383Y1334676D03*
X1696047D03*
X1705383Y1329676D03*
X1696047Y1332176D03*
Y1329676D03*
X1705383Y1332176D03*
X1693417Y1336766D03*
Y1339266D03*
X1700376Y1399528D03*
X1696888Y1397928D03*
X1699626Y1396960D03*
X1703392Y1390270D03*
X1705822D03*
X1700272Y1460547D03*
X1702281Y1449801D03*
X1705108Y1451774D03*
X1695020Y1465621D03*
X1698440Y1466590D03*
X1705246Y1465325D03*
X1701348Y1466557D03*
X1709964Y1597490D03*
X1709833Y1612940D03*
Y1606340D03*
X1701984Y1671618D03*
X1695987D03*
X1700156Y1698830D03*
X1702750Y1696185D03*
X1706086Y1691568D03*
X1717148Y19910D03*
X1712977Y19986D03*
X1722148Y19910D03*
X1722085Y25908D03*
X1717055D03*
X1710106Y39768D03*
X1723241Y48822D03*
X1710106Y48978D03*
X1721646Y68115D03*
X1716558Y67866D03*
X1715861Y72593D03*
X1712486Y117908D03*
X1712686Y111908D03*
X1719909Y112713D03*
Y116713D03*
X1713399Y132858D03*
X1721384Y135373D03*
X1717384D03*
X1716609Y141297D03*
X1721628Y147312D03*
X1714293Y156278D03*
X1711293D03*
X1716893D03*
X1719493D03*
X1722093D03*
X1711293Y158878D03*
X1714293D03*
X1711293Y161478D03*
X1714293D03*
X1711293Y163978D03*
X1714293D03*
X1711293Y166478D03*
X1714293D03*
X1722093Y158878D03*
X1719493D03*
X1716893D03*
X1722093Y161478D03*
Y163978D03*
Y166478D03*
X1719493Y161478D03*
X1716893D03*
X1719493Y163978D03*
X1716893D03*
Y166478D03*
X1719493D03*
X1719200Y371162D03*
X1717220Y381152D03*
X1713720D03*
X1717220Y384652D03*
Y388152D03*
X1713720D03*
Y384652D03*
X1717220Y391652D03*
X1713720D03*
X1709000Y415862D03*
Y413362D03*
X1709339Y637251D03*
X1718465Y657982D03*
X1720050Y649142D03*
X1716030Y668182D03*
X1709759Y670221D03*
X1718686Y676154D03*
X1722672Y1313237D03*
X1708672Y1313737D03*
X1707916Y1329319D03*
X1722672Y1316237D03*
X1708672Y1322737D03*
Y1319737D03*
X1710536Y1329119D03*
X1708016Y1326619D03*
X1710536D03*
X1722672Y1319237D03*
Y1322237D03*
X1719916Y1326559D03*
X1717396D03*
X1719916Y1329059D03*
X1717396D03*
X1708672Y1316737D03*
X1707916Y1334319D03*
Y1331819D03*
Y1339319D03*
Y1336819D03*
X1710536Y1336619D03*
Y1339119D03*
X1719916Y1339059D03*
X1717396D03*
X1719916Y1336559D03*
X1717396D03*
X1710536Y1334119D03*
Y1331619D03*
X1719916Y1331559D03*
Y1334059D03*
X1717396D03*
Y1331559D03*
X1710176Y1342089D03*
X1718706Y1341629D03*
Y1344129D03*
X1710176Y1344589D03*
X1708713Y1384435D03*
Y1387335D03*
X1708252Y1390270D03*
X1715282Y1396375D03*
X1713082Y1391975D03*
X1715282Y1390575D03*
X1711016Y1393705D03*
Y1396605D03*
X1713182Y1394975D03*
X1715282Y1393475D03*
X1717447Y1417213D03*
X1714447D03*
X1717447Y1423213D03*
Y1420213D03*
X1714447D03*
Y1423213D03*
X1722334Y1468146D03*
X1718425Y1468245D03*
X1722347Y1471246D03*
X1716070Y1472037D03*
X1712870Y1586615D03*
X1715693Y1597190D03*
X1713593Y1609640D03*
Y1603040D03*
X1720845Y1668498D03*
X1719181Y1706712D03*
X1721172Y1712115D03*
X1710360Y1706502D03*
X1721912Y1705115D03*
X1719218Y1727265D03*
X1719148Y1721530D03*
X1722149Y1720265D03*
X1710230Y1729654D03*
X1736006Y41838D03*
Y44338D03*
X1729836Y54524D03*
X1727336D03*
X1724685Y51454D03*
X1727225Y51424D03*
X1729895Y51354D03*
X1726741Y48822D03*
X1730241D03*
X1737617Y75640D03*
Y73140D03*
Y79140D03*
Y81640D03*
X1722984Y101713D03*
X1723184Y93313D03*
X1736731Y102293D03*
X1728965Y112941D03*
X1729046Y118178D03*
X1739686Y120938D03*
X1725093Y156278D03*
Y158878D03*
Y161478D03*
Y163978D03*
Y166478D03*
X1735471Y293682D03*
Y290682D03*
Y296682D03*
Y299682D03*
X1730331Y293722D03*
Y296722D03*
X1732831D03*
X1730331Y299722D03*
X1732831D03*
Y293722D03*
X1723492Y293068D03*
X1732751Y305732D03*
X1730251D03*
X1732751Y302732D03*
X1730251D03*
X1735391Y305692D03*
Y302692D03*
X1725344Y359334D03*
X1728300Y377787D03*
X1733043Y657091D03*
X1736848Y650974D03*
X1726409Y653641D03*
X1737002Y671494D03*
X1724191Y767299D03*
Y771099D03*
X1737850Y766794D03*
X1732702Y1313007D03*
Y1316007D03*
Y1322007D03*
Y1319007D03*
X1732766Y1410562D03*
Y1413062D03*
X1735266Y1410562D03*
Y1413062D03*
X1732766Y1426362D03*
Y1428862D03*
X1735266Y1426362D03*
Y1428862D03*
X1730004Y1540968D03*
X1726604Y1540970D03*
X1735379Y1566282D03*
X1735354Y1580480D03*
X1735351Y1569832D03*
X1736479Y1584330D03*
X1730202Y1602093D03*
X1735463Y1651965D03*
X1730381Y1647386D03*
X1726381D03*
X1734500Y1656965D03*
X1734589Y1666203D03*
X1734962Y1662965D03*
X1734963Y1673465D03*
X1724263Y1672465D03*
X1734763Y1680465D03*
X1735463Y1694465D03*
X1725423Y1692656D03*
X1731936Y1690165D03*
X1731117Y1715265D03*
X1732251Y1708265D03*
X1731117Y1730415D03*
X1748708Y26641D03*
X1751031Y39063D03*
X1738093Y53103D03*
Y55603D03*
X1741621Y76613D03*
Y74113D03*
Y82613D03*
Y80113D03*
X1743491Y92827D03*
X1738435Y100244D03*
X1741935D03*
X1745435D03*
X1740231Y102293D03*
X1743731D03*
X1748686Y97408D03*
X1740091Y92827D03*
X1750786Y120018D03*
X1744976Y122998D03*
X1754339Y128242D03*
X1752022Y269794D03*
Y266794D03*
X1742971Y293682D03*
Y290682D03*
X1737971D03*
X1740471Y293682D03*
Y290682D03*
Y299682D03*
X1737971D03*
X1740471Y296682D03*
X1737971D03*
Y293682D03*
X1751352Y293386D03*
X1745671Y290682D03*
Y293682D03*
X1737891Y302692D03*
X1740391D03*
X1737891Y305692D03*
X1740391D03*
X1744510Y377452D03*
X1744380Y382892D03*
X1742398Y484304D03*
X1742306Y661032D03*
X1745484Y668216D03*
X1751490Y713890D03*
X1748990D03*
X1746490D03*
X1743990D03*
X1751490Y706390D03*
X1748990D03*
X1746490D03*
X1743990D03*
X1751490Y708890D03*
X1748990D03*
X1746490D03*
X1743990D03*
X1751490Y711390D03*
X1748990D03*
X1746490D03*
X1743990D03*
X1742766Y1418462D03*
Y1415962D03*
X1737766Y1410562D03*
Y1413062D03*
X1740266Y1410562D03*
Y1413062D03*
X1742766D03*
Y1410562D03*
X1740266Y1415962D03*
Y1418462D03*
X1737766Y1426362D03*
Y1428862D03*
X1742766Y1423462D03*
X1740266Y1426362D03*
Y1423462D03*
Y1420962D03*
X1742766D03*
X1741329Y1506405D03*
Y1503405D03*
Y1509405D03*
Y1512405D03*
X1745543Y1518678D03*
X1742758Y1521239D03*
X1745746D03*
X1751120Y1521223D03*
X1751087Y1518704D03*
X1748346Y1521223D03*
X1748313Y1518704D03*
X1739565Y1528105D03*
X1751132Y1526748D03*
Y1524248D03*
Y1529248D03*
X1742810Y1524534D03*
X1745410D03*
X1748358Y1526748D03*
Y1524248D03*
Y1529248D03*
X1746779Y1583378D03*
X1751558Y1579332D03*
X1746079Y1587705D03*
X1750463Y1654465D03*
X1744963Y1656465D03*
X1744463Y1651229D03*
X1747986Y1686215D03*
X1751340Y1686140D03*
X1744620Y1716018D03*
X1750380Y1707468D03*
X1747120Y1710824D03*
X1749480Y1718158D03*
X1765920Y17031D03*
X1765980Y27031D03*
X1765920Y22031D03*
X1758638Y26477D03*
X1755238D03*
X1767266Y48748D03*
X1763010Y51223D03*
X1765527Y53692D03*
X1758635Y50649D03*
X1755235D03*
X1757923Y72637D03*
X1767956Y76843D03*
X1767136Y83653D03*
X1761417Y90017D03*
X1760444Y106173D03*
X1763644D03*
X1755944Y111073D03*
Y108473D03*
X1760944Y116773D03*
X1757944D03*
X1760124Y128246D03*
X1755504Y202263D03*
X1758030D03*
X1762564Y202326D03*
X1765090D03*
X1761573Y266657D03*
X1764573D03*
X1761573Y269657D03*
X1764573D03*
X1758022Y269794D03*
Y266794D03*
X1755022Y269794D03*
Y266794D03*
X1755772Y278859D03*
X1758772D03*
X1761772D03*
X1755772Y281859D03*
X1758772D03*
X1761772D03*
X1752772Y278859D03*
Y281859D03*
X1756800Y364048D03*
Y368048D03*
X1756933Y372452D03*
X1759379Y507927D03*
X1753566Y512968D03*
X1768041Y556537D03*
X1753990Y711390D03*
Y708890D03*
Y706390D03*
Y713890D03*
X1753891Y767305D03*
Y771105D03*
X1767450Y766870D03*
X1759949Y1297324D03*
X1764267Y1460080D03*
X1756329Y1506405D03*
Y1503405D03*
X1764029Y1506405D03*
Y1503405D03*
X1756329Y1509405D03*
Y1512405D03*
X1764029Y1509405D03*
Y1512405D03*
X1765286Y1518471D03*
X1765176Y1515902D03*
X1765286Y1521095D03*
X1765246Y1524001D03*
Y1526601D03*
X1765334Y1529342D03*
X1764679Y1572105D03*
X1765679Y1575405D03*
X1762679D03*
X1766079Y1578705D03*
X1763079D03*
X1753512Y1583478D03*
X1763706Y1616451D03*
X1760206D03*
X1767206D03*
X1765854Y1646456D03*
X1755463Y1654465D03*
X1767888Y1664465D03*
X1762263Y1671765D03*
X1765163Y1670543D03*
X1765463Y1677465D03*
X1761463Y1683465D03*
X1775920Y17031D03*
X1770920D03*
X1775920Y27068D03*
X1770920Y22031D03*
X1775920D03*
X1768956Y37558D03*
X1777720Y37792D03*
X1773830Y49000D03*
X1779377Y50738D03*
X1774294Y60133D03*
X1774291Y57191D03*
X1769240Y50788D03*
X1769200Y54300D03*
X1780300Y54400D03*
X1775546Y73376D03*
X1774294Y63033D03*
X1779744Y72973D03*
Y70073D03*
X1770334Y72737D03*
X1778205Y90982D03*
X1781451Y88238D03*
X1773577Y88339D03*
X1778544Y97973D03*
X1769244Y113773D03*
Y110973D03*
Y108073D03*
X1781368Y162824D03*
X1780929Y179408D03*
X1776930Y179051D03*
X1773581Y194120D03*
X1771055D03*
X1771931Y200920D03*
X1769405D03*
X1777170Y201002D03*
X1774644D03*
X1778796Y261633D03*
X1767573Y266657D03*
X1775633Y261666D03*
X1767573Y269657D03*
X1778796Y266633D03*
Y269133D03*
Y264133D03*
X1775633Y269166D03*
Y266666D03*
Y264166D03*
X1778796Y271633D03*
X1775633Y271666D03*
X1770280Y372452D03*
X1770220Y382952D03*
Y377452D03*
X1782324Y403932D03*
Y410432D03*
Y418932D03*
Y425432D03*
X1779376Y558324D03*
X1782376D03*
X1773963Y557537D03*
X1776986Y749023D03*
X1776550Y763765D03*
X1769650Y1280200D03*
X1771000Y1278060D03*
X1782369Y1447581D03*
X1782385Y1450095D03*
X1782337Y1453191D03*
X1775682Y1466568D03*
X1779029Y1506405D03*
Y1503405D03*
Y1509405D03*
Y1512405D03*
X1780012Y1518631D03*
Y1516031D03*
Y1521231D03*
X1777152Y1518631D03*
Y1516031D03*
Y1521231D03*
X1774552D03*
Y1516031D03*
Y1518631D03*
X1768176Y1515902D03*
X1768286Y1518471D03*
Y1521095D03*
X1770886D03*
Y1518471D03*
X1770776Y1515902D03*
X1780039Y1523860D03*
Y1526360D03*
X1779997Y1528888D03*
X1777179Y1526360D03*
Y1523860D03*
X1774579D03*
Y1526360D03*
X1768246Y1526601D03*
Y1524001D03*
X1768334Y1529342D03*
X1770846Y1524001D03*
Y1526601D03*
X1771079Y1566782D03*
X1770404Y1575330D03*
X1780579Y1582178D03*
X1771094Y1570332D03*
X1778794Y1585332D03*
X1768105Y1595925D03*
X1775794Y1585332D03*
X1768030Y1599249D03*
X1768180Y1606549D03*
X1768030Y1603149D03*
X1780154Y1615026D03*
X1777454D03*
X1780154Y1617726D03*
X1777454D03*
X1773349Y1631938D03*
Y1634438D03*
Y1636938D03*
X1770649Y1631938D03*
Y1634438D03*
X1781423Y1634394D03*
Y1636894D03*
X1778723Y1634294D03*
X1776023D03*
Y1636894D03*
X1778723D03*
X1773929Y1657465D03*
Y1654956D03*
X1768929Y1651956D03*
X1774338Y1676865D03*
X1771038Y1692956D03*
X1787826Y37548D03*
X1783700Y50011D03*
X1794099Y50461D03*
X1788204Y74958D03*
X1785108Y76078D03*
X1787756Y85178D03*
X1788204Y82338D03*
Y78108D03*
X1784144Y113973D03*
Y111173D03*
Y108273D03*
X1797692Y146285D03*
X1784006Y137395D03*
X1788950Y142750D03*
X1787390Y165834D03*
Y156834D03*
Y151834D03*
X1793444Y178083D03*
X1785320Y193072D03*
X1784915Y186053D03*
X1783896Y266633D03*
Y269133D03*
X1794174Y274499D03*
X1790674D03*
X1783896Y271633D03*
X1789771Y367866D03*
X1797929Y385293D03*
X1786260Y379059D03*
X1792507Y403932D03*
X1792335Y418775D03*
X1792450Y410615D03*
X1792220Y425432D03*
X1785376Y558324D03*
X1788376D03*
X1792895Y683536D03*
X1783592Y767565D03*
Y771365D03*
X1792692Y766870D03*
X1794362Y1275546D03*
X1785336Y1447565D03*
Y1450065D03*
X1785634Y1456326D03*
X1782530Y1456229D03*
X1785408Y1453385D03*
X1788029Y1506405D03*
Y1503405D03*
Y1509405D03*
Y1512405D03*
X1794265Y1518262D03*
Y1520862D03*
Y1523462D03*
Y1526062D03*
X1794268Y1528720D03*
X1784601Y1578967D03*
X1787239Y1579406D03*
X1789294Y1583278D03*
X1797118Y1596588D03*
X1797143Y1607014D03*
X1797076Y1603662D03*
X1797043Y1599811D03*
X1791979Y1616550D03*
X1795479D03*
X1782654Y1615026D03*
Y1617726D03*
X1784048Y1636875D03*
Y1634375D03*
X1786615Y1631800D03*
X1786588Y1634472D03*
X1786624Y1637021D03*
X1802565Y156557D03*
X1800554Y177229D03*
X1808622Y170869D03*
X1806470Y186866D03*
X1802570Y186913D03*
X1811274Y198098D03*
X1807596Y264133D03*
Y266633D03*
Y269133D03*
X1797674Y274499D03*
X1801174D03*
X1807596Y271633D03*
X1800160Y362542D03*
X1808962Y698055D03*
Y700555D03*
Y703055D03*
X1798462Y698055D03*
X1801962D03*
X1805462D03*
Y700555D03*
X1801962D03*
X1798462D03*
X1805462Y703055D03*
X1801962D03*
X1798462D03*
X1808962Y705555D03*
Y708055D03*
X1798462Y705555D03*
X1801962D03*
X1805462D03*
X1798462Y708055D03*
X1801962D03*
X1805462D03*
X1809002Y710945D03*
Y713445D03*
Y715945D03*
X1805502Y710945D03*
Y713445D03*
Y715945D03*
X1802050Y710940D03*
X1811526Y1281671D03*
X1803029Y1506405D03*
Y1503405D03*
X1812029Y1506405D03*
Y1503405D03*
X1803029Y1509405D03*
Y1512405D03*
X1812029Y1509405D03*
Y1512405D03*
X1797362Y1518304D03*
X1799882Y1520912D03*
Y1518312D03*
X1797362Y1520904D03*
X1804049Y1528031D03*
X1799882Y1523512D03*
X1797362Y1523504D03*
X1799882Y1526112D03*
X1797362Y1526104D03*
X1799994Y1528674D03*
X1797450Y1528768D03*
X1809890Y1524532D03*
X1807290D03*
X1798479Y1575605D03*
X1798879Y1578905D03*
X1801479Y1575605D03*
X1800479Y1572305D03*
X1801879Y1578905D03*
X1798979Y1616550D03*
X1815005Y149325D03*
X1817196Y163797D03*
Y159947D03*
X1818828Y175241D03*
X1817275Y180619D03*
X1813224Y194699D03*
X1816190Y208879D03*
X1817157Y373829D03*
X1828669Y379552D03*
X1816994Y398052D03*
X1816224Y410432D03*
X1822724Y424948D03*
X1815724Y423932D03*
X1825874Y424948D03*
X1822394Y436225D03*
X1827073Y565157D03*
X1824073D03*
X1821073D03*
X1812462Y698055D03*
Y700555D03*
Y703055D03*
Y705555D03*
Y708055D03*
X1812502Y710945D03*
Y713445D03*
Y715945D03*
X1827029Y1506405D03*
Y1503405D03*
Y1509405D03*
Y1512405D03*
X1818475Y1524682D03*
X1815875D03*
X1823649Y1525144D03*
X1831166Y149986D03*
X1827580Y151834D03*
X1829732Y371329D03*
X1828483Y431678D03*
X1833288Y1469639D03*
X1850791Y170287D03*
G54D30*
X180780Y1507509D03*
X178580D03*
X177487Y1521612D03*
X177086Y1518121D03*
X178745Y1513218D03*
X177533Y1535698D03*
Y1537898D03*
X178980Y1540317D03*
X183051Y1544625D03*
X188155Y1516970D03*
X192879D03*
X197604D03*
X189730Y1519698D03*
X194454D03*
X199178D03*
X202328Y1516970D03*
X207052D03*
X211777D03*
X216501D03*
X203903Y1519698D03*
X208627D03*
X213352D03*
X221226Y1516970D03*
X225950D03*
X230674D03*
X218076Y1519698D03*
X222800D03*
X227525D03*
X235399Y1516970D03*
X240123D03*
X244848D03*
X236974Y1519698D03*
X241698D03*
X246422D03*
X232249D03*
X249572Y1516970D03*
X254297D03*
X259021D03*
X251147Y1519698D03*
X255871D03*
X260596D03*
X265421Y1507355D03*
X263321D03*
X266828Y1514073D03*
X266772Y1516336D03*
X267123Y1536640D03*
Y1534540D03*
X267124Y1531618D03*
X267035Y1528698D03*
X266538Y1538658D03*
X305549Y1521612D03*
X305148Y1518121D03*
X305595Y1535698D03*
Y1537898D03*
X316107Y895569D03*
X314256Y905135D03*
Y924269D03*
X316107Y914702D03*
Y933836D03*
Y952970D03*
X314256Y943403D03*
Y962537D03*
X316107Y972104D03*
X314256Y981671D03*
Y1000805D03*
X316107Y991238D03*
X317957Y988049D03*
X317288Y1028056D03*
X313587D03*
X320988D03*
X315437Y1037623D03*
X319138Y1031245D03*
X315437Y1056757D03*
X317288Y1047190D03*
X319138Y1056757D03*
X320988Y1047190D03*
X317288Y1066324D03*
Y1085458D03*
X315437Y1075891D03*
X317288Y1104592D03*
X315437Y1095025D03*
Y1114159D03*
Y1133293D03*
X317288Y1123726D03*
Y1142859D03*
X315437Y1158804D03*
Y1152426D03*
X319138Y1158804D03*
X308893Y1507460D03*
X316217Y1516970D03*
X320941D03*
X317792Y1519698D03*
X306807Y1513218D03*
X316217Y1530608D03*
X320941D03*
X317792Y1533336D03*
X311113Y1544625D03*
X307042Y1540317D03*
X327209Y882813D03*
X332760Y886002D03*
X330910Y889191D03*
Y895569D03*
X332760Y892380D03*
X323508Y882813D03*
X330910Y908325D03*
X332760Y898758D03*
X330910Y901947D03*
X332760Y905135D03*
Y911513D03*
Y917891D03*
X330910Y921080D03*
X332760Y924269D03*
X330910Y914702D03*
Y927458D03*
X332760Y937025D03*
X330910Y940214D03*
Y933836D03*
X332760Y930647D03*
Y943403D03*
X330910Y946592D03*
X332760Y956159D03*
X330910Y952970D03*
X332760Y949781D03*
Y962537D03*
X330910Y965726D03*
Y959348D03*
X332760Y968915D03*
Y975293D03*
X330910Y978482D03*
Y972104D03*
X332760Y994427D03*
X330910Y997616D03*
X332760Y1000805D03*
X330910Y991238D03*
X332760Y988049D03*
X323508Y991238D03*
X330910Y1010372D03*
X332760Y1007183D03*
X330910Y1003994D03*
X323508Y1010372D03*
X324689Y1028056D03*
X332091D03*
Y1034434D03*
X333941Y1037623D03*
X332091Y1040812D03*
X333941Y1044001D03*
Y1031245D03*
X326540Y1044001D03*
X332091Y1059946D03*
X333941Y1050379D03*
X332091Y1053568D03*
X333941Y1056757D03*
X332091Y1047190D03*
X324689Y1053568D03*
X332091Y1072702D03*
X333941Y1063135D03*
Y1069513D03*
X332091Y1066324D03*
X333941Y1075891D03*
X332091Y1079080D03*
X333941Y1082269D03*
Y1088647D03*
X332091Y1085458D03*
X333941Y1101403D03*
X332091Y1091836D03*
X333941Y1095025D03*
X332091Y1098214D03*
Y1104592D03*
Y1110970D03*
X333941Y1114159D03*
X332091Y1117348D03*
X333941Y1107781D03*
Y1120537D03*
X332091Y1130103D03*
X333941Y1133293D03*
Y1126915D03*
X332091Y1123726D03*
Y1136481D03*
X333941Y1139670D03*
X332091Y1149237D03*
X333941Y1146048D03*
X332091Y1142859D03*
X333941Y1152426D03*
X332091Y1155615D03*
Y1161993D03*
X333941Y1165182D03*
X326539D03*
X324689Y1161993D03*
X325666Y1516970D03*
X330390D03*
X335114D03*
X322516Y1519698D03*
X327240D03*
X331965D03*
X325666Y1530608D03*
X330390D03*
X335114D03*
X322516Y1533336D03*
X327240D03*
X331965D03*
X343862Y886002D03*
X349414Y889191D03*
X345713D03*
Y895569D03*
X349414D03*
X343862Y892380D03*
X338311Y889191D03*
X336461Y892380D03*
X338311Y895569D03*
X342012D03*
X345713Y908325D03*
X343862Y898758D03*
X349414Y901947D03*
X345713D03*
X343862Y905135D03*
X349414Y908325D03*
X343862Y911513D03*
X336461D03*
X338311Y901947D03*
X336461Y905135D03*
X338311Y908325D03*
X336461Y898758D03*
X340162Y905135D03*
X343862Y917891D03*
X349414Y921080D03*
X345713D03*
X343862Y924269D03*
X345713Y914702D03*
X349414D03*
X338311Y921080D03*
X336461Y924269D03*
X338311Y914702D03*
X336461Y917891D03*
X340162Y924269D03*
X342012Y914702D03*
X349414Y927458D03*
X345713D03*
X343862Y937025D03*
X349414Y940214D03*
X345713D03*
Y933836D03*
X349414D03*
X343862Y930647D03*
X338311Y927458D03*
X336461Y930647D03*
X338311Y940214D03*
Y933836D03*
X336461Y937025D03*
X342012Y933836D03*
X343862Y943403D03*
X349414Y946592D03*
X345713D03*
X343862Y956159D03*
X345713Y952970D03*
X349414D03*
X343862Y949781D03*
X336461Y943403D03*
X338311Y946592D03*
X336461Y949781D03*
X338311Y952970D03*
X336461Y956159D03*
X342012Y952970D03*
X340162Y943403D03*
X343862Y962537D03*
X349414Y965726D03*
X345713D03*
X349414Y959348D03*
X345713D03*
X343862Y968915D03*
X338311Y965726D03*
X336461Y968915D03*
X338311Y959348D03*
X336461Y962537D03*
X340162D03*
X349414Y984860D03*
X343862Y975293D03*
X349414Y978482D03*
X345713D03*
Y972104D03*
X349414D03*
X338311Y984860D03*
Y978482D03*
X336461Y981671D03*
X338311Y972104D03*
X336461Y975293D03*
X342012Y972104D03*
X340162Y981671D03*
X343862Y994427D03*
X345713Y997616D03*
X349414D03*
X343862Y1000805D03*
X345713Y991238D03*
X336461Y988049D03*
X338311Y997616D03*
X336461Y1000805D03*
Y994427D03*
X340162Y1000805D03*
X342012Y991238D03*
X338311D03*
X349414D03*
X343862Y988049D03*
X345713Y1010372D03*
X343862Y1007183D03*
X345713Y1003994D03*
X349414D03*
X338311D03*
X336461Y1007183D03*
X338311Y1010372D03*
X349414D03*
X343193Y1028056D03*
X350595D03*
X339492D03*
X346894D03*
X350595Y1034434D03*
X346894D03*
X345043Y1037623D03*
X350595Y1040812D03*
X346894D03*
X345043Y1044001D03*
X337642Y1031245D03*
X339492Y1034434D03*
X337642Y1037623D03*
X339492Y1040812D03*
X341343Y1037623D03*
X337642Y1044001D03*
X345043Y1031245D03*
X346894Y1059946D03*
X350595Y1047190D03*
X345043Y1050379D03*
X346894Y1053568D03*
X337642Y1050379D03*
X339492Y1047190D03*
X341343Y1056757D03*
X343193Y1047190D03*
X339492Y1053568D03*
X345043Y1056757D03*
X346894Y1047190D03*
X350595Y1053568D03*
X346894Y1072702D03*
X345043Y1063135D03*
X350595Y1066324D03*
X345043Y1069513D03*
X350595Y1072702D03*
X346894Y1066324D03*
X337642Y1063135D03*
X339492Y1066324D03*
X337642Y1069513D03*
X339492Y1072702D03*
X343193Y1066324D03*
X345043Y1075891D03*
X350595Y1079080D03*
X346894D03*
X345043Y1082269D03*
X350595Y1085458D03*
X345043Y1088647D03*
X346894Y1085458D03*
X337642Y1075891D03*
X339492Y1079080D03*
X337642Y1082269D03*
X339492Y1085458D03*
X337642Y1088647D03*
X343193Y1085458D03*
X341343Y1075891D03*
X345043Y1101403D03*
X350595Y1104592D03*
X346894Y1091836D03*
X345043Y1095025D03*
X350595Y1098214D03*
X346894D03*
Y1104592D03*
X350595Y1091836D03*
X339492Y1104592D03*
X337642Y1095025D03*
X339492Y1098214D03*
X337642Y1101403D03*
X339492Y1091836D03*
X341343Y1095025D03*
X343193Y1104592D03*
X346894Y1110970D03*
X345043Y1114159D03*
X350595Y1117348D03*
X346894D03*
X345043Y1107781D03*
X350595Y1110970D03*
X337642Y1114159D03*
X339492Y1117348D03*
X337642Y1107781D03*
X339492Y1110970D03*
X341343Y1114159D03*
X345043Y1120537D03*
X350595Y1123726D03*
X346894Y1130103D03*
X345043Y1133293D03*
Y1126915D03*
X346894Y1123726D03*
X350595Y1130103D03*
X337642Y1120537D03*
X339492Y1123726D03*
X337642Y1133293D03*
Y1126915D03*
X339492Y1130103D03*
X343193Y1123726D03*
X341343Y1133293D03*
X350595Y1136481D03*
X346894D03*
X345043Y1139670D03*
X350595Y1142859D03*
X346894Y1149237D03*
X345043Y1146048D03*
X346894Y1142859D03*
X350595Y1149237D03*
X339492Y1136481D03*
X337642Y1139670D03*
X339492Y1142859D03*
X337642Y1146048D03*
X339492Y1149237D03*
X343193Y1142859D03*
X345043Y1152426D03*
X350595Y1155615D03*
X337642Y1152426D03*
X339492Y1161993D03*
X341343Y1165182D03*
X350595Y1161993D03*
X341343Y1152426D03*
X345043Y1158804D03*
X339839Y1516970D03*
X344563D03*
X349288D03*
X336689Y1519698D03*
X341414D03*
X346138D03*
X350862D03*
X339839Y1530608D03*
X344563D03*
X349288D03*
X336689Y1533336D03*
X341414D03*
X346138D03*
X350862D03*
X364217Y876435D03*
X358665Y879624D03*
X351264Y892380D03*
Y911513D03*
Y905135D03*
Y898758D03*
Y924269D03*
Y917891D03*
Y930647D03*
Y937025D03*
Y943403D03*
Y949781D03*
Y956159D03*
Y968915D03*
Y962537D03*
Y981671D03*
Y975293D03*
Y988049D03*
Y1000805D03*
Y994427D03*
X364217Y991238D03*
X358666Y988049D03*
X351264Y1007183D03*
X364217Y1010372D03*
X365398Y1028056D03*
X357996D03*
X352445Y1031245D03*
Y1037623D03*
X363547Y1044001D03*
X359847Y1031245D03*
X352445Y1044001D03*
Y1050379D03*
X359847Y1056757D03*
X357996Y1047190D03*
X365398Y1053568D03*
X352445Y1063135D03*
Y1069513D03*
Y1075891D03*
Y1082269D03*
Y1088647D03*
Y1095025D03*
Y1101403D03*
Y1114159D03*
Y1107781D03*
Y1120537D03*
Y1133293D03*
Y1126915D03*
Y1139670D03*
Y1146048D03*
Y1152426D03*
X359847Y1165182D03*
X357996Y1161993D03*
X352445Y1165182D03*
X365398Y1161993D03*
X363461Y1516970D03*
X354012D03*
X358736D03*
X365036Y1519698D03*
X355587D03*
X360311D03*
X363461Y1530608D03*
X354012D03*
X358736D03*
X365036Y1533336D03*
X355587D03*
X360311D03*
X367917Y876435D03*
X371618D03*
X379020D03*
X369768Y873246D03*
X373469D03*
X377169D03*
X371618Y882813D03*
X375319D03*
X379020Y889191D03*
X367917Y895569D03*
X366067Y905135D03*
X379020Y901947D03*
X366067Y924269D03*
X367917Y914702D03*
X379020D03*
X367917Y933836D03*
X379020Y927458D03*
X366067Y943403D03*
X367917Y952970D03*
X379020Y946592D03*
X366067Y962537D03*
X379020Y959348D03*
X366067Y981671D03*
X367917Y972104D03*
X379020D03*
X366067Y1000805D03*
X367917Y991238D03*
X375319D03*
X369768Y988049D03*
X379020Y1010372D03*
X375319D03*
X369099Y1028056D03*
X376500D03*
X372799D03*
X367248Y1037623D03*
X378351Y1044001D03*
X370949Y1031245D03*
X367248Y1056757D03*
X369099Y1047190D03*
X370949Y1056757D03*
X372799Y1047190D03*
X376500Y1053568D03*
X369099Y1066324D03*
X380201D03*
X367248Y1075891D03*
X369099Y1085458D03*
X380201Y1079080D03*
Y1091836D03*
X367248Y1095025D03*
X369099Y1104592D03*
X367248Y1114159D03*
X380201Y1110970D03*
X369099Y1123726D03*
X367248Y1133293D03*
X380201Y1123726D03*
Y1149237D03*
X369099Y1142859D03*
X380201Y1136481D03*
X378351Y1165182D03*
X374650D03*
X367248Y1158804D03*
X370949D03*
X369099Y1161993D03*
X372799D03*
X380201D03*
X367248Y1152426D03*
X368185Y1516970D03*
X372910D03*
X377634D03*
X369760Y1519698D03*
X374484D03*
X379209D03*
X368185Y1530608D03*
X372910D03*
X377634D03*
X369760Y1533336D03*
X374484D03*
X379209D03*
X393823Y876435D03*
X382721D03*
X390122D03*
X380870Y879624D03*
X384571D03*
X380870Y873246D03*
X391973D03*
X395673D03*
Y879624D03*
X391973D03*
Y886002D03*
X393823Y895569D03*
X380870Y886002D03*
X382721Y895569D03*
X390122Y889191D03*
X386421Y895569D03*
X395673Y886002D03*
X393823Y908325D03*
X386421D03*
X382721D03*
X393823Y921080D03*
X382721D03*
X386421D03*
X393823Y940214D03*
X382721D03*
X386421D03*
X380870Y937025D03*
X395673D03*
X388272D03*
X391973D03*
X384571D03*
X393823Y952970D03*
X382721D03*
X386421D03*
X393823Y965726D03*
X382721D03*
X386421D03*
X395673Y962537D03*
Y968915D03*
X384571Y962537D03*
Y968915D03*
X388272Y962537D03*
Y968915D03*
X380870Y981671D03*
X382721Y984860D03*
X388272Y981671D03*
X390122Y984860D03*
X386421Y978482D03*
X393823D03*
X395673Y981671D03*
X382721Y978482D03*
X395673Y975293D03*
X384571D03*
X388272D03*
X395673Y994427D03*
Y988049D03*
Y1000805D03*
X380870Y988049D03*
Y994427D03*
X382721Y997616D03*
Y991238D03*
X380870Y1000805D03*
X388272Y994427D03*
X390122Y997616D03*
X388272Y988049D03*
X390122Y991238D03*
X388272Y1000805D03*
X380870Y1007183D03*
X382721Y1003994D03*
X388272Y1007183D03*
X390122Y1003994D03*
X393823Y1010372D03*
X386421D03*
X391303Y1028056D03*
X383902D03*
X382051Y1031245D03*
Y1037623D03*
Y1044001D03*
X391303Y1034434D03*
X389453Y1037623D03*
X391303Y1040812D03*
X389453Y1044001D03*
Y1031245D03*
X383902Y1040812D03*
Y1034434D03*
X395004Y1059946D03*
X383902D03*
X387603D03*
X389453Y1056757D03*
X382051Y1050379D03*
X391303Y1047190D03*
X383902D03*
X391303Y1053568D03*
X389453Y1050379D03*
X383902Y1053568D03*
X385752Y1056757D03*
X382051D03*
X395004Y1072702D03*
X383902D03*
X387603D03*
X395004Y1085458D03*
X383902D03*
X387603D03*
X395004Y1098214D03*
X383902D03*
X387603D03*
X382051Y1101403D03*
X393154D03*
X389453D03*
X385752D03*
X395004Y1117348D03*
X387603D03*
X383902D03*
X395004Y1130103D03*
X387603D03*
X383902D03*
X395004Y1142859D03*
X387603D03*
X383902D03*
X391303Y1149237D03*
X382051Y1152426D03*
X383902Y1161993D03*
X391303D03*
X395004D03*
X393154Y1152426D03*
X393483Y1507355D03*
X391383D03*
X382359Y1516970D03*
X387083D03*
X383933Y1519698D03*
X388658D03*
X394890Y1514073D03*
X394834Y1516336D03*
X382359Y1530608D03*
X387083D03*
X383933Y1533336D03*
X388658D03*
X395185Y1536640D03*
Y1534540D03*
X395186Y1531618D03*
X395097Y1528698D03*
X394600Y1538658D03*
X404925Y876435D03*
X401225D03*
X403075Y879624D03*
X406776D03*
X403075Y873246D03*
X397524Y895569D03*
X403075Y886002D03*
X401225Y889191D03*
X408626Y895569D03*
X404925D03*
X406776Y886002D03*
X410477D03*
X399374D03*
X397524Y908325D03*
X408626D03*
X404925Y908324D03*
X397524Y921080D03*
X408626D03*
X404925D03*
X397524Y940214D03*
X410477Y930647D03*
X406776D03*
X408626Y940214D03*
X404925D03*
X403075Y937025D03*
X404925Y933836D03*
X410477Y937025D03*
X408626Y933836D03*
X399374Y937025D03*
X406776D03*
X397524Y952970D03*
X408626D03*
X404925D03*
X397524Y965726D03*
X408626D03*
X404925D03*
X406776Y962537D03*
Y968915D03*
X399374Y962537D03*
Y968915D03*
X410477Y962537D03*
Y968915D03*
X397524Y978482D03*
Y984860D03*
X404925Y978482D03*
X408626D03*
X410477Y981671D03*
X403075D03*
X404925Y984860D03*
X406776Y975293D03*
X399374D03*
X410477D03*
X397524Y991238D03*
X410477Y988049D03*
X403075D03*
X404925Y991238D03*
X397524Y997616D03*
X403075Y994427D03*
Y1000805D03*
X401225Y1010372D03*
X397524Y1003994D03*
X406763Y1007175D03*
X403075Y1007183D03*
X406094Y1028064D03*
X402406Y1028056D03*
X406104Y1040820D03*
X404256Y1044001D03*
X398705Y1040812D03*
X406094Y1034442D03*
X404256Y1037623D03*
Y1031245D03*
X402406Y1034434D03*
X396855Y1044001D03*
Y1031245D03*
Y1037623D03*
X398705Y1047190D03*
X406107D03*
X404256Y1050379D03*
X398705Y1059946D03*
Y1053568D03*
X396855Y1050379D03*
Y1056757D03*
X409807Y1059946D03*
X406107D03*
Y1053568D03*
X404256Y1056757D03*
X398705Y1072702D03*
X406107D03*
X409807D03*
X398705Y1085458D03*
X406107D03*
X409807D03*
X398705Y1098214D03*
X406107D03*
X409807D03*
Y1104592D03*
X407957Y1101403D03*
X404256D03*
X396855D03*
X406107Y1104592D03*
X400555Y1101403D03*
X398705Y1117348D03*
X407957Y1107781D03*
X406107Y1117348D03*
X409807D03*
X398705Y1130103D03*
X406107D03*
X409807D03*
X398705Y1142859D03*
X406107D03*
X409807D03*
X402406Y1149237D03*
X404256Y1152426D03*
X406107Y1161993D03*
X402406D03*
X416028Y876435D03*
X412327D03*
X423429D03*
X414177Y873246D03*
X412327Y889191D03*
X425280Y886002D03*
X423429Y889191D03*
X419729Y895569D03*
X416028D03*
X414177Y886002D03*
X419729Y908325D03*
X416028D03*
Y921080D03*
X419729D03*
X417878Y930647D03*
X421579D03*
X416028Y940214D03*
X419729D03*
X416028Y952970D03*
X419729D03*
Y965726D03*
X416028D03*
X417878Y962537D03*
Y968915D03*
X421579Y962537D03*
Y968915D03*
X412327Y984860D03*
X416028Y978482D03*
X419729D03*
X425280Y981671D03*
X417878D03*
X419729Y984860D03*
X417878Y975293D03*
X421579D03*
X417878Y988049D03*
X425280D03*
X412315Y997608D03*
X412327Y991238D03*
X419716Y997608D03*
X419729Y991238D03*
X413496Y1040820D03*
X420897D03*
X413508Y1047190D03*
X420910D03*
X419059Y1050379D03*
X411658D03*
X413508Y1053568D03*
X411658Y1056757D03*
X420910Y1053568D03*
X419059Y1056757D03*
X417209Y1059946D03*
X420910D03*
X417209Y1072702D03*
X420910D03*
X417209Y1085458D03*
X420910D03*
Y1098214D03*
X417209D03*
X411658Y1101403D03*
Y1107781D03*
X422760D03*
X419059D03*
X420910Y1117348D03*
X417209D03*
X420910Y1130103D03*
X417209D03*
Y1142859D03*
X420910D03*
X413508Y1149237D03*
X424610D03*
Y1161993D03*
X415358Y1152426D03*
X413508Y1161993D03*
X417209D03*
X427130Y876435D03*
X428981Y892380D03*
X432681D03*
X428981Y911513D03*
X432681D03*
X428981Y898758D03*
X432681D03*
X428981Y924269D03*
X432681D03*
X427130Y933836D03*
X430831D03*
X428981Y943403D03*
Y956159D03*
X432681Y943403D03*
Y956159D03*
X428981Y968915D03*
X432681D03*
X427130Y959348D03*
Y965726D03*
X430831Y959348D03*
Y965726D03*
X427130Y984860D03*
X432681Y981671D03*
X434532Y984860D03*
X427130Y978482D03*
Y972104D03*
X430831Y978482D03*
Y972104D03*
X432681Y988049D03*
X434532Y991238D03*
X427118Y997608D03*
X427130Y991238D03*
X434519Y997608D03*
X428299Y1040820D03*
X428311Y1047190D03*
X435713D03*
X433862Y1050379D03*
X426461D03*
Y1056757D03*
X428311Y1053568D03*
X433862Y1056757D03*
X435713Y1053568D03*
X430162Y1069513D03*
X433862D03*
X430162Y1082269D03*
X433862D03*
X430162Y1095025D03*
X428311Y1104592D03*
X433862Y1095025D03*
X432012Y1104592D03*
X430162Y1114159D03*
X433862D03*
X430162Y1126915D03*
X433862D03*
X430162Y1139670D03*
Y1146048D03*
X433862Y1139670D03*
Y1146048D03*
Y1158804D03*
X432012Y1161993D03*
X428311D03*
X426461Y1152426D03*
X430162D03*
X433862D03*
X432012Y1155615D03*
X426461Y1158804D03*
X428311Y1155615D03*
X454861Y873246D03*
X453011Y876435D03*
X449310D03*
X451160Y879624D03*
X454861D03*
X451160Y873246D03*
Y886002D03*
X454861D03*
X451160Y892380D03*
X447460D03*
Y886002D03*
X449310Y882813D03*
X451160Y911513D03*
X447460D03*
X451160Y898758D03*
X447460D03*
X449310Y921080D03*
Y914702D03*
X453011Y921080D03*
Y914702D03*
X451160Y924269D03*
X447460D03*
X453011Y940214D03*
X449310D03*
Y927458D03*
X453011D03*
X449310Y933836D03*
X453011D03*
Y952970D03*
Y946592D03*
X449310Y952970D03*
Y946592D03*
X451160Y943403D03*
Y956159D03*
X447460Y943403D03*
Y956159D03*
X453011Y959348D03*
Y965726D03*
X449310Y959348D03*
Y965726D03*
X451160Y968915D03*
X447460D03*
X453011Y978482D03*
Y972104D03*
X449310Y978482D03*
Y972104D03*
X451160Y981671D03*
X449310Y984860D03*
X449323Y997608D03*
X451160Y988049D03*
X449310Y991238D03*
X450491Y1047190D03*
X452341Y1056757D03*
X450491Y1053568D03*
X452341Y1050379D03*
X448641Y1069513D03*
X452341D03*
X448641Y1082269D03*
X452341D03*
X448641Y1095025D03*
X452341D03*
X450491Y1104592D03*
X454192D03*
X448641Y1114159D03*
X452341D03*
X448641Y1126915D03*
X452341D03*
X448641Y1139670D03*
X452341D03*
X448641Y1146048D03*
X452341D03*
X450491Y1161993D03*
X452341Y1165182D03*
X454192Y1161993D03*
X452341Y1152426D03*
X448640Y1165182D03*
X448641Y1158804D03*
X452341D03*
X450491Y1155615D03*
X444953Y1507509D03*
X442753D03*
X442918Y1513218D03*
X441660Y1521612D03*
X441259Y1518121D03*
X441706Y1535698D03*
Y1537898D03*
X443153Y1540317D03*
X447224Y1544625D03*
X462263Y879624D03*
X458562D03*
Y873246D03*
X462263D03*
X456712Y876435D03*
X467814D03*
X464113D03*
X465964Y879624D03*
Y873246D03*
X460412Y882813D03*
X464113D03*
X469664Y886002D03*
X456712Y889191D03*
X460412Y895569D03*
X465964Y886002D03*
X467814Y889191D03*
X464113Y895569D03*
X462263Y886002D03*
X458562D03*
X456712Y882813D03*
X458562Y911513D03*
X469664D03*
X462263D03*
X460412Y908325D03*
X464113D03*
X458562Y924269D03*
Y917891D03*
X469664Y924269D03*
Y917891D03*
X462263Y924269D03*
Y917891D03*
X460412Y921080D03*
X464113D03*
X462263Y937025D03*
X458562D03*
X462263Y930647D03*
X458562D03*
X460412Y940214D03*
X469664Y930647D03*
X464113Y940214D03*
X465964Y930647D03*
X469664Y937025D03*
X462263Y956159D03*
Y943403D03*
Y949781D03*
X458562Y956159D03*
Y943403D03*
Y949781D03*
X469664Y956159D03*
Y943403D03*
Y949781D03*
X460412Y952970D03*
X464113D03*
X462263Y962537D03*
Y968915D03*
X458562Y962537D03*
Y968915D03*
X469664Y962537D03*
Y968915D03*
X460412Y965726D03*
X464113D03*
X462263Y975293D03*
X458562D03*
X469664D03*
X460412Y978482D03*
X458562Y981671D03*
X456712Y984860D03*
X464113Y978482D03*
X465964Y981671D03*
X464113Y984860D03*
X458562Y988049D03*
X456724Y997608D03*
X456712Y991238D03*
X464126Y997608D03*
X465964Y988049D03*
X464113Y991238D03*
X457905Y1040820D03*
X465307D03*
X457893Y1047190D03*
X465294D03*
X459743Y1050379D03*
X465294Y1053568D03*
X467145Y1056757D03*
Y1050379D03*
X457893Y1053568D03*
X461593Y1059946D03*
X459743Y1056757D03*
X465294Y1059946D03*
X461593Y1072702D03*
X465294D03*
X461593Y1085458D03*
X465294D03*
X461593Y1098214D03*
X465294D03*
X459743Y1107781D03*
X461593Y1117348D03*
X463444Y1107781D03*
X465294Y1117348D03*
X461593Y1130103D03*
X465294D03*
X461593Y1142859D03*
X457893Y1149237D03*
X465294Y1142859D03*
X468995Y1149237D03*
X467145Y1165182D03*
X468995Y1161993D03*
X465294D03*
X467145Y1152426D03*
X457893Y1161993D03*
X456042Y1152426D03*
X459743Y1165182D03*
X456042Y1158804D03*
X457893Y1155615D03*
X456042Y1165182D03*
X461593Y1161993D03*
Y1155615D03*
X463444Y1152426D03*
Y1158804D03*
X467145D03*
X468995Y1155615D03*
X463444Y1165182D03*
X484467Y873246D03*
X473365D03*
X477066D03*
X484467Y879624D03*
X477066D03*
X473365D03*
X475215Y876435D03*
X478916D03*
X484467Y886002D03*
X480767D03*
X473365D03*
X477066D03*
X475215Y895569D03*
X471515D03*
X478916Y889191D03*
X482617Y895569D03*
X480767Y911513D03*
X484467D03*
X473365D03*
X475215Y908325D03*
X471515D03*
X482617D03*
X480767Y917891D03*
Y924269D03*
X484467Y917891D03*
Y924269D03*
X473365D03*
Y917891D03*
X475215Y921080D03*
X471515D03*
X482617D03*
X480767Y930647D03*
X484467D03*
X473365D03*
X471515Y940214D03*
X475215D03*
X482617D03*
X477066Y937025D03*
X480767D03*
X475215Y933836D03*
X471515D03*
X484467Y937025D03*
X473365D03*
X484467Y956159D03*
Y943403D03*
Y949781D03*
X473365Y956159D03*
Y943403D03*
Y949781D03*
X480767Y956159D03*
Y943403D03*
Y949781D03*
X475215Y952970D03*
X471515D03*
X482617D03*
X484467Y962537D03*
Y968915D03*
X473365Y962537D03*
Y968915D03*
X480767Y962537D03*
Y968915D03*
X475215Y965726D03*
X471515D03*
X482617D03*
X484467Y975293D03*
X473365D03*
X480767D03*
X475215Y978482D03*
X471515D03*
X473365Y981671D03*
X471515Y984860D03*
X478916D03*
X482617Y978482D03*
X480767Y981671D03*
X473365Y988049D03*
X471527Y997608D03*
X471515Y991238D03*
X478916Y997616D03*
Y991238D03*
X480767Y994427D03*
Y988049D03*
Y1000805D03*
X478916Y1003994D03*
Y1010372D03*
X480767Y1007183D03*
X483798Y1028056D03*
X472708Y1040820D03*
X481948Y1044001D03*
Y1037623D03*
X480097Y1040812D03*
X483798Y1034434D03*
X478247Y1031245D03*
X472696Y1047190D03*
X480097D03*
X474546Y1050379D03*
Y1056757D03*
X472696Y1053568D03*
Y1059946D03*
X476397D03*
X483798D03*
X481948Y1056757D03*
X480097Y1053568D03*
X481948Y1050379D03*
X476397Y1072702D03*
X472696D03*
X483798D03*
X472696Y1085458D03*
X476397D03*
X483798D03*
X472696Y1098214D03*
X476397D03*
X483798D03*
X478247Y1101403D03*
X472696Y1104592D03*
X481948Y1101403D03*
X476397Y1104592D03*
X470845Y1101403D03*
X474546D03*
X470845Y1107781D03*
X474546D03*
X476397Y1117348D03*
X472696D03*
X483798D03*
X472696Y1130103D03*
X483798D03*
X476396D03*
X472696Y1142859D03*
X476397D03*
X483798D03*
X480097Y1149237D03*
X483798Y1155615D03*
X480097Y1161993D03*
X476397D03*
X478247Y1152426D03*
X470846Y1165182D03*
X481948D03*
X483798Y1161993D03*
X472696Y1155615D03*
X481948Y1152426D03*
X478247Y1158804D03*
X474546D03*
X478247Y1165182D03*
X480097Y1155615D03*
X474546Y1165182D03*
X470845Y1152426D03*
X472696Y1161993D03*
X499271Y879624D03*
X488168Y873246D03*
Y879624D03*
X486318Y876435D03*
X490019D03*
X497420D03*
X495570Y879624D03*
Y886002D03*
X491869D03*
X488168D03*
X490019Y889191D03*
X493719Y895569D03*
X486318D03*
X499271Y886002D03*
X497420Y895569D03*
Y882813D03*
X493719Y908325D03*
X486318D03*
X497420D03*
X491869Y917891D03*
Y924269D03*
X495570Y917891D03*
Y924269D03*
X493719Y921080D03*
X486318D03*
X497420D03*
X491869Y930647D03*
X495570D03*
X493719Y940214D03*
X486318D03*
X497420D03*
X499271Y937025D03*
X488168D03*
X491869D03*
X495570D03*
Y956159D03*
Y943403D03*
Y949781D03*
X491869Y956159D03*
Y943403D03*
Y949781D03*
X486318Y952970D03*
X493719D03*
X497420D03*
X495570Y962537D03*
Y968915D03*
X491869Y962537D03*
Y968915D03*
X493719Y965726D03*
X486318D03*
X497420D03*
X495570Y975293D03*
X491869D03*
X493719Y978482D03*
X486318D03*
X488168Y981671D03*
X493719Y984860D03*
X486318D03*
X495570Y981671D03*
X497420Y978482D03*
X488168Y988049D03*
Y994427D03*
X486318Y997616D03*
X493719D03*
X486318Y991238D03*
X493719D03*
X488168Y1000805D03*
X495570Y994427D03*
Y988049D03*
Y1000805D03*
X488168Y1007183D03*
X486318Y1003994D03*
Y1010372D03*
X493719Y1003994D03*
Y1010372D03*
X495570Y1007183D03*
X491200Y1028056D03*
X498601D03*
X494901Y1040812D03*
X489349Y1044001D03*
X487499Y1040812D03*
X489349Y1037623D03*
X496751Y1044001D03*
Y1037623D03*
X485649Y1031245D03*
X493050D03*
X491200Y1034434D03*
X498601D03*
X496751Y1050379D03*
X494901Y1047190D03*
X487499D03*
X489349Y1050379D03*
X494901Y1059946D03*
Y1053568D03*
X487499Y1059946D03*
X489349Y1056757D03*
X487499Y1053568D03*
X496751Y1056757D03*
X498601Y1059946D03*
X494901Y1072702D03*
X487499D03*
X498601D03*
X494901Y1085458D03*
X487499D03*
X498601D03*
X494901Y1098214D03*
X487499D03*
X498601D03*
X493050Y1101403D03*
X485649D03*
X489349D03*
X494901Y1117348D03*
X487499D03*
X498601D03*
X487499Y1130103D03*
X494901D03*
X498601D03*
X494901Y1142859D03*
X487499D03*
X491200Y1149237D03*
X498601Y1142859D03*
Y1161993D03*
X487499D03*
X491200D03*
X489349Y1152426D03*
X493050Y1165182D03*
X485649Y1158804D03*
Y1165182D03*
X496751D03*
Y1158804D03*
X489349D03*
X491200Y1155615D03*
X493050Y1152426D03*
X494901Y1161993D03*
Y1155615D03*
X489349Y1165182D03*
X510373Y879624D03*
X514074D03*
X508523Y876435D03*
X506672Y879624D03*
X512223Y876435D03*
X501121D03*
Y889191D03*
X512223Y895569D03*
X501121Y882813D03*
X514074Y905135D03*
X501121Y901947D03*
X512223Y914702D03*
X514074Y924269D03*
X501121Y914702D03*
X512223Y933836D03*
X501121Y927458D03*
X514074Y943403D03*
X512223Y952970D03*
X501121Y946592D03*
X514074Y962537D03*
X501121Y959348D03*
X514074Y981671D03*
X512223Y972104D03*
X501121D03*
Y984860D03*
Y997616D03*
Y991238D03*
X512223D03*
X514074Y1000805D03*
X502971Y994427D03*
X508523Y991238D03*
X501121Y1010372D03*
X512223D03*
X501121Y1003994D03*
X504822Y1010372D03*
X506003Y1028056D03*
X509704D03*
X502302Y1040812D03*
X500452Y1031245D03*
X511554Y1044001D03*
Y1031245D03*
X502302Y1047190D03*
Y1053568D03*
X513405Y1047190D03*
X511554Y1056757D03*
X509704Y1047190D03*
X506003Y1053568D03*
X513405Y1066324D03*
X502302D03*
X513405Y1085458D03*
X502302Y1079080D03*
X513405Y1104592D03*
X502302Y1091836D03*
X500452Y1101403D03*
X502302Y1110970D03*
X513405Y1123726D03*
X502302D03*
X513405Y1142859D03*
X502302Y1136481D03*
Y1149237D03*
X513405Y1161993D03*
X511554Y1158804D03*
X509704Y1161993D03*
X502302D03*
X500452Y1152426D03*
X506003Y1161993D03*
X500452Y1158804D03*
Y1165182D03*
X507853D03*
X504153D03*
X521475Y879624D03*
X519625Y876435D03*
X517775Y879624D03*
X521475Y873246D03*
X517775D03*
X527027Y876435D03*
X528877Y879624D03*
Y892380D03*
X515924Y882813D03*
X527027D03*
X528877Y911513D03*
Y905135D03*
Y898758D03*
Y924269D03*
Y917891D03*
Y930647D03*
Y937025D03*
Y943403D03*
Y949781D03*
Y956159D03*
Y968915D03*
Y962537D03*
Y981671D03*
Y975293D03*
Y988049D03*
Y1000805D03*
X517775Y994427D03*
X523326Y991238D03*
X528877Y994427D03*
Y1007183D03*
X515924Y1010372D03*
X517105Y1028056D03*
X524507D03*
X515255Y1037623D03*
X522656Y1044001D03*
Y1031245D03*
X515255Y1056757D03*
X522656D03*
X524507Y1047190D03*
X517105Y1053568D03*
X515255Y1075891D03*
Y1095025D03*
Y1114159D03*
Y1133293D03*
X528208Y1161993D03*
X515255Y1152426D03*
X524507Y1161993D03*
X520806D03*
X518956Y1158804D03*
X529594Y1507355D03*
X527494D03*
X530727Y876435D03*
X532578Y873246D03*
X536279Y886002D03*
X530727Y889191D03*
X534428D03*
Y895569D03*
X530727D03*
X536279Y892380D03*
X541830Y889191D03*
X543680Y892380D03*
X541830Y895569D03*
X538129D03*
X539979Y886002D03*
X530727Y882813D03*
X541830D03*
X534428Y908325D03*
X536279Y898758D03*
X530727Y901947D03*
X534428D03*
X536279Y905135D03*
X530727Y908325D03*
X536279Y911513D03*
X543680D03*
X541830Y901947D03*
X543680Y905135D03*
X541830Y908325D03*
X543680Y898758D03*
X539979Y905135D03*
X536279Y917891D03*
X530727Y921080D03*
X534428D03*
X536279Y924269D03*
X534428Y914702D03*
X530727D03*
X541830Y921080D03*
X543680Y924269D03*
X541830Y914702D03*
X543680Y917891D03*
X539979Y924269D03*
X538129Y914702D03*
X530727Y927458D03*
X534428D03*
X536279Y937025D03*
X530727Y940214D03*
X534428D03*
Y933836D03*
X530727D03*
X536279Y930647D03*
X541830Y927458D03*
X543680Y930647D03*
X541830Y940214D03*
Y933836D03*
X543680Y937025D03*
X538129Y933836D03*
X536279Y943403D03*
X530727Y946592D03*
X534428D03*
X536279Y956159D03*
X534428Y952970D03*
X530727D03*
X536279Y949781D03*
X543680Y943403D03*
X541830Y946592D03*
X543680Y949781D03*
X541830Y952970D03*
X543680Y956159D03*
X538129Y952970D03*
X539979Y943403D03*
X536279Y962537D03*
X530727Y965726D03*
X534428D03*
X530727Y959348D03*
X534428D03*
X536279Y968915D03*
X541830Y965726D03*
X543680Y968915D03*
X541830Y959348D03*
X543680Y962537D03*
X539979D03*
X530727Y984860D03*
X536279Y975293D03*
X530727Y978482D03*
X534428D03*
Y972104D03*
X530727D03*
X541830Y984860D03*
Y978482D03*
X543680Y981671D03*
X541830Y972104D03*
X543680Y975293D03*
X538129Y972104D03*
X539979Y981671D03*
X536279Y994427D03*
X534428Y997616D03*
X530727D03*
X536279Y1000805D03*
Y988049D03*
X530727Y991238D03*
X543680Y988049D03*
X541830Y997616D03*
X543680Y1000805D03*
X541830Y991238D03*
X539979Y1000805D03*
X538129Y991238D03*
X543680Y994427D03*
X534428Y991238D03*
Y1010372D03*
X536279Y1007183D03*
X534428Y1003994D03*
X530727D03*
X541830D03*
X543680Y1007183D03*
X538129Y1010372D03*
X530727D03*
X541830D03*
X531908Y1028056D03*
X543011D03*
X535609D03*
X530058Y1031245D03*
X531908Y1034434D03*
X535609D03*
X537460Y1037623D03*
X530058D03*
X531908Y1040812D03*
X535609D03*
X530058Y1044001D03*
X543011Y1034434D03*
Y1040812D03*
X541160Y1037623D03*
X537460Y1044001D03*
Y1031245D03*
X530058Y1050379D03*
X535609Y1059946D03*
X531908Y1047190D03*
X537460Y1050379D03*
X535609Y1053568D03*
X543011Y1047190D03*
X541160Y1056757D03*
X539310Y1047190D03*
X543011Y1053568D03*
X537460Y1056757D03*
X535609Y1047190D03*
X531908Y1053568D03*
X535609Y1072702D03*
X530058Y1063135D03*
X537460D03*
X531908Y1066324D03*
X530058Y1069513D03*
X537460D03*
X531908Y1072702D03*
X535609Y1066324D03*
X543011D03*
Y1072702D03*
X539310Y1066324D03*
X530058Y1075891D03*
X537460D03*
X531908Y1079080D03*
X535609D03*
X530058Y1082269D03*
X537460D03*
X531908Y1085458D03*
X537460Y1088647D03*
X530058D03*
X535609Y1085458D03*
X543011Y1079080D03*
Y1085458D03*
X539310D03*
X541160Y1075891D03*
X537460Y1101403D03*
X531908Y1104592D03*
X535609Y1091836D03*
X530058Y1095025D03*
X537460D03*
X531908Y1098214D03*
X535609D03*
X530058Y1101403D03*
X535609Y1104592D03*
X531908Y1091836D03*
X543011Y1104592D03*
Y1098214D03*
Y1091836D03*
X541160Y1095025D03*
X539310Y1104592D03*
X535609Y1110970D03*
X530058Y1114159D03*
X537460D03*
X531908Y1117348D03*
X535609D03*
X537460Y1107781D03*
X530058D03*
X531908Y1110970D03*
X543011Y1117348D03*
Y1110970D03*
X541160Y1114159D03*
X530058Y1120537D03*
X537460D03*
X531908Y1123726D03*
X535609Y1130103D03*
X530058Y1133293D03*
X537460D03*
Y1126915D03*
X530058D03*
X535609Y1123726D03*
X531908Y1130103D03*
X543011Y1123726D03*
Y1130103D03*
X539310Y1123726D03*
X541160Y1133293D03*
X531908Y1136481D03*
X535609D03*
X530058Y1139670D03*
X537460D03*
X531908Y1142859D03*
X535609Y1149237D03*
X537460Y1146048D03*
X530058D03*
X535609Y1142859D03*
X531908Y1149237D03*
X543011Y1136481D03*
Y1142859D03*
Y1149237D03*
X539310Y1142859D03*
X530058Y1152426D03*
X537460D03*
X531908Y1155615D03*
X541160Y1152426D03*
X531908Y1161993D03*
X535609D03*
X539310D03*
X537460Y1158804D03*
X541160D03*
X531001Y1514073D03*
X530945Y1516336D03*
X532310Y1536640D03*
X531926Y1534540D03*
X531537Y1531618D03*
X531208Y1528698D03*
X530711Y1538658D03*
X554783Y879624D03*
X547381Y886002D03*
X549231Y889191D03*
Y895569D03*
X547381Y892380D03*
X556633Y882813D03*
X552932D03*
X549231Y908325D03*
X547381Y898758D03*
X549231Y901947D03*
X547381Y905135D03*
Y911513D03*
Y917891D03*
X549231Y921080D03*
X547381Y924269D03*
X549231Y914702D03*
Y927458D03*
X547381Y937025D03*
X549231Y940214D03*
Y933836D03*
X547381Y930647D03*
Y943403D03*
X549231Y946592D03*
X547381Y956159D03*
X549231Y952970D03*
X547381Y949781D03*
Y962537D03*
X549231Y965726D03*
Y959348D03*
X547381Y968915D03*
Y975293D03*
X549231Y978482D03*
Y972104D03*
X547381Y994427D03*
X549231Y997616D03*
X547381Y1000805D03*
Y988049D03*
X554782Y994427D03*
X549231Y991238D03*
Y1010372D03*
X547381Y1007183D03*
X549231Y1003994D03*
X556633Y1010372D03*
X557814Y1028056D03*
X550412D03*
X544861Y1031245D03*
X550412Y1034434D03*
X548562Y1037623D03*
X544861D03*
X550412Y1040812D03*
X544861Y1044001D03*
X548562D03*
Y1031245D03*
X544861Y1050379D03*
X550412Y1059946D03*
X548562Y1050379D03*
X550412Y1053568D03*
X557814D03*
X548562Y1056757D03*
X550412Y1047190D03*
Y1072702D03*
X544861Y1063135D03*
X548562D03*
X544861Y1069513D03*
X548562D03*
X550412Y1066324D03*
X544861Y1075891D03*
X548562D03*
X550412Y1079080D03*
X544861Y1082269D03*
X548562D03*
Y1088647D03*
X544861D03*
X550412Y1085458D03*
X548562Y1101403D03*
X550412Y1091836D03*
X544861Y1095025D03*
X548562D03*
X550412Y1098214D03*
X544861Y1101403D03*
X550412Y1104592D03*
Y1110970D03*
X544861Y1114159D03*
X548562D03*
X550412Y1117348D03*
X548562Y1107781D03*
X544861D03*
Y1120537D03*
X548562D03*
X550412Y1130103D03*
X544861Y1133293D03*
X548562D03*
Y1126915D03*
X544861D03*
X550412Y1123726D03*
Y1136481D03*
X544861Y1139670D03*
X548562D03*
X550412Y1149237D03*
X548562Y1146048D03*
X544861D03*
X550412Y1142859D03*
X546712Y1161993D03*
X544861Y1152426D03*
X548562D03*
X550412Y1155615D03*
X557814Y1161993D03*
X544861Y1158804D03*
X562184Y873246D03*
X565885Y879624D03*
X564034Y876435D03*
X573286Y879624D03*
X571436Y876435D03*
X569586Y879624D03*
X564034Y895569D03*
X565885Y886002D03*
X567735Y882813D03*
X565885Y905135D03*
Y924269D03*
X564034Y914702D03*
Y933836D03*
Y952970D03*
X565885Y943403D03*
Y962537D03*
Y981671D03*
X564034Y972104D03*
X565885Y1000805D03*
X564034Y991238D03*
X560334D03*
X564034Y1010372D03*
X567735D03*
X568916Y1028056D03*
X561515D03*
X567066Y1037623D03*
X563365Y1044001D03*
Y1031245D03*
X567066Y1056757D03*
X565215Y1047190D03*
X563365Y1056757D03*
X561515Y1047190D03*
X565215Y1066324D03*
Y1085458D03*
X567066Y1075891D03*
X565215Y1104592D03*
X567066Y1095025D03*
Y1114159D03*
Y1133293D03*
X565215Y1123726D03*
Y1142859D03*
X567066Y1158804D03*
X563365D03*
X567066Y1152426D03*
X572617Y1161993D03*
X570767Y1165182D03*
X567066D03*
X568916Y1161993D03*
X570815Y1507509D03*
X573066Y1507460D03*
X570980Y1513218D03*
X569722Y1521612D03*
X569321Y1518121D03*
X569768Y1535698D03*
Y1537898D03*
X571215Y1540317D03*
X575286Y1544625D03*
X657656Y1507355D03*
X655556D03*
X659063Y1514073D03*
X659007Y1516336D03*
X659358Y1536640D03*
Y1534540D03*
X659359Y1531618D03*
X659270Y1528698D03*
X662353Y1534413D03*
X660877Y1530158D03*
X658773Y1538658D03*
X1184959Y1551121D03*
X1185360Y1554612D03*
X1185406Y1568698D03*
Y1570898D03*
X1196028Y1549970D03*
X1197603Y1552698D03*
X1188653Y1540509D03*
X1186453D03*
X1186618Y1546218D03*
X1186853Y1573317D03*
X1190924Y1577625D03*
X1200752Y1549970D03*
X1205477D03*
X1210201D03*
X1214925D03*
X1202327Y1552698D03*
X1207051D03*
X1211776D03*
X1219650Y1549970D03*
X1224374D03*
X1229099D03*
X1216500Y1552698D03*
X1221225D03*
X1225949D03*
X1243272Y1549970D03*
X1233823D03*
X1238547D03*
X1244847Y1552698D03*
X1230673D03*
X1235398D03*
X1240122D03*
X1247996Y1549970D03*
X1252721D03*
X1257445D03*
X1249571Y1552698D03*
X1254295D03*
X1259020D03*
X1262170Y1549970D03*
X1266894D03*
X1263744Y1552698D03*
X1268469D03*
X1273294Y1540355D03*
X1271194D03*
X1274701Y1547073D03*
X1274645Y1549336D03*
X1274996Y1567540D03*
X1274997Y1564618D03*
X1274908Y1561698D03*
X1274411Y1571658D03*
X1274996Y1569640D03*
X1288549Y876434D03*
X1288548Y1010371D03*
X1289729Y1028055D03*
X1297800Y879623D03*
X1299650Y876434D03*
X1290399Y879623D03*
X1303351Y882812D03*
X1292249Y895568D03*
X1299650Y882812D03*
X1290398Y905134D03*
X1292249Y914701D03*
X1290398Y924268D03*
X1292249Y933835D03*
Y952969D03*
X1290398Y943402D03*
Y962536D03*
X1292249Y972103D03*
X1290398Y981670D03*
X1292249Y991237D03*
X1290398Y1000804D03*
X1299650Y991237D03*
X1294099Y988048D03*
X1299650Y1010371D03*
X1293430Y1028055D03*
X1300831D03*
X1297130D03*
X1291579Y1037622D03*
X1302682Y1044000D03*
X1295280Y1031244D03*
X1291579Y1056756D03*
X1293430Y1047189D03*
X1295280Y1056756D03*
X1297130Y1047189D03*
X1300831Y1053567D03*
X1293430Y1066323D03*
Y1085457D03*
X1291579Y1075890D03*
X1293430Y1104591D03*
X1291579Y1095024D03*
Y1114158D03*
Y1133292D03*
X1293430Y1123725D03*
Y1142858D03*
X1291579Y1158803D03*
X1295280D03*
X1291579Y1152425D03*
X1300831Y1161992D03*
X1302682Y1165181D03*
X1318154Y876434D03*
X1305201Y879623D03*
X1312603D03*
X1316304D03*
X1307052Y876434D03*
X1308902Y886001D03*
X1314453Y889190D03*
X1307052D03*
X1312603Y892379D03*
X1307052Y895568D03*
X1314453D03*
X1308902Y892379D03*
X1318154Y895568D03*
X1307052Y908324D03*
X1312603Y911512D03*
X1308902Y898757D03*
X1314453Y901946D03*
X1307052D03*
X1312603Y905134D03*
X1308902D03*
X1314453Y908324D03*
X1308902Y911512D03*
X1312603Y898757D03*
X1316304Y905134D03*
X1308902Y917890D03*
X1314453Y921079D03*
X1307052D03*
X1312603Y924268D03*
X1308902D03*
X1307052Y914701D03*
X1314453D03*
X1312603Y917890D03*
X1316304Y924268D03*
X1318154Y914701D03*
X1314453Y927457D03*
X1307052D03*
X1312603Y930646D03*
X1308902Y937024D03*
X1314453Y940213D03*
X1307052D03*
Y933835D03*
X1314453D03*
X1308902Y930646D03*
X1312603Y937024D03*
X1318154Y933835D03*
X1312603Y943402D03*
X1308902D03*
X1314453Y946591D03*
X1307052D03*
X1312603Y949780D03*
X1308902Y956158D03*
X1307052Y952969D03*
X1314453D03*
X1308902Y949780D03*
X1312603Y956158D03*
X1318154Y952969D03*
X1316304Y943402D03*
X1308902Y962536D03*
X1314453Y965725D03*
X1307052D03*
X1312603Y968914D03*
X1314453Y959347D03*
X1307052D03*
X1312603Y962536D03*
X1308902Y968914D03*
X1316304Y962536D03*
X1314453Y984859D03*
X1308902Y975292D03*
X1314453Y978481D03*
X1307052D03*
X1312603Y981670D03*
X1307052Y972103D03*
X1314453D03*
X1312603Y975292D03*
X1316304Y981670D03*
X1318154Y972103D03*
X1312603Y988048D03*
X1308902Y994426D03*
X1307052Y997615D03*
X1314453D03*
X1312603Y1000804D03*
X1308902D03*
X1307052Y991237D03*
X1312603Y994426D03*
X1316304Y1000804D03*
X1318154Y991237D03*
X1314453D03*
X1308902Y988048D03*
X1307052Y1010371D03*
X1308902Y1007182D03*
X1307052Y1003993D03*
X1314453D03*
X1312603Y1007182D03*
X1314453Y1010371D03*
X1319335Y1028055D03*
X1315634D03*
X1308233D03*
X1313784Y1031244D03*
X1315634Y1034433D03*
X1308233D03*
X1310083Y1037622D03*
X1313784D03*
X1315634Y1040811D03*
X1308233D03*
X1310083Y1044000D03*
X1317485Y1037622D03*
X1313784Y1044000D03*
X1310083Y1031244D03*
X1313784Y1050378D03*
X1308233Y1059945D03*
X1315634Y1047189D03*
X1310083Y1050378D03*
X1308233Y1053567D03*
X1317485Y1056756D03*
X1319335Y1047189D03*
X1310083Y1056756D03*
X1308233Y1047189D03*
X1315634Y1053567D03*
X1308233Y1072701D03*
X1313784Y1063134D03*
X1310083D03*
X1315634Y1066323D03*
X1313784Y1069512D03*
X1310083D03*
X1315634Y1072701D03*
X1308233Y1066323D03*
X1319335D03*
X1313784Y1075890D03*
X1310083D03*
X1315634Y1079079D03*
X1308233D03*
X1313784Y1082268D03*
X1310083D03*
X1315634Y1085457D03*
X1310083Y1088646D03*
X1313784D03*
X1308233Y1085457D03*
X1319335D03*
X1317485Y1075890D03*
X1310083Y1101402D03*
X1315634Y1104591D03*
X1308233Y1091835D03*
X1313784Y1095024D03*
X1310083D03*
X1315634Y1098213D03*
X1308233D03*
X1313784Y1101402D03*
X1308233Y1104591D03*
X1315634Y1091835D03*
X1319335Y1104591D03*
X1317485Y1095024D03*
X1308233Y1110969D03*
X1313784Y1114158D03*
X1310083D03*
X1315634Y1117347D03*
X1308233D03*
X1310083Y1107780D03*
X1313784D03*
X1315634Y1110969D03*
X1317485Y1114158D03*
X1313784Y1120536D03*
X1310083D03*
X1315634Y1123725D03*
X1308233Y1130102D03*
X1313784Y1133292D03*
X1310083D03*
Y1126914D03*
X1313784D03*
X1308233Y1123725D03*
X1315634Y1130102D03*
X1317485Y1133292D03*
X1319335Y1123725D03*
X1315634Y1136480D03*
X1308233D03*
X1313784Y1139669D03*
X1310083D03*
X1315634Y1142858D03*
X1308233Y1149236D03*
X1310083Y1146047D03*
X1313784D03*
X1308233Y1142858D03*
X1315634Y1149236D03*
X1319335Y1142858D03*
X1313784Y1152425D03*
X1310083D03*
X1308233Y1155614D03*
X1317485Y1152425D03*
X1308233Y1161992D03*
X1310083Y1165181D03*
X1317485D03*
X1315634Y1161992D03*
X1316766Y1540460D03*
X1314515Y1540509D03*
X1314680Y1546218D03*
X1313021Y1551121D03*
X1313422Y1554612D03*
X1313468Y1568698D03*
Y1570898D03*
X1318986Y1577625D03*
X1314915Y1573317D03*
X1323705Y879623D03*
X1327406D03*
X1321855Y876434D03*
X1332957D03*
X1329256D03*
X1334807Y879623D03*
X1320004Y886001D03*
X1325556Y889190D03*
X1321855D03*
X1327406Y892379D03*
X1321855Y895568D03*
X1325556D03*
X1320004Y892379D03*
X1321855Y908324D03*
X1327406Y911512D03*
X1320004Y898757D03*
X1325556Y901946D03*
X1321855D03*
X1327406Y905134D03*
X1320004D03*
X1325556Y908324D03*
X1320004Y911512D03*
X1327406Y898757D03*
X1320004Y917890D03*
X1325556Y921079D03*
X1321855D03*
X1327406Y924268D03*
X1320004D03*
X1321855Y914701D03*
X1325556D03*
X1327406Y917890D03*
X1325556Y927457D03*
X1321855D03*
X1327406Y930646D03*
X1320004Y937024D03*
X1325556Y940213D03*
X1321855D03*
Y933835D03*
X1325556D03*
X1320004Y930646D03*
X1327406Y937024D03*
Y943402D03*
X1320004D03*
X1325556Y946591D03*
X1321855D03*
X1327406Y949780D03*
X1320004Y956158D03*
X1321855Y952969D03*
X1325556D03*
X1320004Y949780D03*
X1327406Y956158D03*
X1320004Y962536D03*
X1325556Y965725D03*
X1321855D03*
X1327406Y968914D03*
X1325556Y959347D03*
X1321855D03*
X1327406Y962536D03*
X1320004Y968914D03*
X1325556Y984859D03*
X1320004Y975292D03*
X1325556Y978481D03*
X1321855D03*
X1327406Y981670D03*
X1321855Y972103D03*
X1325556D03*
X1327406Y975292D03*
Y988048D03*
X1320004Y994426D03*
X1321855Y997615D03*
X1325556D03*
X1327406Y1000804D03*
X1320004D03*
X1321855Y991237D03*
X1327406Y994426D03*
X1334808Y988048D03*
X1325556Y991237D03*
X1320004Y988048D03*
X1321855Y1010371D03*
X1320004Y1007182D03*
X1321855Y1003993D03*
X1325556D03*
X1327406Y1007182D03*
X1325556Y1010371D03*
X1326737Y1028055D03*
X1334138D03*
X1323036D03*
X1328587Y1031244D03*
X1326737Y1034433D03*
X1323036D03*
X1321185Y1037622D03*
X1328587D03*
X1326737Y1040811D03*
X1323036D03*
X1321185Y1044000D03*
X1328587D03*
X1321185Y1031244D03*
X1328587Y1050378D03*
X1323036Y1059945D03*
X1326737Y1047189D03*
X1321185Y1050378D03*
X1323036Y1053567D03*
X1334138Y1047189D03*
X1321185Y1056756D03*
X1323036Y1047189D03*
X1326737Y1053567D03*
X1323036Y1072701D03*
X1328587Y1063134D03*
X1321185D03*
X1326737Y1066323D03*
X1328587Y1069512D03*
X1321185D03*
X1326737Y1072701D03*
X1323036Y1066323D03*
X1328587Y1075890D03*
X1321185D03*
X1326737Y1079079D03*
X1323036D03*
X1328587Y1082268D03*
X1321185D03*
X1326737Y1085457D03*
X1321185Y1088646D03*
X1328587D03*
X1323036Y1085457D03*
X1321185Y1101402D03*
X1326737Y1104591D03*
X1323036Y1091835D03*
X1328587Y1095024D03*
X1321185D03*
X1326737Y1098213D03*
X1323036D03*
X1328587Y1101402D03*
X1323036Y1104591D03*
X1326737Y1091835D03*
X1323036Y1110969D03*
X1328587Y1114158D03*
X1321185D03*
X1326737Y1117347D03*
X1323036D03*
X1321185Y1107780D03*
X1328587D03*
X1326737Y1110969D03*
X1328587Y1120536D03*
X1321185D03*
X1326737Y1123725D03*
X1323036Y1130102D03*
X1328587Y1133292D03*
X1321185D03*
Y1126914D03*
X1328587D03*
X1323036Y1123725D03*
X1326737Y1130102D03*
Y1136480D03*
X1323036D03*
X1328587Y1139669D03*
X1321185D03*
X1326737Y1142858D03*
X1323036Y1149236D03*
X1321185Y1146047D03*
X1328587D03*
X1323036Y1142858D03*
X1326737Y1149236D03*
X1328587Y1152425D03*
X1321185D03*
X1326737Y1155614D03*
X1321185Y1158803D03*
X1334138Y1161992D03*
X1324090Y1549970D03*
X1328814D03*
X1333539D03*
X1325665Y1552698D03*
X1330389D03*
X1344059Y876434D03*
X1347760D03*
X1340359D03*
X1347760Y882812D03*
X1344059Y895568D03*
X1342209Y905134D03*
X1344059Y914701D03*
X1342209Y924268D03*
X1344059Y933835D03*
X1342209Y943402D03*
X1344059Y952969D03*
X1342209Y962536D03*
Y981670D03*
X1344059Y972103D03*
Y991237D03*
X1342209Y1000804D03*
X1340359Y991237D03*
X1345910Y988048D03*
X1340359Y1010371D03*
X1345241Y1028055D03*
X1341540D03*
X1348941D03*
X1343390Y1037622D03*
X1339689Y1044000D03*
X1335989Y1031244D03*
X1347091D03*
X1345241Y1047189D03*
X1343390Y1056756D03*
X1335989D03*
X1341540Y1053567D03*
X1347091Y1056756D03*
X1348941Y1047189D03*
X1345241Y1066323D03*
X1343390Y1075890D03*
X1345241Y1085457D03*
X1343390Y1095024D03*
X1345241Y1104591D03*
X1343390Y1114158D03*
Y1133292D03*
X1345241Y1123725D03*
Y1142858D03*
X1347091Y1158803D03*
X1348941Y1161992D03*
X1345241D03*
X1343390Y1152425D03*
X1335989Y1165181D03*
X1343390Y1158803D03*
X1341540Y1161992D03*
X1338263Y1549970D03*
X1342987D03*
X1347712D03*
X1335113Y1552698D03*
X1339838D03*
X1344562D03*
X1349287D03*
X1358863Y876434D03*
X1355162D03*
X1351461Y882812D03*
X1357012Y886001D03*
X1362563Y895568D03*
X1358863D03*
X1355162Y889190D03*
X1362563Y908324D03*
X1358863D03*
X1355162Y901946D03*
X1364414Y917890D03*
Y924268D03*
X1360713Y917890D03*
Y924268D03*
X1358863Y921079D03*
X1362563D03*
X1355162Y914701D03*
X1364414Y930646D03*
X1360713D03*
X1362563Y940213D03*
X1358863D03*
X1357012Y937024D03*
X1355162Y927457D03*
X1364414Y937024D03*
X1360713D03*
Y956158D03*
Y943402D03*
Y949780D03*
X1364414Y956158D03*
Y943402D03*
Y949780D03*
X1362563Y952969D03*
X1358863D03*
X1355162Y946591D03*
X1360713Y962536D03*
Y968914D03*
X1364414Y962536D03*
Y968914D03*
X1362563Y965725D03*
X1358863D03*
X1355162Y959347D03*
X1360713Y975292D03*
X1364414D03*
X1357012Y981670D03*
X1364414D03*
X1358863Y984859D03*
X1362563Y978481D03*
X1358863D03*
X1355162Y972103D03*
X1357012Y988048D03*
X1358863Y997615D03*
X1357012Y994426D03*
X1358863Y991237D03*
X1364414Y988048D03*
Y994426D03*
X1357012Y1000804D03*
X1364414D03*
X1351461Y991237D03*
X1357012Y1007182D03*
X1358863Y1003993D03*
X1364414Y1007182D03*
X1355162Y1010371D03*
X1362563D03*
X1351461D03*
X1360044Y1028055D03*
X1352642D03*
X1358193Y1031244D03*
X1360044Y1040811D03*
Y1034433D03*
X1358193Y1037622D03*
Y1044000D03*
X1354493D03*
X1363745Y1059945D03*
X1360044D03*
Y1047189D03*
X1358193Y1050378D03*
X1360044Y1053567D03*
X1361894Y1056756D03*
X1358193D03*
X1352642Y1053567D03*
X1363745Y1072701D03*
X1360044D03*
X1356343Y1066323D03*
X1363745Y1085457D03*
X1360044D03*
X1356343Y1079079D03*
X1363745Y1098213D03*
X1360044D03*
X1356343Y1091835D03*
X1358193Y1101402D03*
X1361894D03*
X1363745Y1117347D03*
X1360044D03*
X1356343Y1110969D03*
X1363745Y1130102D03*
X1360044D03*
X1356343Y1123725D03*
X1360044Y1142858D03*
X1363745D03*
X1356343Y1149236D03*
Y1136480D03*
X1358193Y1152425D03*
X1356343Y1161992D03*
X1360044D03*
X1352436Y1549970D03*
X1357161D03*
X1361885D03*
X1354011Y1552698D03*
X1358735D03*
X1363460D03*
X1369965Y876434D03*
X1366264D03*
X1377367D03*
X1368115Y879623D03*
X1371815D03*
X1368115Y886001D03*
X1369965Y895568D03*
X1373666D03*
X1366264Y889190D03*
X1377366D03*
X1379216Y886001D03*
X1371815D03*
X1375516D03*
Y911512D03*
X1371815D03*
X1369965Y908324D03*
X1373666D03*
X1375516Y917890D03*
Y924268D03*
X1371815Y917890D03*
Y924268D03*
X1369965Y921079D03*
X1373666D03*
X1375516Y930646D03*
X1371815D03*
X1369965Y940213D03*
X1373666D03*
X1371815Y937024D03*
X1379217D03*
X1368115D03*
X1375516D03*
X1371815Y956158D03*
Y943402D03*
Y949780D03*
X1375516Y956158D03*
Y943402D03*
Y949780D03*
X1369965Y952969D03*
X1373666D03*
X1371815Y962536D03*
Y968914D03*
X1375516Y962536D03*
Y968914D03*
X1369965Y965725D03*
X1373666D03*
X1371815Y975292D03*
X1375516D03*
X1366264Y984859D03*
X1369965Y978481D03*
X1373666D03*
X1371815Y981670D03*
X1379217D03*
X1373666Y984859D03*
Y991237D03*
X1371815Y988048D03*
Y994426D03*
Y1000804D03*
X1366264Y997615D03*
Y991237D03*
X1379217Y988048D03*
Y994426D03*
X1373666Y997615D03*
X1379217Y1000804D03*
X1366264Y1003993D03*
X1379217Y1007182D03*
X1377367Y1010371D03*
X1373666Y1003993D03*
X1369965Y1010371D03*
X1378548Y1028055D03*
X1367445D03*
X1374847Y1040811D03*
X1378548Y1034433D03*
X1372997Y1037622D03*
Y1044000D03*
X1367445Y1040811D03*
Y1034433D03*
X1365595Y1031244D03*
Y1037622D03*
Y1044000D03*
X1372997Y1031244D03*
X1374847Y1047189D03*
Y1053567D03*
X1371146Y1059945D03*
X1372997Y1056756D03*
Y1050378D03*
X1374847Y1059945D03*
X1365595Y1056756D03*
X1367445Y1047189D03*
Y1053567D03*
X1365595Y1050378D03*
X1371146Y1072701D03*
X1374847D03*
Y1085457D03*
X1371146D03*
X1374847Y1098213D03*
X1371146D03*
X1372997Y1101402D03*
X1376697D03*
X1369296D03*
X1365595D03*
X1374847Y1117347D03*
X1371146D03*
Y1130102D03*
X1374847D03*
Y1142858D03*
X1371146D03*
X1378548Y1149236D03*
X1367445D03*
X1369296Y1152425D03*
X1371146Y1161992D03*
X1378548D03*
X1367445D03*
X1371334Y1549970D03*
X1376058D03*
X1366609D03*
X1372909Y1552698D03*
X1377633D03*
X1368184D03*
X1388469Y876434D03*
X1392170D03*
X1381067D03*
X1390320Y879623D03*
X1394021D03*
X1381067Y895568D03*
X1384768D03*
X1390319Y886001D03*
X1392170Y895568D03*
X1388469Y889190D03*
X1394021Y886001D03*
X1386619Y911512D03*
X1394020D03*
X1382918D03*
X1384768Y908324D03*
X1392170D03*
X1381067Y908323D03*
X1386619Y924268D03*
Y917890D03*
X1394020Y924268D03*
Y917890D03*
X1382918Y924268D03*
Y917890D03*
X1384768Y921079D03*
X1381067D03*
X1392170D03*
X1394020Y937024D03*
X1382918Y930646D03*
X1386619D03*
X1384768Y940213D03*
X1381067D03*
X1394020Y930646D03*
X1392170Y940213D03*
X1381067Y933835D03*
X1386619Y937024D03*
X1384768Y933835D03*
X1382918Y937024D03*
X1394020Y956158D03*
Y943402D03*
Y949780D03*
X1382918Y956158D03*
Y943402D03*
Y949780D03*
X1386619Y956158D03*
Y943402D03*
Y949780D03*
X1384768Y952969D03*
X1381067D03*
X1392170D03*
X1394020Y962536D03*
Y968914D03*
X1382918Y962536D03*
Y968914D03*
X1386619Y962536D03*
Y968914D03*
X1384768Y965725D03*
X1381067D03*
X1392170D03*
X1394020Y975292D03*
X1382918D03*
X1386619D03*
X1381067Y978481D03*
X1384768D03*
X1386619Y981670D03*
X1381067Y984859D03*
X1392170Y978481D03*
X1394020Y981670D03*
X1388469Y984859D03*
X1386619Y988048D03*
X1394020D03*
X1381067Y991237D03*
X1388457Y997607D03*
X1388469Y991237D03*
X1382905Y1007174D03*
X1382236Y1028063D03*
X1380398Y1044000D03*
X1382246Y1040819D03*
X1389638D03*
X1382236Y1034441D03*
X1380398Y1037622D03*
Y1031244D03*
X1382249Y1047189D03*
X1389650D03*
X1380398Y1050378D03*
X1382249Y1059945D03*
Y1053567D03*
X1385949Y1059945D03*
X1380398Y1056756D03*
X1387800D03*
X1393351Y1059945D03*
X1387800Y1050378D03*
X1389650Y1053567D03*
X1382249Y1072701D03*
X1385949D03*
X1393351D03*
X1382249Y1085457D03*
X1385949D03*
X1393351D03*
X1382249Y1098213D03*
X1385949D03*
X1393351D03*
X1385949Y1104591D03*
X1384099Y1101402D03*
X1380398D03*
X1382249Y1104591D03*
X1387800Y1101402D03*
X1384099Y1107780D03*
X1382249Y1117347D03*
X1385949D03*
X1387800Y1107780D03*
X1393351Y1117347D03*
X1385949Y1130102D03*
X1382249D03*
X1393351D03*
X1382249Y1142858D03*
X1385949D03*
X1393351D03*
X1389650Y1149236D03*
X1380398Y1152425D03*
X1382249Y1161992D03*
X1391500Y1152425D03*
X1393351Y1161992D03*
X1389650D03*
X1380783Y1549970D03*
X1385507D03*
X1390232D03*
X1382357Y1552698D03*
X1387082D03*
X1391806D03*
X1399571Y876434D03*
X1403272D03*
X1405123Y879623D03*
X1401423D03*
X1401422Y886001D03*
X1395871Y895568D03*
X1399571Y889190D03*
X1408823Y892379D03*
X1405123D03*
X1397722Y886001D03*
X1408824D03*
X1405123D03*
X1397721Y911512D03*
X1395871Y908324D03*
X1408823Y911512D03*
X1405123D03*
X1408823Y898757D03*
X1405123D03*
X1406973Y921079D03*
Y914701D03*
X1397721Y924268D03*
Y917890D03*
X1403272Y921079D03*
Y914701D03*
X1395871Y921079D03*
X1408823Y924268D03*
X1405123D03*
X1403272Y940213D03*
X1406973D03*
X1397721Y937024D03*
X1406973Y927457D03*
X1403272D03*
X1397721Y930646D03*
X1395871Y940213D03*
X1406973Y933835D03*
X1403272D03*
Y952969D03*
Y946591D03*
X1406973Y952969D03*
Y946591D03*
X1397721Y956158D03*
Y943402D03*
Y949780D03*
X1395871Y952969D03*
X1405123Y943402D03*
X1408823D03*
X1405123Y956158D03*
X1408823D03*
X1403272Y959347D03*
Y965725D03*
X1406973Y959347D03*
Y965725D03*
X1397721Y962536D03*
Y968914D03*
X1405123D03*
X1395871Y965725D03*
X1408823Y968914D03*
X1403272Y978481D03*
Y972103D03*
X1406973Y978481D03*
Y972103D03*
X1397721Y975292D03*
X1395871Y978481D03*
X1401422Y981670D03*
X1395871Y984859D03*
X1408823Y981670D03*
X1403272Y984859D03*
X1401422Y988048D03*
X1395858Y997607D03*
X1395871Y991237D03*
X1403260Y997607D03*
X1408823Y988048D03*
X1403272Y991237D03*
X1397039Y1040819D03*
X1404441D03*
X1397052Y1047189D03*
X1404453D03*
X1395201Y1050378D03*
X1402603Y1056756D03*
Y1050378D03*
X1395201Y1056756D03*
X1397052Y1059945D03*
Y1053567D03*
X1404453D03*
X1406304Y1069512D03*
X1397052Y1072701D03*
Y1085457D03*
X1406304Y1082268D03*
X1397052Y1098213D03*
X1406304Y1095024D03*
X1408154Y1104591D03*
X1404453D03*
X1398902Y1107780D03*
X1395201D03*
X1397052Y1117347D03*
X1406304Y1114158D03*
X1397052Y1130102D03*
X1406304Y1126914D03*
X1397052Y1142858D03*
X1400752Y1149236D03*
X1406304Y1139669D03*
Y1146047D03*
X1402603Y1152425D03*
X1400752Y1161992D03*
X1406304Y1152425D03*
X1404453Y1161992D03*
X1408154Y1155614D03*
X1394956Y1549970D03*
X1396531Y1552698D03*
X1399256Y1540355D03*
X1401356D03*
X1402763Y1547073D03*
X1402707Y1549336D03*
X1403058Y1567540D03*
X1403059Y1564618D03*
X1402970Y1561698D03*
X1402473Y1571658D03*
X1423602Y892379D03*
Y911512D03*
Y898757D03*
Y924268D03*
Y943402D03*
Y956158D03*
Y968914D03*
X1410674Y984859D03*
X1410661Y997607D03*
X1410674Y991237D03*
X1411855Y1047189D03*
X1410004Y1050378D03*
X1411855Y1053567D03*
X1410004Y1056756D03*
Y1069512D03*
Y1082268D03*
Y1095024D03*
Y1114158D03*
Y1126914D03*
Y1139669D03*
Y1146047D03*
Y1152425D03*
Y1158803D03*
X1438405Y879623D03*
X1431003Y873245D03*
X1434704Y879623D03*
Y873245D03*
X1438405D03*
X1429153Y876434D03*
X1432854D03*
X1436554Y882812D03*
X1431003Y886001D03*
X1427302D03*
Y892379D03*
X1432854Y889190D03*
X1436554Y895568D03*
X1438405Y886001D03*
X1427302Y911512D03*
X1436554Y908324D03*
X1427302Y898757D03*
Y924268D03*
X1436554Y921079D03*
X1429153Y933835D03*
X1425452D03*
X1434704Y930646D03*
X1438405D03*
X1436554Y940213D03*
X1427302Y943402D03*
Y956158D03*
X1436554Y952969D03*
X1438405Y962536D03*
X1429153Y965725D03*
Y959347D03*
X1438405Y968914D03*
X1434704Y962536D03*
X1425452Y965725D03*
Y959347D03*
X1434704Y968914D03*
X1427302D03*
X1436554Y965725D03*
X1438405Y975292D03*
X1429153Y972103D03*
Y978481D03*
X1434704Y975292D03*
X1425452Y972103D03*
Y978481D03*
X1427302Y981670D03*
X1434704D03*
X1425452Y984859D03*
X1432854D03*
X1436554Y978481D03*
X1434704Y988048D03*
X1425465Y997607D03*
X1432866D03*
X1427302Y988048D03*
X1425452Y991237D03*
X1432854D03*
X1434047Y1040819D03*
X1434035Y1047189D03*
X1426633D03*
X1435885Y1050378D03*
X1428483D03*
X1437735Y1059945D03*
X1435885Y1056756D03*
X1428483D03*
X1426633Y1053567D03*
X1434035D03*
X1428483Y1069512D03*
X1424783D03*
X1437735Y1072701D03*
X1428483Y1082268D03*
X1424783D03*
X1437735Y1085457D03*
X1428483Y1095024D03*
X1424783D03*
X1430334Y1104591D03*
X1426633D03*
X1437735Y1098213D03*
X1428483Y1114158D03*
X1424783D03*
X1435885Y1107780D03*
X1437735Y1117347D03*
X1424783Y1126914D03*
X1428483D03*
X1437735Y1130102D03*
X1428483Y1139669D03*
X1424783D03*
X1434035Y1149236D03*
X1428483Y1146047D03*
X1424783D03*
X1437735Y1142858D03*
X1426633Y1161992D03*
X1424783Y1152425D03*
X1426633Y1155614D03*
X1428483Y1152425D03*
X1432184D03*
X1434035Y1161992D03*
X1430334D03*
X1424783Y1158803D03*
X1432184D03*
X1434035Y1155614D03*
X1428484Y1158803D03*
X1437735Y1155614D03*
X1443956Y876434D03*
X1440255D03*
X1451358D03*
X1449507Y873245D03*
X1453208D03*
X1440255Y882812D03*
X1442106Y886001D03*
X1443956Y889190D03*
X1447657Y895568D03*
X1440255D03*
X1453208Y886001D03*
X1451358Y895568D03*
X1447657Y908324D03*
X1440255D03*
X1451357D03*
X1447657Y921079D03*
X1440255D03*
X1451357D03*
X1445806Y930646D03*
X1449507D03*
X1447657Y940213D03*
X1440255D03*
X1451357D03*
X1442106Y930646D03*
X1453208Y937024D03*
X1445806D03*
X1451357Y933835D03*
X1447657D03*
X1449507Y937024D03*
X1447657Y952969D03*
X1440255D03*
X1451357D03*
X1449507Y968914D03*
Y962536D03*
X1445806Y968914D03*
Y962536D03*
X1440255Y965725D03*
X1447657D03*
X1451357D03*
X1449507Y975292D03*
X1445806D03*
X1440255Y978481D03*
X1447657D03*
X1442106Y981670D03*
X1449507D03*
X1447657Y984859D03*
X1440255D03*
X1451357Y978481D03*
X1449507Y988048D03*
X1440268Y997607D03*
X1447669D03*
X1442106Y988048D03*
X1440255Y991237D03*
X1447657D03*
X1441449Y1040819D03*
X1448850D03*
X1441436Y1047189D03*
X1448838D03*
X1450688Y1050378D03*
Y1056756D03*
X1441436Y1059945D03*
Y1053567D03*
X1443287Y1056756D03*
X1448838Y1053567D03*
X1443287Y1050378D03*
X1448838Y1059945D03*
X1452539D03*
X1441436Y1072701D03*
X1448838D03*
X1452539D03*
X1448838Y1085457D03*
X1441436D03*
X1452539D03*
X1448838Y1098213D03*
X1441436D03*
X1452539D03*
X1448838Y1104591D03*
X1452539D03*
X1446987Y1101402D03*
X1450688D03*
Y1107780D03*
X1446987D03*
X1439586D03*
X1448838Y1117347D03*
X1441436D03*
X1452539D03*
X1448838Y1130102D03*
X1441436D03*
X1452539Y1130103D03*
X1448838Y1142858D03*
X1441436D03*
X1445137Y1149236D03*
X1452539Y1142858D03*
X1446987Y1152425D03*
X1443287Y1165181D03*
X1439586Y1158803D03*
X1443287Y1152425D03*
X1452539Y1161992D03*
X1441436D03*
X1445137D03*
X1448838Y1155614D03*
X1439586Y1152425D03*
X1445137Y1155614D03*
X1443287Y1158803D03*
X1450627Y1540509D03*
X1452827D03*
X1450792Y1546218D03*
X1449133Y1551121D03*
X1449534Y1554612D03*
X1449580Y1568698D03*
Y1570898D03*
X1451027Y1573317D03*
X1462460Y876434D03*
X1455058D03*
X1466161D03*
X1464310Y873245D03*
X1460609D03*
Y879623D03*
X1464310D03*
Y886001D03*
X1458759Y895568D03*
X1462460D03*
X1466161Y889190D03*
X1455058D03*
X1460609Y886001D03*
X1456909D03*
X1468011D03*
X1458759Y908324D03*
X1462460D03*
X1458759Y921079D03*
X1462460D03*
Y940213D03*
X1458759D03*
X1456909Y937024D03*
X1464310D03*
X1460609D03*
X1468011D03*
X1458759Y952969D03*
X1462460D03*
X1460609Y968914D03*
Y962536D03*
X1468011Y968914D03*
Y962536D03*
X1456909Y968914D03*
Y962536D03*
X1462460Y965725D03*
X1458759D03*
X1460609Y975292D03*
X1468011D03*
X1456909D03*
X1462460Y978481D03*
X1458759D03*
X1464310Y981670D03*
X1456909D03*
X1462460Y984859D03*
X1455058D03*
X1464310Y988048D03*
Y994426D03*
X1456909Y988048D03*
Y994426D03*
X1462460Y997615D03*
Y991237D03*
X1455058Y997615D03*
Y991237D03*
X1456909Y1000804D03*
X1464310D03*
Y1007182D03*
X1456909D03*
X1462460Y1010371D03*
Y1003993D03*
X1455058Y1010371D03*
Y1003993D03*
X1459940Y1028055D03*
X1467342D03*
X1458090Y1037622D03*
Y1044000D03*
X1465491Y1037622D03*
Y1044000D03*
X1463641Y1040811D03*
X1456239D03*
X1459940Y1034433D03*
X1461791Y1031244D03*
X1454389D03*
X1467342Y1034433D03*
X1463641Y1047189D03*
X1456239D03*
X1465491Y1050378D03*
X1456239Y1053567D03*
X1463641D03*
X1458090Y1056756D03*
X1463641Y1059945D03*
X1465491Y1056756D03*
X1458090Y1050378D03*
X1459940Y1059945D03*
X1463641Y1072701D03*
X1459940D03*
X1463641Y1085457D03*
X1459940D03*
X1463641Y1098213D03*
X1459940D03*
X1454389Y1101402D03*
X1461791D03*
X1458090D03*
X1465491D03*
X1459940Y1117347D03*
X1463641D03*
X1459940Y1130102D03*
X1463641D03*
Y1142858D03*
X1459940D03*
X1456239Y1149236D03*
X1467342D03*
X1454389Y1158803D03*
X1467342Y1155614D03*
X1465491Y1158803D03*
X1459940Y1155614D03*
X1465491Y1152425D03*
X1454389D03*
X1467342Y1161992D03*
X1463641D03*
X1456239D03*
X1461791Y1165181D03*
X1458090Y1152425D03*
X1461791Y1158803D03*
X1456239Y1155614D03*
X1455098Y1577625D03*
X1475413Y879623D03*
X1482814D03*
X1473562Y876434D03*
X1477263D03*
X1471712Y873245D03*
X1475413D03*
X1480964Y876434D03*
X1475413Y886001D03*
X1477263Y889190D03*
X1473562Y895568D03*
X1469861D03*
X1471712Y886001D03*
X1469861Y908324D03*
X1473562D03*
X1477263Y901946D03*
X1473562Y921079D03*
X1469861D03*
X1477263Y914701D03*
X1469861Y940213D03*
X1473562D03*
X1477263Y927457D03*
X1475413Y937024D03*
X1471712D03*
X1473562Y952969D03*
X1469861D03*
X1477263Y946591D03*
X1471712Y968914D03*
Y962536D03*
X1473562Y965725D03*
X1469861D03*
X1477263Y959347D03*
X1471712Y975292D03*
Y981670D03*
X1473562Y978481D03*
X1469861D03*
Y984859D03*
X1477263Y972103D03*
Y984859D03*
Y991237D03*
X1469861Y997615D03*
Y991237D03*
X1471712Y988048D03*
Y994426D03*
X1477263Y997615D03*
X1471712Y1000804D03*
X1479113Y994426D03*
X1471712Y1007182D03*
X1477263Y1010371D03*
Y1003993D03*
X1469861Y1010371D03*
Y1003993D03*
X1480964Y1010371D03*
X1474743Y1028055D03*
X1482145D03*
X1478444Y1040811D03*
X1471043D03*
X1472893Y1037622D03*
Y1044000D03*
X1474743Y1034433D03*
X1476594Y1031244D03*
X1469192D03*
X1472893Y1050378D03*
X1478444Y1047189D03*
X1471043D03*
X1478444Y1053567D03*
X1472893Y1056756D03*
X1471043Y1053567D03*
X1474743Y1059945D03*
X1471043D03*
X1482145Y1053567D03*
X1478444Y1066323D03*
X1471043Y1072701D03*
X1474743D03*
X1478444Y1079079D03*
X1474743Y1085457D03*
X1471043D03*
X1478444Y1091835D03*
X1476594Y1101402D03*
X1474743Y1098213D03*
X1471043D03*
X1469192Y1101402D03*
X1478444Y1110969D03*
X1474743Y1117347D03*
X1471043D03*
X1478444Y1123725D03*
X1474743Y1130102D03*
X1471043D03*
X1478444Y1136480D03*
X1474743Y1142858D03*
X1471043D03*
X1478444Y1149236D03*
X1472893Y1158803D03*
X1471043Y1155614D03*
Y1161992D03*
X1469192Y1152425D03*
X1476594D03*
X1478444Y1161992D03*
X1474743D03*
X1476594Y1158803D03*
X1476778Y1165778D03*
X1486515Y879623D03*
X1490216D03*
X1484665Y876434D03*
X1488365D03*
Y895568D03*
X1492066Y882812D03*
X1490216Y905134D03*
X1488365Y914701D03*
X1490216Y924268D03*
X1488365Y933835D03*
X1490216Y943402D03*
X1488365Y952969D03*
X1490216Y962536D03*
Y981670D03*
X1488365Y972103D03*
Y991237D03*
X1490216Y1000804D03*
X1493917Y994426D03*
X1484665Y991237D03*
X1488365Y1010371D03*
X1492066D03*
X1493247Y1028055D03*
X1485846D03*
X1491397Y1037622D03*
X1498798Y1044000D03*
Y1031244D03*
X1487696Y1044000D03*
Y1031244D03*
X1489547Y1047189D03*
X1491397Y1056756D03*
X1498798D03*
X1493247Y1053567D03*
X1487696Y1056756D03*
X1485846Y1047189D03*
X1489547Y1066323D03*
X1491397Y1075890D03*
X1489547Y1085457D03*
X1491397Y1095024D03*
X1489547Y1104591D03*
X1491397Y1114158D03*
Y1133292D03*
X1489547Y1123725D03*
Y1142858D03*
X1491397Y1152425D03*
X1489547Y1161992D03*
X1485846D03*
X1487696Y1158803D03*
X1506869Y876434D03*
X1512421Y879623D03*
X1505019D03*
X1512421Y886001D03*
X1506869Y889190D03*
X1510570D03*
X1505019Y892379D03*
X1510570Y895568D03*
X1506869D03*
X1512421Y892379D03*
X1506869Y882812D03*
X1510570Y908324D03*
X1505019Y911512D03*
X1512421Y898757D03*
X1506869Y901946D03*
X1510570D03*
X1505019Y905134D03*
X1512421D03*
X1506869Y908324D03*
X1512421Y911512D03*
X1505019Y898757D03*
X1512421Y917890D03*
X1506869Y921079D03*
X1510570D03*
X1505019Y924268D03*
X1512421D03*
X1510570Y914701D03*
X1506869D03*
X1505019Y917890D03*
X1506869Y927457D03*
X1510570D03*
X1505019Y930646D03*
X1512421Y937024D03*
X1506869Y940213D03*
X1510570D03*
Y933835D03*
X1506869D03*
X1512421Y930646D03*
X1505019Y937024D03*
Y943402D03*
X1512421D03*
X1506869Y946591D03*
X1510570D03*
X1505019Y949780D03*
X1512421Y956158D03*
X1510570Y952969D03*
X1506869D03*
X1512421Y949780D03*
X1505019Y956158D03*
X1512421Y962536D03*
X1506869Y965725D03*
X1510570D03*
X1505019Y968914D03*
X1506869Y959347D03*
X1510570D03*
X1505019Y962536D03*
X1512421Y968914D03*
X1506869Y984859D03*
X1512421Y975292D03*
X1506869Y978481D03*
X1510570D03*
X1505019Y981670D03*
X1510570Y972103D03*
X1506869D03*
X1505019Y975292D03*
Y988048D03*
X1512421Y994426D03*
X1510570Y997615D03*
X1506869D03*
X1505019Y1000804D03*
X1512421D03*
Y988048D03*
X1506869Y991237D03*
X1499468D03*
X1505019Y994426D03*
X1510570Y991237D03*
Y1010371D03*
X1512421Y1007182D03*
X1510570Y1003993D03*
X1506869D03*
X1505019Y1007182D03*
X1506869Y1010371D03*
X1508050Y1028055D03*
X1500649D03*
X1511751D03*
X1506200Y1031244D03*
X1508050Y1034433D03*
X1511751D03*
X1513602Y1037622D03*
X1506200D03*
X1508050Y1040811D03*
X1511751D03*
X1506200Y1044000D03*
X1513602D03*
Y1031244D03*
X1506200Y1050378D03*
X1511751Y1059945D03*
X1508050Y1047189D03*
X1513602Y1050378D03*
X1511751Y1053567D03*
X1500649Y1047189D03*
X1513602Y1056756D03*
X1511751Y1047189D03*
X1508050Y1053567D03*
X1511751Y1072701D03*
X1506200Y1063134D03*
X1513602D03*
X1508050Y1066323D03*
X1506200Y1069512D03*
X1513602D03*
X1508050Y1072701D03*
X1511751Y1066323D03*
X1506200Y1075890D03*
X1513602D03*
X1508050Y1079079D03*
X1511751D03*
X1506200Y1082268D03*
X1513602D03*
X1508050Y1085457D03*
X1513602Y1088646D03*
X1506200D03*
X1511751Y1085457D03*
X1513602Y1101402D03*
X1508050Y1104591D03*
X1511751Y1091835D03*
X1506200Y1095024D03*
X1513602D03*
X1508050Y1098213D03*
X1511751D03*
X1506200Y1101402D03*
X1511751Y1104591D03*
X1508050Y1091835D03*
X1511751Y1110969D03*
X1506200Y1114158D03*
X1513602D03*
X1508050Y1117347D03*
X1511751D03*
X1513602Y1107780D03*
X1506200D03*
X1508050Y1110969D03*
X1506200Y1120536D03*
X1513602D03*
X1508050Y1123725D03*
X1511751Y1130102D03*
X1506200Y1133292D03*
X1513602D03*
Y1126914D03*
X1506200D03*
X1511751Y1123725D03*
X1508050Y1130102D03*
Y1136480D03*
X1511751D03*
X1506200Y1139669D03*
X1513602D03*
X1508050Y1142858D03*
X1511751Y1149236D03*
X1513602Y1146047D03*
X1506200D03*
X1511751Y1142858D03*
X1508050Y1149236D03*
X1506200Y1152425D03*
X1513602D03*
X1508050Y1155614D03*
X1513602Y1158803D03*
X1500649Y1161992D03*
X1504350D03*
X1527224Y873245D03*
X1516121D03*
X1519822D03*
X1514271Y876434D03*
X1523523Y879623D03*
X1525373Y876434D03*
X1523523Y886001D03*
X1517972Y889190D03*
X1525373D03*
X1519822Y892379D03*
X1525373Y895568D03*
X1517972D03*
X1523523Y892379D03*
X1516121Y886001D03*
X1514271Y895568D03*
X1525373Y908324D03*
X1519822Y911512D03*
X1523523Y898757D03*
X1517972Y901946D03*
X1525373D03*
X1519822Y905134D03*
X1523523D03*
X1517972Y908324D03*
X1523523Y911512D03*
X1519822Y898757D03*
X1516121Y905134D03*
X1523523Y917890D03*
X1517972Y921079D03*
X1525373D03*
X1519822Y924268D03*
X1523523D03*
X1525373Y914701D03*
X1517972D03*
X1519822Y917890D03*
X1516121Y924268D03*
X1514271Y914701D03*
X1517972Y927457D03*
X1525373D03*
X1519822Y930646D03*
X1523523Y937024D03*
X1517972Y940213D03*
X1525373D03*
Y933835D03*
X1517972D03*
X1523523Y930646D03*
X1519822Y937024D03*
X1514271Y933835D03*
X1519822Y943402D03*
X1523523D03*
X1517972Y946591D03*
X1525373D03*
X1519822Y949780D03*
X1523523Y956158D03*
X1525373Y952969D03*
X1517972D03*
X1523523Y949780D03*
X1519822Y956158D03*
X1516121Y943402D03*
X1514271Y952969D03*
X1523523Y962536D03*
X1517972Y965725D03*
X1525373D03*
X1519822Y968914D03*
X1517972Y959347D03*
X1525373D03*
X1519822Y962536D03*
X1523523Y968914D03*
X1516121Y962536D03*
X1517972Y984859D03*
X1523523Y975292D03*
X1517972Y978481D03*
X1525373D03*
X1519822Y981670D03*
X1525373Y972103D03*
X1517972D03*
X1519822Y975292D03*
X1516121Y981670D03*
X1514271Y972103D03*
X1519822Y988048D03*
X1523523Y994426D03*
X1525373Y997615D03*
X1517972D03*
X1519822Y1000804D03*
X1523523D03*
Y988048D03*
X1517972Y991237D03*
X1516121Y1000804D03*
X1514271Y991237D03*
X1519822Y994426D03*
X1525373Y991237D03*
Y1010371D03*
X1523523Y1007182D03*
X1525373Y1003993D03*
X1517972D03*
X1519822Y1007182D03*
X1514271Y1010371D03*
X1517972D03*
X1519153Y1028055D03*
X1526554D03*
X1521003Y1031244D03*
X1519153Y1034433D03*
X1526554D03*
X1524704Y1037622D03*
X1521003D03*
X1519153Y1040811D03*
X1526554D03*
X1521003Y1044000D03*
X1517302Y1037622D03*
X1524704Y1044000D03*
Y1031244D03*
X1521003Y1050378D03*
X1526554Y1059945D03*
X1519153Y1047189D03*
X1524704Y1050378D03*
X1526554Y1053567D03*
X1517302Y1056756D03*
X1515452Y1047189D03*
X1524704Y1056756D03*
X1526554Y1047189D03*
X1519153Y1053567D03*
X1526554Y1072701D03*
X1521003Y1063134D03*
X1524704D03*
X1519153Y1066323D03*
X1521003Y1069512D03*
X1524704D03*
X1519153Y1072701D03*
X1526554Y1066323D03*
X1515452D03*
X1521003Y1075890D03*
X1524704D03*
X1519153Y1079079D03*
X1526554D03*
X1521003Y1082268D03*
X1524704D03*
X1519153Y1085457D03*
X1524704Y1088646D03*
X1521003D03*
X1526554Y1085457D03*
X1515452D03*
X1517302Y1075890D03*
X1524704Y1101402D03*
X1519153Y1104591D03*
X1526554Y1091835D03*
X1521003Y1095024D03*
X1524704D03*
X1519153Y1098213D03*
X1526554D03*
X1521003Y1101402D03*
X1526554Y1104591D03*
X1519153Y1091835D03*
X1515452Y1104591D03*
X1517302Y1095024D03*
X1526554Y1110969D03*
X1521003Y1114158D03*
X1524704D03*
X1519153Y1117347D03*
X1526554D03*
X1524704Y1107780D03*
X1521003D03*
X1519153Y1110969D03*
X1517302Y1114158D03*
X1521003Y1120536D03*
X1524704D03*
X1519153Y1123725D03*
X1526554Y1130102D03*
X1521003Y1133292D03*
X1524704D03*
Y1126914D03*
X1521003D03*
X1526554Y1123725D03*
X1519153Y1130102D03*
X1517302Y1133292D03*
X1515452Y1123725D03*
X1519153Y1136480D03*
X1526554D03*
X1521003Y1139669D03*
X1524704D03*
X1519153Y1142858D03*
X1526554Y1149236D03*
X1524704Y1146047D03*
X1521003D03*
X1526554Y1142858D03*
X1519153Y1149236D03*
X1515452Y1142858D03*
X1521003Y1152425D03*
X1524704D03*
X1526554Y1155614D03*
X1517302Y1152425D03*
X1521003Y1158803D03*
X1515452Y1161992D03*
X1542027Y879623D03*
X1540176Y876434D03*
X1530924Y873245D03*
X1534625Y879623D03*
X1536476Y876434D03*
X1540176Y895568D03*
X1542027Y886001D03*
X1532775Y882812D03*
X1542027Y905134D03*
Y924268D03*
X1540176Y914701D03*
Y933835D03*
Y952969D03*
X1542027Y943402D03*
Y962536D03*
Y981670D03*
X1540176Y972103D03*
X1542027Y1000804D03*
X1540176Y991237D03*
X1530924Y994426D03*
X1536476Y991237D03*
X1540176Y1010371D03*
X1532775D03*
X1533956Y1028055D03*
X1537657D03*
X1543208Y1037622D03*
X1539507Y1044000D03*
Y1031244D03*
X1543208Y1056756D03*
X1541357Y1047189D03*
X1539507Y1056756D03*
X1537657Y1047189D03*
X1533956Y1053567D03*
X1541357Y1066323D03*
Y1085457D03*
X1543208Y1075890D03*
X1541357Y1104591D03*
X1543208Y1095024D03*
Y1114158D03*
Y1133292D03*
X1541357Y1123725D03*
Y1142858D03*
X1533956Y1161992D03*
X1543208Y1158803D03*
X1539507D03*
X1543208Y1152425D03*
X1537657Y1161992D03*
X1530255D03*
X1535368Y1540355D03*
X1537468D03*
X1538875Y1547073D03*
X1538819Y1549336D03*
X1539170Y1567540D03*
X1539171Y1564618D03*
X1539082Y1561698D03*
X1538585Y1571658D03*
X1539170Y1569640D03*
X1549428Y879623D03*
X1545728D03*
X1543877Y1010371D03*
X1545058Y1028055D03*
X1548759Y1161992D03*
X1546909Y1165181D03*
X1580940Y1540460D03*
X1578689Y1540509D03*
X1578854Y1546218D03*
X1577195Y1551121D03*
X1577596Y1554612D03*
X1577642Y1568698D03*
Y1570898D03*
X1583160Y1577625D03*
X1579089Y1573317D03*
X1663430Y1540355D03*
X1665530D03*
X1666937Y1547073D03*
X1666881Y1549336D03*
X1667231Y1567540D03*
X1667232Y1564618D03*
X1667143Y1561698D03*
X1670227Y1567413D03*
X1668750Y1563158D03*
X1666647Y1571658D03*
X1667231Y1569640D03*
G54D41*
X326731Y653394D03*
X363731D03*
X433624Y594259D03*
X754645Y1426892D03*
X766889Y1486756D03*
Y1530256D03*
X1166535Y1412479D03*
X1291146Y1375715D03*
X1320516D03*
X1415690Y601230D03*
X1487677Y640145D03*
X1524437Y640365D03*
X1701285Y198612D03*
X1700840Y1424519D03*
X1731660Y198612D03*
X1770442Y284934D03*
X1800002D03*
G54D25*
X79729Y289822D03*
Y310256D03*
X89729Y289822D03*
X99729D03*
X89729Y310256D03*
X99729D03*
X757184Y1712772D03*
Y1722772D03*
X1072863Y1419176D03*
Y1429176D03*
X1080970Y1650958D03*
Y1660958D03*
X1299439Y92812D03*
Y102812D03*
X1530377Y581353D03*
X1540377D03*
G54D68*
X1233404Y60384D03*
X1241278D03*
X1249152D03*
X1439049Y87432D03*
X1431175D03*
X1446923D03*
G54D23*
X64823Y756832D03*
Y760178D03*
X73933Y768706D03*
X73960Y766090D03*
X69323Y780257D03*
Y786950D03*
Y803682D03*
Y793643D03*
Y796989D03*
Y817068D03*
Y810375D03*
Y823761D03*
Y830454D03*
Y833800D03*
Y840493D03*
Y847186D03*
Y853879D03*
Y860572D03*
Y877304D03*
Y867265D03*
Y870611D03*
Y883997D03*
Y890690D03*
Y897383D03*
Y904076D03*
Y907423D03*
Y914115D03*
Y920808D03*
Y927501D03*
Y934194D03*
Y940887D03*
Y950926D03*
Y944234D03*
Y964312D03*
Y957619D03*
Y971005D03*
Y977698D03*
Y984391D03*
Y1001123D03*
Y997777D03*
Y991084D03*
Y1031241D03*
Y1037934D03*
Y1044627D03*
Y1058013D03*
Y1051320D03*
Y1074745D03*
Y1068052D03*
Y1064706D03*
Y1081438D03*
Y1088131D03*
Y1098171D03*
Y1104863D03*
Y1091478D03*
Y1111556D03*
Y1118249D03*
Y1134982D03*
Y1124942D03*
Y1128289D03*
Y1148367D03*
Y1141675D03*
Y1155060D03*
Y1161753D03*
Y1165100D03*
Y1171793D03*
Y1178486D03*
Y1185178D03*
Y1191871D03*
Y1208604D03*
Y1198564D03*
Y1201911D03*
Y1215297D03*
Y1221989D03*
Y1228682D03*
Y1235375D03*
Y1238722D03*
Y1245415D03*
Y1252108D03*
X94524Y760178D03*
Y756832D03*
X89965D03*
X90015Y766871D03*
X85465Y776911D03*
X89965Y763525D03*
X94474D03*
X90015Y770218D03*
X85465Y783604D03*
Y790297D03*
Y800336D03*
Y807029D03*
Y793643D03*
Y813722D03*
Y820415D03*
Y837147D03*
Y830454D03*
Y827108D03*
Y843840D03*
Y850533D03*
Y857226D03*
Y863919D03*
Y873958D03*
Y880651D03*
Y867265D03*
Y887344D03*
Y894037D03*
Y910769D03*
Y904076D03*
Y900730D03*
Y924155D03*
Y917462D03*
Y930848D03*
Y940887D03*
Y937541D03*
Y947580D03*
Y954273D03*
Y960966D03*
Y967659D03*
Y974352D03*
Y981045D03*
Y987737D03*
Y994430D03*
Y1001123D03*
Y1027895D03*
Y1034588D03*
Y1041281D03*
Y1047974D03*
Y1054667D03*
Y1061360D03*
Y1071399D03*
Y1064706D03*
Y1078092D03*
Y1088131D03*
Y1084785D03*
Y1094824D03*
Y1101517D03*
Y1108210D03*
Y1114903D03*
Y1131635D03*
Y1124942D03*
Y1121596D03*
Y1138328D03*
Y1145021D03*
Y1151714D03*
Y1161753D03*
Y1158407D03*
Y1168446D03*
Y1175139D03*
Y1181832D03*
Y1188525D03*
Y1205257D03*
Y1198564D03*
Y1195218D03*
Y1211950D03*
Y1218643D03*
Y1225336D03*
Y1235375D03*
Y1232029D03*
Y1242068D03*
Y1248761D03*
X103574Y763766D03*
X99024Y1068052D03*
Y1064706D03*
X124224Y760178D03*
Y756832D03*
X119666D03*
X119616Y767166D03*
X119666Y763525D03*
X124174D03*
X119716Y770218D03*
X115166Y960966D03*
X120666D03*
X133124Y763766D03*
X128724Y1068052D03*
Y1064706D03*
X153925Y760178D03*
Y756832D03*
X149366D03*
X149416Y766871D03*
X149366Y763525D03*
X153875D03*
X149416Y770218D03*
X144866Y960966D03*
X150366D03*
X162975Y763766D03*
X158425Y1068052D03*
Y1064706D03*
X183626Y760178D03*
Y756832D03*
X179067D03*
X179117Y766871D03*
X179067Y763525D03*
X183576D03*
X179117Y770218D03*
X174567Y960966D03*
X180067D03*
X186530Y1523953D03*
X192676Y763766D03*
X188126Y780257D03*
Y786950D03*
Y803682D03*
Y793643D03*
Y796989D03*
Y817068D03*
Y810375D03*
Y823761D03*
Y830454D03*
Y833800D03*
Y840493D03*
Y847186D03*
Y853879D03*
Y860572D03*
Y877304D03*
Y867265D03*
Y870611D03*
Y883997D03*
Y890690D03*
Y897383D03*
Y904076D03*
Y907423D03*
Y914115D03*
Y920808D03*
Y927501D03*
Y934194D03*
Y940887D03*
Y950926D03*
Y944234D03*
Y964312D03*
Y957619D03*
Y971005D03*
Y977698D03*
Y984391D03*
Y1001123D03*
Y997777D03*
Y991084D03*
Y1031241D03*
Y1037934D03*
Y1044627D03*
Y1058013D03*
Y1051320D03*
Y1074745D03*
Y1068052D03*
Y1064706D03*
Y1081438D03*
Y1088131D03*
Y1098171D03*
Y1104863D03*
Y1091478D03*
Y1111556D03*
Y1118249D03*
Y1134982D03*
Y1124942D03*
Y1128289D03*
Y1148367D03*
Y1141675D03*
Y1155060D03*
Y1161753D03*
Y1165100D03*
Y1171793D03*
Y1178486D03*
Y1185178D03*
Y1191871D03*
Y1208604D03*
Y1198564D03*
Y1201911D03*
Y1215297D03*
Y1221989D03*
Y1228682D03*
Y1235375D03*
Y1238722D03*
Y1245415D03*
Y1252108D03*
X195979Y1523953D03*
X196530Y1526353D03*
X191805D03*
X187081D03*
X200703Y1523953D03*
X201254Y1526353D03*
X191254Y1523953D03*
X188254Y1544997D03*
X192978D03*
X197703D03*
X188254Y1548397D03*
X192978D03*
X197703D03*
X188166Y1624292D03*
X200226D03*
X191566D03*
X194196Y1614292D03*
X197596D03*
X213327Y760178D03*
Y756832D03*
X208768D03*
X204268Y776911D03*
X208768Y763525D03*
X212772Y766871D03*
X213277Y763525D03*
X208818Y770218D03*
X204268Y783604D03*
Y790297D03*
Y800336D03*
Y807029D03*
Y793643D03*
Y813722D03*
Y820415D03*
Y837147D03*
Y830454D03*
Y827108D03*
Y843840D03*
Y850533D03*
Y857226D03*
Y863919D03*
Y873958D03*
Y880651D03*
Y867265D03*
Y887344D03*
Y894037D03*
Y910769D03*
Y904076D03*
Y900730D03*
Y924155D03*
Y917462D03*
Y930848D03*
Y940887D03*
Y937541D03*
Y947580D03*
Y954273D03*
Y960966D03*
Y967659D03*
Y974352D03*
Y981045D03*
Y987737D03*
Y994430D03*
Y1001123D03*
Y1027895D03*
Y1034588D03*
Y1041281D03*
Y1047974D03*
Y1054667D03*
Y1061360D03*
Y1071399D03*
Y1064706D03*
Y1078092D03*
Y1088131D03*
Y1084785D03*
Y1094824D03*
Y1101517D03*
Y1108210D03*
Y1114903D03*
Y1131635D03*
Y1124942D03*
Y1121596D03*
Y1138328D03*
Y1145021D03*
Y1151714D03*
Y1161753D03*
Y1158407D03*
Y1168446D03*
Y1175139D03*
Y1181832D03*
Y1188525D03*
Y1205257D03*
Y1198564D03*
Y1195218D03*
Y1211950D03*
Y1218643D03*
Y1225336D03*
Y1235375D03*
Y1232029D03*
Y1242068D03*
Y1248761D03*
X205427Y1523953D03*
X205978Y1526353D03*
X210703D03*
X210152Y1523953D03*
X214876D03*
X215427Y1526353D03*
X202427Y1544997D03*
X207152D03*
X211876D03*
X216601D03*
X202427Y1548397D03*
X207152D03*
X211876D03*
X216601D03*
X212286Y1624292D03*
X203626D03*
X215686D03*
X206256Y1614292D03*
X209656D03*
X222377Y763766D03*
X227540Y960966D03*
X220152Y1526353D03*
X224876D03*
X224325Y1523953D03*
X219601D03*
X229049D03*
X229600Y1526353D03*
X221325Y1544997D03*
X226050D03*
X230774D03*
X221325Y1548397D03*
X226050D03*
X230774D03*
X224346Y1624292D03*
X227746D03*
X218316Y1614292D03*
X230376D03*
X221716D03*
X238469Y756832D03*
Y763525D03*
X238519Y770218D03*
X233969Y960966D03*
X243223Y1523953D03*
X243774Y1526353D03*
X238498Y1523953D03*
X239049Y1526353D03*
X233774Y1523953D03*
X234325Y1526353D03*
X235499Y1544997D03*
X240223D03*
X244947D03*
X235499Y1548397D03*
X240223D03*
X244947D03*
X236406Y1624292D03*
X239806D03*
X242436Y1614292D03*
X233776D03*
X245836D03*
X257396Y1523953D03*
X253223Y1526353D03*
X252672Y1523953D03*
X257947Y1526353D03*
X248498D03*
X247947Y1523953D03*
X249671Y1544997D03*
X254396D03*
X259120D03*
X249671Y1548397D03*
X254396D03*
X259120D03*
X248466Y1624292D03*
X260526D03*
X251866D03*
X254496Y1614292D03*
X257896D03*
X272525Y108556D03*
X268981D03*
Y111056D03*
X265438Y108556D03*
X261895D03*
Y111056D03*
X265438D03*
X272525D03*
X272586Y1624292D03*
X263926D03*
X275986D03*
X266556Y1614292D03*
X269956D03*
X284646Y1624292D03*
X288046D03*
X278616Y1614292D03*
X290676D03*
X282016D03*
X296706Y1624292D03*
X300106D03*
X302736Y1614292D03*
X294076D03*
X306136D03*
X306694Y1507279D03*
X319867Y1526353D03*
X315143D03*
X319316Y1523953D03*
X314592D03*
X316316Y1544997D03*
X321040D03*
X316316Y1548397D03*
X321040D03*
X308766Y1624292D03*
X320826D03*
X312166D03*
X314796Y1614292D03*
X318196D03*
X324041Y1523953D03*
X324592Y1526353D03*
X328765Y1523953D03*
X329316Y1526353D03*
X334040D03*
X333489Y1523953D03*
X325765Y1544997D03*
X330489D03*
X335214D03*
X325765Y1548397D03*
X330489D03*
X335214D03*
X332886Y1624292D03*
X324226D03*
X326856Y1614292D03*
X330256D03*
X338765Y1526353D03*
X338214Y1523953D03*
X347663D03*
X348214Y1526353D03*
X343489D03*
X342938Y1523953D03*
X339938Y1544997D03*
X344663D03*
X349387D03*
X339938Y1548397D03*
X344663D03*
X349387D03*
X344946Y1624292D03*
X336286D03*
X348346D03*
X338916Y1614292D03*
X350976D03*
X342316D03*
X362387Y1526353D03*
X361836Y1523953D03*
X352387D03*
X352938Y1526353D03*
X357662D03*
X357111Y1523953D03*
X363561Y1544997D03*
X354112D03*
X358836D03*
X363561Y1548397D03*
X354112D03*
X358836D03*
X357006Y1624292D03*
X360406D03*
X363036Y1614292D03*
X354376D03*
X380734Y1523953D03*
X376560Y1526353D03*
X376009Y1523953D03*
X371285D03*
X371836Y1526353D03*
X367111D03*
X366560Y1523953D03*
X368285Y1544997D03*
X373009D03*
X377733D03*
X368285Y1548397D03*
X373009D03*
X377733D03*
X369066Y1624292D03*
X372466D03*
X375096Y1614292D03*
X366436D03*
X378496D03*
X385458Y1523953D03*
X381285Y1526353D03*
X386009D03*
X382458Y1544997D03*
X387182D03*
X382458Y1548397D03*
X387182D03*
X450703Y1523953D03*
X451254Y1526353D03*
X452427Y1544997D03*
Y1548397D03*
X452339Y1624292D03*
X464876Y1523953D03*
X460703Y1526353D03*
X455978D03*
X465427D03*
X455427Y1523953D03*
X460152D03*
X469600D03*
X470151Y1526353D03*
X457151Y1544997D03*
X461876D03*
X466600D03*
X457151Y1548397D03*
X461876D03*
X466600D03*
X458369Y1602380D03*
X461769D03*
X464399Y1624292D03*
X455739D03*
X467799D03*
X458369Y1614292D03*
X461769D03*
X474325Y1523953D03*
X474876Y1526353D03*
X483774Y1523953D03*
X484325Y1526353D03*
X479049Y1523953D03*
X479600Y1526353D03*
X471325Y1544997D03*
X476049D03*
X480774D03*
X471325Y1548397D03*
X476049D03*
X480774D03*
X470429Y1602380D03*
X482489D03*
X473829D03*
X476459Y1624292D03*
X479859D03*
X470429Y1614292D03*
X482489D03*
X473829D03*
X497947Y1523953D03*
X498498Y1526353D03*
X488498Y1523953D03*
X489049Y1526353D03*
X493222Y1523953D03*
X493773Y1526353D03*
X499672Y1544997D03*
X485498D03*
X490223D03*
X494947D03*
X499672Y1548397D03*
X485498D03*
X490223D03*
X494947D03*
X494549Y1602380D03*
X485889D03*
X497949D03*
X488519Y1624292D03*
X491919D03*
X494549Y1614292D03*
X485889D03*
X497949D03*
X507947Y1526353D03*
X507396Y1523953D03*
X512120D03*
X512671Y1526353D03*
X503222D03*
X502671Y1523953D03*
X504396Y1544997D03*
X509120D03*
X513844D03*
X504396Y1548397D03*
X509120D03*
X513844D03*
X506609Y1602380D03*
X510009D03*
X500579Y1624292D03*
X512639D03*
X503979D03*
X506609Y1614292D03*
X510009D03*
X521569Y1523953D03*
X522120Y1526353D03*
X517396D03*
X516845Y1523953D03*
X518569Y1544997D03*
X523293D03*
X518569Y1548397D03*
X523293D03*
X518669Y1602380D03*
X522069D03*
X524699Y1624292D03*
X516039D03*
X528099D03*
X518669Y1614292D03*
X522069D03*
X530729Y1602380D03*
X542789D03*
X534129D03*
X536759Y1624292D03*
X540159D03*
X530729Y1614292D03*
X542789D03*
X534129D03*
X554849Y1602380D03*
X546189D03*
X558249D03*
X548819Y1624292D03*
X552219D03*
X554849Y1614292D03*
X546189D03*
X558249D03*
X566909Y1602380D03*
X570309D03*
X572939Y1624292D03*
X560879D03*
X564279D03*
X566909Y1614292D03*
X570309D03*
X588765Y1526353D03*
X588214Y1523953D03*
X578765D03*
X583489D03*
X579316Y1526353D03*
X584040D03*
X580489Y1544997D03*
X585213D03*
X580489Y1548397D03*
X585213D03*
X578969Y1602380D03*
X582369D03*
X584999Y1624292D03*
X576339D03*
X588399D03*
X578969Y1614292D03*
X582369D03*
X602387Y1523953D03*
X602938Y1526353D03*
X592938Y1523953D03*
X593489Y1526353D03*
X598213D03*
X597662Y1523953D03*
X589938Y1544997D03*
X594662D03*
X599387D03*
X604111D03*
X589938Y1548397D03*
X594662D03*
X599387D03*
X604111D03*
X591029Y1602380D03*
X603089D03*
X594429D03*
X597059Y1624292D03*
X600459D03*
X591029Y1614292D03*
X603089D03*
X594429D03*
X616560Y1523953D03*
X617111Y1526353D03*
X607111Y1523953D03*
X607662Y1526353D03*
X612387D03*
X611836Y1523953D03*
X608836Y1544997D03*
X613560D03*
X618285D03*
X608836Y1548397D03*
X613560D03*
X618285D03*
X615149Y1602380D03*
X606489D03*
X618549D03*
X609119Y1624292D03*
X612519D03*
X615149Y1614292D03*
X606489D03*
X618549D03*
X626009Y1523953D03*
X626560Y1526353D03*
X631284D03*
X630733Y1523953D03*
X621835Y1526353D03*
X621284Y1523953D03*
X627734Y1544997D03*
X632458D03*
X623009D03*
X627734Y1548397D03*
X632458D03*
X623009D03*
X627209Y1602380D03*
X630609D03*
X621179Y1624292D03*
X633239D03*
X624579D03*
X627209Y1614292D03*
X630609D03*
X642854Y760178D03*
Y756832D03*
X642804Y763525D03*
X644907Y1523953D03*
X640733Y1526353D03*
X640182Y1523953D03*
X635458D03*
X636009Y1526353D03*
X645458D03*
X637182Y1544997D03*
X641906D03*
X646631D03*
X637182Y1548397D03*
X641906D03*
X646631D03*
X639269Y1602380D03*
X642669D03*
X636639Y1624292D03*
X639269Y1614292D03*
X642669D03*
X651905Y763766D03*
X663496Y960966D03*
X657996D03*
X650182Y1526353D03*
X649631Y1523953D03*
X651355Y1544997D03*
Y1548397D03*
X664634Y449952D03*
X667996Y756832D03*
X672555D03*
Y760178D03*
X668046Y766871D03*
X667996Y763525D03*
X672505D03*
X668046Y770218D03*
X677055Y780257D03*
Y786950D03*
Y803682D03*
Y793643D03*
Y796989D03*
Y817068D03*
Y810375D03*
Y823761D03*
Y830454D03*
Y833800D03*
Y840493D03*
Y847186D03*
Y853879D03*
Y860572D03*
Y877304D03*
Y867265D03*
Y870611D03*
Y883997D03*
Y890690D03*
Y897383D03*
Y904076D03*
Y907423D03*
Y914115D03*
Y920808D03*
Y927501D03*
Y934194D03*
Y940887D03*
Y950926D03*
Y944234D03*
Y964312D03*
Y957619D03*
Y971005D03*
Y977698D03*
Y984391D03*
Y1001123D03*
Y997777D03*
Y991084D03*
Y1031241D03*
Y1037934D03*
Y1044627D03*
Y1058013D03*
Y1051320D03*
Y1074745D03*
Y1068052D03*
Y1064706D03*
Y1081438D03*
Y1088131D03*
Y1098171D03*
Y1104863D03*
Y1091478D03*
Y1111556D03*
Y1118249D03*
Y1134982D03*
Y1124942D03*
Y1128289D03*
Y1148367D03*
Y1141675D03*
Y1155060D03*
Y1161753D03*
Y1165100D03*
Y1171793D03*
Y1178486D03*
Y1185178D03*
Y1191871D03*
Y1208604D03*
Y1198564D03*
Y1201911D03*
Y1215297D03*
Y1221989D03*
Y1228682D03*
Y1235375D03*
Y1238722D03*
Y1245415D03*
Y1252108D03*
X695796Y430957D03*
Y437256D03*
Y468672D03*
X693197Y776911D03*
X681606Y763766D03*
X693197Y783604D03*
Y790297D03*
Y800336D03*
Y807029D03*
Y793643D03*
Y813722D03*
Y820415D03*
Y837147D03*
Y830454D03*
Y827108D03*
Y843840D03*
Y850533D03*
Y857226D03*
Y863919D03*
Y873958D03*
Y880651D03*
Y867265D03*
Y887344D03*
Y894037D03*
Y910769D03*
Y904076D03*
Y900730D03*
Y924155D03*
Y917462D03*
Y930848D03*
Y940887D03*
Y937541D03*
Y947580D03*
Y954273D03*
Y960966D03*
Y967659D03*
Y974352D03*
Y981045D03*
Y987737D03*
Y994430D03*
Y1001123D03*
Y1027895D03*
Y1034588D03*
Y1041281D03*
Y1047974D03*
Y1054667D03*
Y1061360D03*
Y1071399D03*
Y1064706D03*
Y1078092D03*
Y1088131D03*
Y1084785D03*
Y1094824D03*
Y1101517D03*
Y1108210D03*
Y1114903D03*
Y1131635D03*
Y1124942D03*
Y1121596D03*
Y1138328D03*
Y1145021D03*
Y1151714D03*
Y1161753D03*
Y1158407D03*
Y1168446D03*
Y1175139D03*
Y1181832D03*
Y1188525D03*
Y1205257D03*
Y1198564D03*
Y1195218D03*
Y1211950D03*
Y1218643D03*
Y1225336D03*
Y1235375D03*
Y1232029D03*
Y1242068D03*
Y1248761D03*
X698599Y115178D03*
X705686D03*
X702142D03*
X698599Y112678D03*
X705686D03*
X702142D03*
X695056D03*
Y115178D03*
X708395Y427807D03*
Y424657D03*
X705245D03*
Y427807D03*
X702095D03*
X708395Y434106D03*
X705245Y430957D03*
X702095Y434106D03*
X698946Y427807D03*
X705245Y437256D03*
X698946Y430957D03*
X705245Y434106D03*
X702095Y430957D03*
X705245Y446705D03*
X708395Y440405D03*
Y443555D03*
X702095Y446705D03*
X705245Y443555D03*
X702095Y437256D03*
Y440405D03*
Y443555D03*
X705245Y440405D03*
X708395Y437256D03*
X698946Y446705D03*
X708395D03*
X698946Y449854D03*
X708395Y462373D03*
Y449854D03*
X705245Y459223D03*
X702095Y456074D03*
Y459223D03*
X708395Y456074D03*
X705245Y462373D03*
X702095D03*
X705245Y456074D03*
X695796Y449854D03*
X708395Y459223D03*
Y465523D03*
X705245Y468672D03*
X702095D03*
X698946Y471822D03*
X702095Y465523D03*
X695796Y471822D03*
X708395Y478121D03*
X705245Y471822D03*
X695796Y465523D03*
X702095Y478121D03*
X705245Y474971D03*
X708395Y471822D03*
Y468672D03*
X705245Y465523D03*
X702095Y471822D03*
X698946Y465523D03*
X705245Y478121D03*
X702095Y474971D03*
X698946Y487570D03*
Y481271D03*
Y484420D03*
X705245Y481271D03*
X702095D03*
X695796Y484420D03*
X708395D03*
Y481271D03*
X697697Y756832D03*
X702256D03*
Y760178D03*
X697747Y766871D03*
X697697Y763525D03*
X702206D03*
X697747Y770218D03*
X706756Y1068052D03*
Y1064706D03*
X720993Y418358D03*
X717843D03*
Y421508D03*
X720993Y430957D03*
X711544D03*
X714694D03*
X717843Y434106D03*
X720993D03*
X717843Y430957D03*
X720993Y421508D03*
X711544Y434106D03*
X714694D03*
X720993Y424657D03*
X717843D03*
Y427807D03*
X714694Y424657D03*
Y427807D03*
X711544Y424657D03*
Y427807D03*
X720993D03*
X717843Y437256D03*
X720993D03*
X714694D03*
X711544D03*
Y443555D03*
X717843D03*
X714694Y446705D03*
Y440405D03*
X720993D03*
X711544D03*
X714694Y443555D03*
X711544Y446705D03*
Y459223D03*
X714694D03*
X717843Y462373D03*
Y456074D03*
Y449854D03*
X714694Y462373D03*
X711544D03*
X714694Y449854D03*
X711544D03*
X714694Y456074D03*
X711544D03*
X720993Y471822D03*
Y468672D03*
X711544Y478121D03*
X717843Y474971D03*
X724143Y471822D03*
X720993Y478121D03*
X717843D03*
X720993Y474971D03*
X714694Y465523D03*
X717843Y471822D03*
Y468672D03*
X714694Y471822D03*
X711544D03*
X714694Y468672D03*
X711544D03*
X720993Y465523D03*
X711544Y474971D03*
X714694Y478121D03*
Y474971D03*
X724143Y481271D03*
X711544Y465523D03*
X717843Y481271D03*
X714694D03*
X720993D03*
X711544D03*
X720993Y484420D03*
X711307Y763766D03*
X722898Y960966D03*
X717398D03*
X731208Y398737D03*
X733512Y418358D03*
X727292D03*
X724143D03*
X736661Y424657D03*
Y430957D03*
Y434106D03*
X733512D03*
Y421508D03*
Y424657D03*
Y430957D03*
X727292D03*
Y434106D03*
X724143Y430957D03*
X727292Y427807D03*
X736661D03*
X727292Y424657D03*
X724143Y434106D03*
Y421508D03*
X739811Y430957D03*
X724143Y427807D03*
Y424657D03*
X733512Y437256D03*
X727292Y440405D03*
X724143Y446705D03*
X736661D03*
X733512Y440405D03*
X736661D03*
X727292Y437256D03*
X724143Y440405D03*
Y437256D03*
X736661D03*
Y459223D03*
Y456074D03*
X733512D03*
Y449854D03*
X736661D03*
X727292Y456074D03*
X724143Y459223D03*
Y456074D03*
X727292Y449854D03*
X724143D03*
X727292Y471822D03*
X724143Y468672D03*
X727292D03*
X736661D03*
X724143Y474971D03*
X733512Y478121D03*
X724143Y465523D03*
X727292D03*
X733512D03*
X736661D03*
X733512Y474971D03*
Y468672D03*
X736661Y478121D03*
Y471822D03*
X724143Y478121D03*
X727292D03*
X733512Y471822D03*
X736661Y474971D03*
Y487570D03*
Y481271D03*
X733512D03*
X727292D03*
X724143Y487570D03*
X727292Y484420D03*
Y487570D03*
X727398Y756832D03*
X731957D03*
Y760178D03*
X727398Y763525D03*
X731462Y766871D03*
X731907Y763525D03*
X727448Y770218D03*
X736457Y1068052D03*
Y1064706D03*
X755559Y421508D03*
X739811Y424657D03*
Y427807D03*
X742961Y424657D03*
Y427807D03*
X746110Y424657D03*
Y427807D03*
X752409Y430957D03*
Y434106D03*
X749260D03*
X752409Y424657D03*
X749260D03*
X746110Y430957D03*
X749260D03*
X742961D03*
X752409Y427807D03*
X749260D03*
X739811Y434106D03*
X742961D03*
X746110D03*
X752409Y443555D03*
X739811Y437256D03*
X746110D03*
X742961D03*
X746110Y440405D03*
X749260Y437256D03*
X739811Y440405D03*
X742961Y443555D03*
Y446705D03*
X752409Y440405D03*
X749260D03*
Y446705D03*
X752409Y437256D03*
Y446705D03*
X746110D03*
Y443555D03*
X749260D03*
X742961Y459223D03*
Y462373D03*
Y456074D03*
Y449854D03*
X752409Y456074D03*
X749260Y449854D03*
X746110Y459223D03*
X752409Y462373D03*
Y459223D03*
X749260D03*
X746110Y456074D03*
Y449854D03*
Y462373D03*
X749260D03*
X752409Y449854D03*
X749260Y456074D03*
X742961Y474971D03*
Y468672D03*
X739811Y478121D03*
Y474971D03*
Y471822D03*
X749260D03*
X739811Y468672D03*
X749260D03*
Y474971D03*
X742961Y471822D03*
X749260Y478121D03*
X746110Y474971D03*
X752409Y468672D03*
X742961Y478121D03*
X746110Y468672D03*
X739811Y465523D03*
X752409Y478121D03*
Y471822D03*
Y465523D03*
X746110D03*
X749260D03*
X752409Y474971D03*
X746110Y478121D03*
Y471822D03*
X749260Y481271D03*
X742961Y484420D03*
X739811Y481271D03*
X746110Y484420D03*
X749260D03*
X752409Y487570D03*
X742961D03*
Y490070D03*
X746110Y481271D03*
X752409D03*
X742961D03*
X741007Y763766D03*
X752599Y960966D03*
X747099D03*
X755559Y418358D03*
X758709D03*
X761858D03*
X755559Y427807D03*
Y430957D03*
X758709Y427807D03*
Y430957D03*
X765008Y424657D03*
X755559D03*
X758709D03*
Y421508D03*
X761858Y424657D03*
X765008Y430957D03*
X755559Y434106D03*
X761858Y430957D03*
Y427807D03*
X758709Y434106D03*
X765008Y427807D03*
Y446705D03*
X758709D03*
X755559Y443555D03*
Y446705D03*
Y437256D03*
X758709Y440405D03*
X755559D03*
X758709Y443555D03*
X761858Y446705D03*
X755559Y449854D03*
Y459223D03*
X765008Y456074D03*
X758709Y465523D03*
X755559Y462373D03*
X758709Y459223D03*
Y462373D03*
Y456074D03*
Y449854D03*
X755559Y478121D03*
Y468672D03*
Y471822D03*
X758709D03*
X761858Y478121D03*
Y474971D03*
Y471822D03*
X758709Y474971D03*
X765008Y471822D03*
Y474971D03*
Y465523D03*
X758709Y478121D03*
X761858Y468672D03*
Y465523D03*
X765008Y468672D03*
X755559Y465523D03*
Y474971D03*
Y481271D03*
Y484420D03*
X765008Y481271D03*
X761858D03*
X758709D03*
X757099Y756832D03*
X761658D03*
Y760178D03*
X757149Y766871D03*
X757099Y763525D03*
X761608D03*
X757149Y770218D03*
X766158Y1068052D03*
Y1064706D03*
X770708Y763766D03*
X782300Y960966D03*
X776800D03*
X786800Y756832D03*
X791358Y760178D03*
Y756832D03*
X786850Y766871D03*
X786800Y763525D03*
X791308D03*
X786850Y770218D03*
X795858Y780257D03*
Y786950D03*
Y803682D03*
Y793643D03*
Y796989D03*
Y817068D03*
Y810375D03*
Y823761D03*
Y830454D03*
Y833800D03*
Y840493D03*
Y847186D03*
Y853879D03*
Y860572D03*
Y877304D03*
Y867265D03*
Y870611D03*
Y883997D03*
Y890690D03*
Y897383D03*
Y904076D03*
Y907423D03*
Y914115D03*
Y920808D03*
Y927501D03*
Y934194D03*
Y940887D03*
Y950926D03*
Y944234D03*
Y964312D03*
Y957619D03*
Y971005D03*
Y977698D03*
Y984391D03*
Y1001123D03*
Y997777D03*
Y991084D03*
Y1031241D03*
Y1037934D03*
Y1044627D03*
Y1058013D03*
Y1051320D03*
Y1074745D03*
Y1068052D03*
Y1064706D03*
Y1081438D03*
Y1088131D03*
Y1098171D03*
Y1104863D03*
Y1091478D03*
Y1111556D03*
Y1118249D03*
Y1134982D03*
Y1124942D03*
Y1128289D03*
Y1148367D03*
Y1141675D03*
Y1155060D03*
Y1161753D03*
Y1165100D03*
Y1171793D03*
Y1178486D03*
Y1185178D03*
Y1191871D03*
Y1208604D03*
Y1198564D03*
Y1201911D03*
Y1215297D03*
Y1221989D03*
Y1228682D03*
Y1235375D03*
Y1238722D03*
Y1245415D03*
Y1252108D03*
X812000Y776911D03*
X800409Y763765D03*
X812000Y783604D03*
Y790297D03*
Y800336D03*
Y807029D03*
Y793643D03*
Y813722D03*
Y820415D03*
Y837147D03*
Y830454D03*
Y827108D03*
Y843840D03*
Y850533D03*
Y857226D03*
Y863919D03*
Y873958D03*
Y880651D03*
Y867265D03*
Y887344D03*
Y894037D03*
Y910769D03*
Y904076D03*
Y900730D03*
Y924155D03*
Y917462D03*
Y930848D03*
Y940887D03*
Y937541D03*
Y947580D03*
Y954273D03*
Y960966D03*
Y967659D03*
Y974352D03*
Y981045D03*
Y987737D03*
Y994430D03*
Y1001123D03*
Y1027895D03*
Y1034588D03*
Y1041281D03*
Y1047974D03*
Y1054667D03*
Y1061360D03*
Y1071399D03*
Y1064706D03*
Y1078092D03*
Y1088131D03*
Y1084785D03*
Y1094824D03*
Y1101517D03*
Y1108210D03*
Y1114903D03*
Y1131635D03*
Y1124942D03*
Y1121596D03*
Y1138328D03*
Y1145021D03*
Y1151714D03*
Y1161753D03*
Y1158407D03*
Y1168446D03*
Y1175139D03*
Y1181832D03*
Y1188525D03*
Y1205257D03*
Y1198564D03*
Y1195218D03*
Y1211950D03*
Y1218643D03*
Y1225336D03*
Y1235375D03*
Y1232029D03*
Y1242068D03*
Y1248761D03*
X816500Y756832D03*
X816550Y770218D03*
X816500Y763525D03*
X998206Y196191D03*
X1000706D03*
X998206Y199735D03*
X1000706D03*
X998206Y206821D03*
X1000706D03*
X998206Y203278D03*
X1000706D03*
X1040965Y756831D03*
Y760177D03*
X1050015Y763765D03*
X1040915Y763524D03*
X1045465Y780256D03*
Y786949D03*
Y803681D03*
Y793642D03*
Y796988D03*
Y817067D03*
Y810374D03*
Y823760D03*
Y830453D03*
Y833799D03*
Y840492D03*
Y847185D03*
Y853878D03*
Y860571D03*
Y877303D03*
Y867264D03*
Y870610D03*
Y883996D03*
Y890689D03*
Y897382D03*
Y904075D03*
Y907422D03*
Y914114D03*
Y920807D03*
Y927500D03*
Y934193D03*
Y940886D03*
Y950925D03*
Y944233D03*
Y964311D03*
Y957618D03*
Y971004D03*
Y977697D03*
Y984390D03*
Y1001122D03*
Y997776D03*
Y991083D03*
Y1031240D03*
Y1037933D03*
Y1044626D03*
Y1058012D03*
Y1051319D03*
Y1074744D03*
Y1068051D03*
Y1064705D03*
Y1081437D03*
Y1088130D03*
Y1098170D03*
Y1104862D03*
Y1091477D03*
Y1111555D03*
Y1118248D03*
Y1134981D03*
Y1124941D03*
Y1128288D03*
Y1148366D03*
Y1141674D03*
Y1155059D03*
Y1161752D03*
Y1165099D03*
Y1171792D03*
Y1178485D03*
Y1185177D03*
Y1191870D03*
Y1208603D03*
Y1198563D03*
Y1201910D03*
Y1215296D03*
Y1221988D03*
Y1228681D03*
Y1235374D03*
Y1238721D03*
Y1245414D03*
Y1252107D03*
X1066107Y756831D03*
X1066157Y766870D03*
X1061607Y776910D03*
X1066107Y763524D03*
X1066157Y770217D03*
X1061607Y783603D03*
Y790296D03*
Y800335D03*
Y807028D03*
Y793642D03*
Y813721D03*
Y820414D03*
Y837146D03*
Y830453D03*
Y827107D03*
Y843839D03*
Y850532D03*
Y857225D03*
Y863918D03*
Y873957D03*
Y880650D03*
Y867264D03*
Y887343D03*
Y894036D03*
Y910768D03*
Y904075D03*
Y900729D03*
Y924154D03*
Y917461D03*
Y930847D03*
Y940886D03*
Y937540D03*
Y947579D03*
Y954272D03*
Y960965D03*
Y967658D03*
Y974351D03*
Y981044D03*
Y987736D03*
Y994429D03*
Y1001122D03*
Y1027894D03*
Y1034587D03*
Y1041280D03*
Y1047973D03*
Y1054666D03*
Y1061359D03*
Y1071398D03*
Y1064705D03*
Y1078091D03*
Y1088130D03*
Y1084784D03*
Y1094823D03*
Y1101516D03*
Y1108209D03*
Y1114902D03*
Y1131634D03*
Y1124941D03*
Y1121595D03*
Y1138327D03*
Y1145020D03*
Y1151713D03*
Y1161752D03*
Y1158406D03*
Y1168445D03*
Y1175138D03*
Y1181831D03*
Y1188524D03*
Y1205256D03*
Y1198563D03*
Y1195217D03*
Y1211949D03*
Y1218642D03*
Y1225335D03*
Y1235374D03*
Y1232028D03*
Y1242067D03*
Y1248760D03*
X1070666Y756831D03*
Y760177D03*
X1079716Y763765D03*
X1070616Y763524D03*
X1075166Y1068051D03*
Y1064705D03*
X1095808Y756831D03*
X1095858Y766870D03*
X1095808Y763524D03*
X1095858Y770217D03*
X1091308Y960965D03*
X1100366Y756831D03*
Y760177D03*
X1109416Y763765D03*
X1100316Y763524D03*
X1096808Y960965D03*
X1104866Y1068051D03*
Y1064705D03*
X1125508Y756831D03*
X1125558Y766870D03*
X1125508Y763524D03*
X1125558Y770217D03*
X1121008Y960965D03*
X1130067Y756831D03*
Y760177D03*
X1139117Y763765D03*
X1130017Y763524D03*
X1126508Y960965D03*
X1134567Y1068051D03*
Y1064705D03*
X1155209Y756831D03*
Y763524D03*
X1155259Y770217D03*
X1150709Y960965D03*
X1159768Y756831D03*
Y760177D03*
X1168818Y763765D03*
X1159718Y763524D03*
X1164268Y780256D03*
Y786949D03*
Y803681D03*
Y793642D03*
Y796988D03*
Y817067D03*
Y810374D03*
Y823760D03*
Y830453D03*
Y833799D03*
Y840492D03*
Y847185D03*
Y853878D03*
Y860571D03*
Y877303D03*
Y867264D03*
Y870610D03*
Y883996D03*
Y890689D03*
Y897382D03*
Y904075D03*
Y907422D03*
Y914114D03*
Y920807D03*
Y927500D03*
Y934193D03*
Y940886D03*
Y950925D03*
Y944233D03*
Y964311D03*
Y957618D03*
Y971004D03*
X1156209Y960965D03*
X1164268Y977697D03*
Y984390D03*
Y1001122D03*
Y997776D03*
Y991083D03*
Y1031240D03*
Y1037933D03*
Y1044626D03*
Y1058012D03*
Y1051319D03*
Y1074744D03*
Y1068051D03*
Y1064705D03*
Y1081437D03*
Y1088130D03*
Y1098170D03*
Y1104862D03*
Y1091477D03*
Y1111555D03*
Y1118248D03*
Y1134981D03*
Y1124941D03*
Y1128288D03*
Y1148366D03*
Y1141674D03*
Y1155059D03*
Y1161752D03*
Y1165099D03*
Y1171792D03*
Y1178485D03*
Y1185177D03*
Y1191870D03*
Y1208603D03*
Y1198563D03*
Y1201910D03*
Y1215296D03*
Y1221988D03*
Y1228681D03*
Y1235374D03*
Y1238721D03*
Y1245414D03*
Y1252107D03*
X1184910Y756831D03*
X1180410Y776910D03*
X1184910Y763524D03*
X1184960Y770217D03*
X1180410Y783603D03*
Y790296D03*
Y800335D03*
Y807028D03*
Y793642D03*
Y813721D03*
Y820414D03*
Y837146D03*
Y830453D03*
Y827107D03*
Y843839D03*
Y850532D03*
Y857225D03*
Y863918D03*
Y873957D03*
Y880650D03*
Y867264D03*
Y887343D03*
Y894036D03*
Y910768D03*
Y904075D03*
Y900729D03*
Y924154D03*
Y917461D03*
Y930847D03*
Y940886D03*
Y937540D03*
Y947579D03*
Y954272D03*
Y960965D03*
Y967658D03*
Y974351D03*
Y981044D03*
Y987736D03*
Y994429D03*
Y1001122D03*
Y1027894D03*
Y1034587D03*
Y1041280D03*
Y1047973D03*
Y1054666D03*
Y1061359D03*
Y1071398D03*
Y1064705D03*
Y1078091D03*
Y1088130D03*
Y1084784D03*
Y1094823D03*
Y1101516D03*
Y1108209D03*
Y1114902D03*
Y1131634D03*
Y1124941D03*
Y1121595D03*
Y1138327D03*
Y1145020D03*
Y1151713D03*
Y1161752D03*
Y1158406D03*
Y1168445D03*
Y1175138D03*
Y1181831D03*
Y1188524D03*
Y1205256D03*
Y1198563D03*
Y1195217D03*
Y1211949D03*
Y1218642D03*
Y1225335D03*
Y1235374D03*
Y1232028D03*
Y1242067D03*
Y1248760D03*
X1189469Y760177D03*
Y756831D03*
X1198519Y763765D03*
X1188805Y766870D03*
X1189419Y763524D03*
X1194403Y1556953D03*
X1199678Y1559353D03*
X1194954D03*
X1199127Y1556953D03*
X1196127Y1577997D03*
Y1581397D03*
X1196039Y1657292D03*
X1199439D03*
X1214600Y759562D03*
X1205448Y769914D03*
X1214661Y766870D03*
X1214611Y763524D03*
X1214841Y772277D03*
X1210111Y960965D03*
X1203682D03*
X1208576Y1556953D03*
X1204403Y1559353D03*
X1209127D03*
X1203852Y1556953D03*
X1213300D03*
X1213851Y1559353D03*
X1200851Y1577997D03*
X1205576D03*
X1210300D03*
X1215025D03*
X1200851Y1581397D03*
X1205576D03*
X1210300D03*
X1215025D03*
X1202069Y1635380D03*
X1214129D03*
X1205469D03*
X1202069Y1647292D03*
X1214129D03*
X1205469D03*
X1208099Y1657292D03*
X1211499D03*
X1218025Y1556953D03*
X1218576Y1559353D03*
X1227474Y1556953D03*
X1228025Y1559353D03*
X1222749Y1556953D03*
X1223300Y1559353D03*
X1219749Y1577997D03*
X1224474D03*
X1229198D03*
X1219749Y1581397D03*
X1224474D03*
X1229198D03*
X1226189Y1635380D03*
X1217529D03*
X1229589D03*
X1226189Y1647292D03*
X1217529D03*
X1229589D03*
X1220159Y1657292D03*
X1223559D03*
X1241647Y1556953D03*
X1242198Y1559353D03*
X1232198Y1556953D03*
X1232749Y1559353D03*
X1236922Y1556953D03*
X1237473Y1559353D03*
X1243372Y1577997D03*
X1233923D03*
X1238647D03*
X1243372Y1581397D03*
X1233923D03*
X1238647D03*
X1238249Y1635380D03*
X1241649D03*
X1238249Y1647292D03*
X1241649D03*
X1232219Y1657292D03*
X1244279D03*
X1235619D03*
X1251647Y1559353D03*
X1251096Y1556953D03*
X1255820D03*
X1256371Y1559353D03*
X1246371Y1556953D03*
X1246922Y1559353D03*
X1248096Y1577997D03*
X1252820D03*
X1257544D03*
X1248096Y1581397D03*
X1252820D03*
X1257544D03*
X1250309Y1635380D03*
X1253709D03*
X1250309Y1647292D03*
X1253709D03*
X1256339Y1657292D03*
X1247679D03*
X1259739D03*
X1265269Y1556953D03*
X1265820Y1559353D03*
X1261096D03*
X1260545Y1556953D03*
X1262269Y1577997D03*
X1266993D03*
X1262269Y1581397D03*
X1266993D03*
X1262369Y1635380D03*
X1274429D03*
X1265769D03*
X1262369Y1647292D03*
X1274429D03*
X1265769D03*
X1268399Y1657292D03*
X1271799D03*
X1286489Y1635380D03*
X1277829D03*
X1289889D03*
X1286489Y1647292D03*
X1277829D03*
X1289889D03*
X1280459Y1657292D03*
X1283859D03*
X1298549Y1635380D03*
X1301949D03*
X1298549Y1647292D03*
X1301949D03*
X1292519Y1657292D03*
X1304579D03*
X1295919D03*
X1310609Y1635380D03*
X1314009D03*
X1310609Y1647292D03*
X1314009D03*
X1316639Y1657292D03*
X1320039D03*
X1307979D03*
X1332465Y1559353D03*
X1331914Y1556953D03*
X1322465D03*
X1327189D03*
X1323016Y1559353D03*
X1327740D03*
X1324189Y1577997D03*
X1328913D03*
X1333638D03*
X1324189Y1581397D03*
X1328913D03*
X1333638D03*
X1322669Y1635380D03*
X1334729D03*
X1326069D03*
X1322669Y1647292D03*
X1334729D03*
X1326069D03*
X1328699Y1657292D03*
X1332099D03*
X1346087Y1556953D03*
X1346638Y1559353D03*
X1336638Y1556953D03*
X1337189Y1559353D03*
X1341913D03*
X1341362Y1556953D03*
X1338362Y1577997D03*
X1343087D03*
X1347811D03*
X1338362Y1581397D03*
X1343087D03*
X1347811D03*
X1346789Y1635380D03*
X1338129D03*
X1346789Y1647292D03*
X1338129D03*
X1340759Y1657292D03*
X1344159D03*
X1360260Y1556953D03*
X1360811Y1559353D03*
X1350811Y1556953D03*
X1351362Y1559353D03*
X1356087D03*
X1355536Y1556953D03*
X1352536Y1577997D03*
X1357260D03*
X1361985D03*
X1352536Y1581397D03*
X1357260D03*
X1361985D03*
X1358849Y1635380D03*
X1350189D03*
X1362249D03*
X1358849Y1647292D03*
X1350189D03*
X1362249D03*
X1352819Y1657292D03*
X1356219D03*
X1369709Y1556953D03*
X1370260Y1559353D03*
X1379158Y1556953D03*
X1374984Y1559353D03*
X1374433Y1556953D03*
X1365535Y1559353D03*
X1364984Y1556953D03*
X1371434Y1577997D03*
X1376158D03*
X1366709D03*
X1371434Y1581397D03*
X1376158D03*
X1366709D03*
X1370909Y1635380D03*
X1374309D03*
X1370909Y1647292D03*
X1374309D03*
X1364879Y1657292D03*
X1376939D03*
X1368279D03*
X1388607Y1556953D03*
X1384433Y1559353D03*
X1383882Y1556953D03*
X1379709Y1559353D03*
X1393882D03*
X1389158D03*
X1393331Y1556953D03*
X1380882Y1577997D03*
X1385606D03*
X1390331D03*
X1380882Y1581397D03*
X1385606D03*
X1390331D03*
X1382969Y1635380D03*
X1386369D03*
X1382969Y1647292D03*
X1386369D03*
X1380339Y1657292D03*
X1395055Y1577997D03*
Y1581397D03*
X1458577Y1556953D03*
X1468577Y1559353D03*
X1463852D03*
X1459128D03*
X1463301Y1556953D03*
X1468026D03*
X1460301Y1577997D03*
X1465025D03*
X1460301Y1581397D03*
X1465025D03*
X1466243Y1635380D03*
Y1647292D03*
X1460213Y1657292D03*
X1463613D03*
X1482199Y1556953D03*
X1482750Y1559353D03*
X1472750Y1556953D03*
X1473301Y1559353D03*
X1477474Y1556953D03*
X1478025Y1559353D03*
X1469750Y1577997D03*
X1474474D03*
X1479199D03*
X1483923D03*
X1469750Y1581397D03*
X1474474D03*
X1479199D03*
X1483923D03*
X1478303Y1635380D03*
X1469643D03*
X1481703D03*
X1478303Y1647292D03*
X1469643D03*
X1481703D03*
X1472273Y1657292D03*
X1475673D03*
X1496372Y1556953D03*
X1491648D03*
X1496923Y1559353D03*
X1492199D03*
X1486923Y1556953D03*
X1487474Y1559353D03*
X1488648Y1577997D03*
X1493372D03*
X1498097D03*
X1488648Y1581397D03*
X1493372D03*
X1498097D03*
X1490363Y1635380D03*
X1493763D03*
X1490363Y1647292D03*
X1493763D03*
X1484333Y1657292D03*
X1496393D03*
X1487733D03*
X1505821Y1556953D03*
X1506372Y1559353D03*
X1511096D03*
X1510545Y1556953D03*
X1501096D03*
X1501647Y1559353D03*
X1507546Y1577997D03*
X1512270D03*
X1502821D03*
X1507546Y1581397D03*
X1512270D03*
X1502821D03*
X1502423Y1635380D03*
X1505823D03*
X1502423Y1647292D03*
X1505823D03*
X1508453Y1657292D03*
X1499793D03*
X1511853D03*
X1515821Y1559353D03*
X1515270Y1556953D03*
X1519994D03*
X1520545Y1559353D03*
X1525270D03*
X1524719Y1556953D03*
X1516994Y1577997D03*
X1521718D03*
X1526443D03*
X1516994Y1581397D03*
X1521718D03*
X1526443D03*
X1514483Y1635380D03*
X1526543D03*
X1517883D03*
X1514483Y1647292D03*
X1526543D03*
X1517883D03*
X1520513Y1657292D03*
X1523913D03*
X1529443Y1556953D03*
X1529994Y1559353D03*
X1531167Y1577997D03*
Y1581397D03*
X1538603Y1635380D03*
X1529943D03*
X1542003D03*
X1538603Y1647292D03*
X1529943D03*
X1542003D03*
X1532573Y1657292D03*
X1535973D03*
X1550663Y1635380D03*
X1554063D03*
X1550663Y1647292D03*
X1554063D03*
X1544633Y1657292D03*
X1556693D03*
X1548033D03*
X1562723Y1635380D03*
X1566123D03*
X1562723Y1647292D03*
X1566123D03*
X1568753Y1657292D03*
X1560093D03*
X1572153D03*
X1586639Y1556953D03*
X1587190Y1559353D03*
X1588363Y1577997D03*
Y1581397D03*
X1586843Y1635380D03*
X1574783D03*
X1578183D03*
X1586843Y1647292D03*
X1574783D03*
X1578183D03*
X1580813Y1657292D03*
X1584213D03*
X1600812Y1556953D03*
X1596639Y1559353D03*
X1596088Y1556953D03*
X1601363Y1559353D03*
X1591363Y1556953D03*
X1591914Y1559353D03*
X1593087Y1577997D03*
X1597812D03*
X1602536D03*
X1593087Y1581397D03*
X1597812D03*
X1602536D03*
X1598903Y1635380D03*
X1590243D03*
X1602303D03*
X1598903Y1647292D03*
X1590243D03*
X1602303D03*
X1592873Y1657292D03*
X1596273D03*
X1610261Y1556953D03*
X1610812Y1559353D03*
X1606087D03*
X1605536Y1556953D03*
X1614985D03*
X1615536Y1559353D03*
X1607261Y1577997D03*
X1611985D03*
X1616710D03*
X1607261Y1581397D03*
X1611985D03*
X1616710D03*
X1610963Y1635380D03*
X1614363D03*
X1610963Y1647292D03*
X1614363D03*
X1604933Y1657292D03*
X1616993D03*
X1608333D03*
X1618996Y760177D03*
Y756831D03*
X1618946Y763524D03*
X1624434Y1556953D03*
X1624985Y1559353D03*
X1620261D03*
X1619710Y1556953D03*
X1629709Y1559353D03*
X1629158Y1556953D03*
X1621434Y1577997D03*
X1626159D03*
X1630883D03*
X1621434Y1581397D03*
X1626159D03*
X1630883D03*
X1623023Y1635380D03*
X1626423D03*
X1623023Y1647292D03*
X1626423D03*
X1629053Y1657292D03*
X1620393D03*
X1632453D03*
X1644138Y756831D03*
Y763524D03*
X1644188Y770217D03*
X1639638Y960965D03*
X1634138D03*
X1633883Y1556953D03*
X1634434Y1559353D03*
X1643332Y1556953D03*
X1643883Y1559353D03*
X1639158D03*
X1638607Y1556953D03*
X1635608Y1577997D03*
X1640332D03*
X1645056D03*
X1635608Y1581397D03*
X1640332D03*
X1645056D03*
X1635083Y1635380D03*
X1647143D03*
X1638483D03*
X1635083Y1647292D03*
X1647143D03*
X1638483D03*
X1641113Y1657292D03*
X1644513D03*
X1648697Y760177D03*
Y756831D03*
X1657747Y763765D03*
X1648647Y766870D03*
Y763524D03*
X1653197Y780256D03*
Y786949D03*
Y803681D03*
Y793642D03*
Y796988D03*
Y817067D03*
Y810374D03*
Y823760D03*
Y830453D03*
Y833799D03*
Y840492D03*
Y847185D03*
Y853878D03*
Y860571D03*
Y877303D03*
Y867264D03*
Y870610D03*
Y883996D03*
Y890689D03*
Y897382D03*
Y904075D03*
Y907422D03*
Y914114D03*
Y920807D03*
Y927500D03*
Y934193D03*
Y940886D03*
Y950925D03*
Y944233D03*
Y964311D03*
Y957618D03*
Y971004D03*
Y977697D03*
Y984390D03*
Y1001122D03*
Y997776D03*
Y991083D03*
Y1031240D03*
Y1037933D03*
Y1044626D03*
Y1058012D03*
Y1051319D03*
Y1074744D03*
Y1068051D03*
Y1064705D03*
Y1081437D03*
Y1088130D03*
Y1098170D03*
Y1104862D03*
Y1091477D03*
Y1111555D03*
Y1118248D03*
Y1134981D03*
Y1124941D03*
Y1128288D03*
Y1148366D03*
Y1141674D03*
Y1155059D03*
Y1161752D03*
Y1165099D03*
Y1171792D03*
Y1178485D03*
Y1185177D03*
Y1191870D03*
Y1208603D03*
Y1198563D03*
Y1201910D03*
Y1215296D03*
Y1221988D03*
Y1228681D03*
Y1235374D03*
Y1238721D03*
Y1245414D03*
Y1252107D03*
X1652781Y1556953D03*
X1648607Y1559353D03*
X1648056Y1556953D03*
X1658056Y1559353D03*
X1653332D03*
X1657505Y1556953D03*
X1649780Y1577997D03*
X1654505D03*
X1659229D03*
X1649780Y1581397D03*
X1654505D03*
X1659229D03*
X1650543Y1635380D03*
Y1647292D03*
X1673839Y756831D03*
X1669339Y776910D03*
X1673839Y763524D03*
X1673889Y770217D03*
X1669339Y783603D03*
Y790296D03*
Y800335D03*
Y807028D03*
Y793642D03*
Y813721D03*
Y820414D03*
Y837146D03*
Y830453D03*
Y827107D03*
Y843839D03*
Y850532D03*
Y857225D03*
Y863918D03*
Y873957D03*
Y880650D03*
Y867264D03*
Y887343D03*
Y894036D03*
Y910768D03*
Y904075D03*
Y900729D03*
Y924154D03*
Y917461D03*
Y930847D03*
Y940886D03*
Y937540D03*
Y947579D03*
Y954272D03*
Y960965D03*
Y967658D03*
Y974351D03*
Y981044D03*
Y987736D03*
Y994429D03*
Y1001122D03*
Y1027894D03*
Y1034587D03*
Y1041280D03*
Y1047973D03*
Y1054666D03*
Y1061359D03*
Y1071398D03*
Y1064705D03*
Y1078091D03*
Y1088130D03*
Y1084784D03*
Y1094823D03*
Y1101516D03*
Y1108209D03*
Y1114902D03*
Y1131634D03*
Y1124941D03*
Y1121595D03*
Y1138327D03*
Y1145020D03*
Y1151713D03*
Y1161752D03*
Y1158406D03*
Y1168445D03*
Y1175138D03*
Y1181831D03*
Y1188524D03*
Y1205256D03*
Y1198563D03*
Y1195217D03*
Y1211949D03*
Y1218642D03*
Y1225335D03*
Y1235374D03*
Y1232028D03*
Y1242067D03*
Y1248760D03*
X1678398Y760177D03*
Y756831D03*
X1687448Y763765D03*
X1678348Y766870D03*
Y763524D03*
X1682898Y1068051D03*
Y1064705D03*
X1703540Y756831D03*
X1703590Y766870D03*
X1703540Y763524D03*
X1703590Y770217D03*
X1699040Y960965D03*
X1693540D03*
X1708099Y760177D03*
Y756831D03*
X1717149Y763765D03*
X1708049Y763524D03*
X1712599Y1068051D03*
Y1064705D03*
X1736986Y109723D03*
Y112223D03*
X1733241Y756831D03*
X1733727Y766870D03*
X1733241Y763524D03*
X1733291Y770217D03*
X1728741Y960965D03*
X1723241D03*
X1740529Y112223D03*
Y109723D03*
X1744072Y112223D03*
Y109723D03*
X1747616Y112223D03*
Y109723D03*
X1737800Y756831D03*
Y760177D03*
X1746850Y763765D03*
X1737750Y763524D03*
X1742300Y1068051D03*
Y1064705D03*
X1762942Y756831D03*
X1762992Y766870D03*
X1762942Y763524D03*
X1762992Y770217D03*
X1758442Y960965D03*
X1752942D03*
X1767500Y760177D03*
Y756831D03*
X1767450Y763524D03*
X1772000Y780256D03*
Y786949D03*
Y803681D03*
Y793642D03*
Y796988D03*
Y817067D03*
Y810374D03*
Y823760D03*
Y830453D03*
Y833799D03*
Y840492D03*
Y847185D03*
Y853878D03*
Y860571D03*
Y877303D03*
Y867264D03*
Y870610D03*
Y883996D03*
Y890689D03*
Y897382D03*
Y904075D03*
Y907422D03*
Y914114D03*
Y920807D03*
Y927500D03*
Y934193D03*
Y940886D03*
Y950925D03*
Y944233D03*
Y964311D03*
Y957618D03*
Y971004D03*
Y977697D03*
Y984390D03*
Y1001122D03*
Y997776D03*
Y991083D03*
Y1031240D03*
Y1037933D03*
Y1044626D03*
Y1058012D03*
Y1051319D03*
Y1074744D03*
Y1068051D03*
Y1064705D03*
Y1081437D03*
Y1088130D03*
Y1098170D03*
Y1104862D03*
Y1091477D03*
Y1111555D03*
Y1118248D03*
Y1134981D03*
Y1124941D03*
Y1128288D03*
Y1148366D03*
Y1141674D03*
Y1155059D03*
Y1161752D03*
Y1165099D03*
Y1171792D03*
Y1178485D03*
Y1185177D03*
Y1191870D03*
Y1208603D03*
Y1198563D03*
Y1201910D03*
Y1215296D03*
Y1221988D03*
Y1228681D03*
Y1235374D03*
Y1238721D03*
Y1245414D03*
Y1252107D03*
X1792642Y756831D03*
X1788142Y776910D03*
X1792642Y763524D03*
X1792692Y770217D03*
X1788142Y783603D03*
Y790296D03*
Y800335D03*
Y807028D03*
Y793642D03*
Y813721D03*
Y820414D03*
Y837146D03*
Y830453D03*
Y827107D03*
Y843839D03*
Y850532D03*
Y857225D03*
Y863918D03*
Y873957D03*
Y880650D03*
Y867264D03*
Y887343D03*
Y894036D03*
Y910768D03*
Y904075D03*
Y900729D03*
Y924154D03*
Y917461D03*
Y930847D03*
Y940886D03*
Y937540D03*
Y947579D03*
Y954272D03*
Y960965D03*
Y967658D03*
Y974351D03*
Y981044D03*
Y987736D03*
Y994429D03*
Y1001122D03*
Y1027894D03*
Y1034587D03*
Y1041280D03*
Y1047973D03*
Y1054666D03*
Y1061359D03*
Y1071398D03*
Y1064705D03*
Y1078091D03*
Y1088130D03*
Y1084784D03*
Y1094823D03*
Y1101516D03*
Y1108209D03*
Y1114902D03*
Y1131634D03*
Y1124941D03*
Y1121595D03*
Y1138327D03*
Y1145020D03*
Y1151713D03*
Y1161752D03*
Y1158406D03*
Y1168445D03*
Y1175138D03*
Y1181831D03*
Y1188524D03*
Y1205256D03*
Y1198563D03*
Y1195217D03*
Y1211949D03*
Y1218642D03*
Y1225335D03*
Y1235374D03*
Y1232028D03*
Y1242067D03*
Y1248760D03*
G54D43*
X373673Y-28871D03*
Y-18871D03*
D03*
Y-8871D03*
X398673Y-28871D03*
Y-18871D03*
D03*
Y-8871D03*
X718093Y-28871D03*
Y-18871D03*
D03*
Y-8871D03*
X743093Y-28871D03*
Y-18871D03*
D03*
Y-8871D03*
X825152Y-35011D03*
Y-25011D03*
Y-15011D03*
Y-25011D03*
Y-15011D03*
Y-5011D03*
D03*
Y4989D03*
Y14989D03*
D03*
Y4989D03*
Y24989D03*
X850152Y-35011D03*
Y-25011D03*
Y-15011D03*
Y-25011D03*
Y-15011D03*
Y-5011D03*
D03*
Y4989D03*
Y14989D03*
D03*
Y4989D03*
Y24989D03*
X1169572Y-35011D03*
Y-15011D03*
Y-25011D03*
D03*
Y-15011D03*
Y-5011D03*
D03*
Y4989D03*
Y14989D03*
Y4989D03*
Y14989D03*
Y24989D03*
X1194572Y-35011D03*
Y-15011D03*
Y-25011D03*
D03*
Y-15011D03*
Y-5011D03*
D03*
Y4989D03*
Y14989D03*
Y4989D03*
Y14989D03*
Y24989D03*
X1228672Y-35011D03*
Y-25011D03*
Y-15011D03*
Y-25011D03*
Y-15011D03*
Y-5011D03*
D03*
Y4989D03*
Y14989D03*
D03*
Y4989D03*
Y24989D03*
X1253672Y-35011D03*
Y-25011D03*
Y-15011D03*
Y-25011D03*
Y-15011D03*
Y-5011D03*
D03*
Y4989D03*
Y14989D03*
D03*
Y4989D03*
Y24989D03*
X1428431Y-35011D03*
Y-15011D03*
Y-25011D03*
D03*
Y-15011D03*
Y-5011D03*
D03*
Y4989D03*
Y14989D03*
Y4989D03*
Y14989D03*
Y24989D03*
X1453431Y-35011D03*
Y-15011D03*
Y-25011D03*
D03*
Y-15011D03*
Y-5011D03*
D03*
Y4989D03*
Y14989D03*
Y4989D03*
Y14989D03*
Y24989D03*
X1521966Y-29212D03*
D03*
Y-39212D03*
Y-19212D03*
X1546966Y-29212D03*
D03*
Y-39212D03*
Y-19212D03*
X1721725Y-29212D03*
Y-39212D03*
Y-29212D03*
Y-19212D03*
X1746725Y-29212D03*
Y-39212D03*
Y-29212D03*
Y-19212D03*
G54D54*
X793879Y194881D03*
X789942Y204724D03*
X793879Y214567D03*
X805690Y188976D03*
Y220472D03*
X817501Y194881D03*
X821438Y204724D03*
X817501Y214567D03*
X828390Y1420331D03*
X841240Y1407481D03*
X832154Y1411245D03*
Y1429417D03*
X841240Y1433181D03*
X850326Y1411245D03*
Y1429417D03*
X854090Y1420331D03*
X1007154Y1411245D03*
X1003390Y1420331D03*
X1007154Y1429417D03*
X1016240Y1407481D03*
Y1433181D03*
X1025326Y1411245D03*
Y1429417D03*
X1029090Y1420331D03*
X1045848Y194881D03*
X1041911Y204724D03*
X1045848Y214567D03*
X1057659Y188976D03*
Y220472D03*
X1069470Y194881D03*
X1073407Y204724D03*
X1069470Y214567D03*
G54D10*
X3001Y61178D03*
Y127178D03*
Y149178D03*
Y171178D03*
Y193178D03*
Y215178D03*
Y237178D03*
Y259178D03*
Y281178D03*
Y303178D03*
X10875Y323721D03*
Y345721D03*
Y367721D03*
Y389721D03*
Y411721D03*
Y433721D03*
Y455721D03*
Y477721D03*
Y499721D03*
Y521721D03*
X20587Y523970D03*
X16342Y516951D03*
X16512Y533155D03*
X10875Y543721D03*
Y565721D03*
Y587721D03*
Y609721D03*
Y653721D03*
Y675721D03*
Y697721D03*
Y719721D03*
Y741721D03*
Y763721D03*
Y785721D03*
Y807721D03*
Y829721D03*
Y851721D03*
Y873721D03*
Y895721D03*
Y917721D03*
Y939721D03*
Y961721D03*
Y983721D03*
Y1005721D03*
Y1027721D03*
Y1049721D03*
Y1071721D03*
Y1093721D03*
Y1115721D03*
Y1137721D03*
Y1159721D03*
Y1181721D03*
Y1203721D03*
Y1225721D03*
Y1247721D03*
Y1269721D03*
Y1291721D03*
Y1445721D03*
Y1467721D03*
Y1489721D03*
Y1511721D03*
Y1533721D03*
Y1555721D03*
Y1577721D03*
X33184Y523285D03*
X36402Y528675D03*
X33257Y540370D03*
X26887Y541805D03*
X35133Y1603396D03*
X35167Y1610521D03*
X28592Y1617961D03*
X35233Y1623196D03*
X28592Y1639961D03*
Y1661961D03*
Y1683961D03*
X44600Y280357D03*
X50500Y311100D03*
X47602Y1622414D03*
X51333Y1640996D03*
X54584Y8335D03*
Y30335D03*
X58633Y1641388D03*
X85133Y1616396D03*
Y1620896D03*
Y1625396D03*
X85167Y1629905D03*
X101939Y1657742D03*
Y1662728D03*
X120891Y521216D03*
X144610Y429560D03*
X163113Y1486190D03*
X160513Y1479500D03*
Y1484280D03*
X165713Y1479500D03*
Y1484280D03*
X160513Y1501300D03*
Y1506080D03*
X165713D03*
X163113Y1507982D03*
X165713Y1501300D03*
X173488Y1510800D03*
Y1514420D03*
Y1518040D03*
X224055Y127146D03*
X262886Y147391D03*
X274201Y579478D03*
X280621Y1486682D03*
X291175Y1486190D03*
X288575Y1484280D03*
Y1479500D03*
X280621Y1500082D03*
X288575Y1506080D03*
Y1501300D03*
X291175Y1507990D03*
X301747Y121469D03*
Y127469D03*
Y124469D03*
X293775Y1484280D03*
Y1479500D03*
Y1506080D03*
Y1501300D03*
X304606Y1546333D03*
X297323Y1659772D03*
X311754Y121472D03*
Y124472D03*
Y127472D03*
X311476Y1552567D03*
X307255Y1649750D03*
X326475Y182855D03*
X349676Y276708D03*
X349695Y286712D03*
X380181Y236674D03*
X390461Y270694D03*
Y267694D03*
Y275194D03*
X387184Y494382D03*
X390082Y1549178D03*
X404743Y494451D03*
X408683Y1486682D03*
Y1500082D03*
X425555Y92014D03*
Y82014D03*
X412715Y254165D03*
X423730Y249570D03*
X412715Y262165D03*
Y270165D03*
X418543Y494374D03*
X418918Y1006025D03*
Y1013505D03*
Y1009765D03*
Y1024726D03*
Y1020986D03*
Y1028466D03*
Y1017245D03*
X415318Y1032206D03*
X424686Y1484280D03*
Y1479500D03*
Y1506080D03*
Y1501300D03*
X431299Y204145D03*
X432343Y494297D03*
X427286Y1486190D03*
X429886Y1484280D03*
Y1479500D03*
Y1506080D03*
Y1501300D03*
X427286Y1507990D03*
X438732Y1546977D03*
X444090Y116007D03*
X443400Y247880D03*
X448852Y283318D03*
X441159Y1055141D03*
X447587Y1552567D03*
X468228Y70016D03*
X457931Y212703D03*
X465699Y282833D03*
X469323Y306273D03*
X462093Y310123D03*
X467943Y311563D03*
X465153Y310123D03*
X467893Y308643D03*
X458873Y310173D03*
X455813D03*
X462365Y1006025D03*
Y1009765D03*
Y1013505D03*
Y1020986D03*
Y1028466D03*
Y1024726D03*
Y1017245D03*
Y1032206D03*
X462500Y1733500D03*
X480323Y291023D03*
X474691Y306073D03*
X471743Y304923D03*
X473643Y308683D03*
X471003Y311563D03*
X470953Y308643D03*
X484063Y313956D03*
X498776Y209285D03*
Y213285D03*
X500269Y225071D03*
X488908Y242754D03*
X503161Y149895D03*
X514418Y141171D03*
X515151Y220166D03*
X501718Y240558D03*
X508723Y280721D03*
X510223Y289035D03*
X507698D03*
Y297090D03*
X510223D03*
X507698Y305145D03*
X510223D03*
X510606Y314124D03*
X508081D03*
X523831Y95445D03*
Y102931D03*
X519579Y207435D03*
X530418Y141171D03*
X538567Y294777D03*
X542813Y319173D03*
X544794Y1486682D03*
Y1500082D03*
X549800Y147000D03*
X553300Y164500D03*
X556811Y152742D03*
X552699Y291833D03*
X556323Y315273D03*
X558743Y313923D03*
X545873Y319173D03*
X549093Y319123D03*
X558003Y320563D03*
X554943D03*
X552153Y319123D03*
X554893Y317643D03*
X557953D03*
X555348Y1486190D03*
X552748Y1484280D03*
Y1479500D03*
X557948Y1484280D03*
Y1479500D03*
X552748Y1506080D03*
Y1501300D03*
X557948Y1506080D03*
Y1501300D03*
X555348Y1507990D03*
X568472Y149226D03*
X563951Y160644D03*
X567323Y300023D03*
X561691Y315073D03*
X560643Y317683D03*
X568573Y321993D03*
X568779Y1546333D03*
X585685Y178125D03*
X578172Y231393D03*
X587140Y257630D03*
X575524Y261171D03*
X575649Y1552567D03*
X599678Y175534D03*
X595723Y289721D03*
X594698Y298035D03*
X597223D03*
X594698Y314145D03*
X597223D03*
X594698Y306090D03*
X597223D03*
Y322200D03*
X594698D03*
X600520Y401728D03*
X616654Y1382864D03*
X633805Y302289D03*
X642816Y574185D03*
X634529Y674890D03*
X640129D03*
X643649Y674781D03*
X649936Y574185D03*
X660062Y672761D03*
X654676Y674806D03*
X654005Y1548999D03*
X670000Y465844D03*
X672856Y1486682D03*
Y1500082D03*
X719195Y172873D03*
Y177865D03*
X714203Y172873D03*
Y177865D03*
X719195Y196373D03*
X714203D03*
X719195Y184873D03*
Y189865D03*
X714203Y184873D03*
Y189865D03*
Y208207D03*
X719195D03*
Y201365D03*
X714203D03*
Y213199D03*
X719195D03*
X733380Y1577231D03*
X727780Y1582361D03*
Y1577231D03*
X733380Y1587491D03*
X727780D03*
X736998Y1597463D03*
X730998D03*
X733998D03*
X736998Y1594463D03*
X730998D03*
X733998D03*
X736998Y1600463D03*
X730998D03*
X733998D03*
Y1603663D03*
X736998D03*
X733998Y1606663D03*
X736998D03*
X730998Y1603663D03*
Y1606663D03*
X744911Y166887D03*
X738880Y1582361D03*
Y1577231D03*
Y1587491D03*
X745998Y1597463D03*
X742998D03*
X745998Y1594463D03*
X742998D03*
X739998Y1597463D03*
Y1594463D03*
X745998Y1600463D03*
X742998D03*
X739998D03*
X745998Y1603663D03*
X742998D03*
X739998D03*
X745998Y1606663D03*
X742998D03*
X739998D03*
X749261Y1628208D03*
X754286Y266319D03*
X754291Y269322D03*
X756692Y278942D03*
X765285Y276374D03*
X761510Y1638434D03*
X762030Y1668583D03*
X755408Y1672381D03*
X757557Y1684444D03*
X773457Y249792D03*
X774485Y286879D03*
X779977Y1577233D03*
Y1582363D03*
Y1587493D03*
X779550Y1594533D03*
X782550D03*
X776550Y1597533D03*
Y1594533D03*
X779550Y1597533D03*
X782550D03*
Y1600533D03*
X776550D03*
X779550D03*
Y1606533D03*
X782550Y1603533D03*
X779550D03*
X776550Y1606533D03*
Y1603533D03*
X782550Y1606533D03*
X791341Y264848D03*
X784261Y1482049D03*
Y1534963D03*
X784277Y1528191D03*
X791077Y1577233D03*
X785577D03*
X791077Y1582363D03*
X785577Y1587493D03*
X791077D03*
X791550Y1597533D03*
X785550Y1594533D03*
X788550D03*
X791550D03*
X785550Y1597533D03*
X788550D03*
X785550Y1600533D03*
X788550D03*
X791550D03*
Y1606533D03*
X788550D03*
X785550D03*
X791550Y1603533D03*
X788550D03*
X785550D03*
X808469Y1356745D03*
Y1359245D03*
X811272Y1382752D03*
X811767Y1388154D03*
X821977Y1577233D03*
X827577D03*
X821977Y1582363D03*
Y1587493D03*
X827577D03*
X821550Y1594533D03*
X827550Y1597533D03*
Y1594533D03*
X824550Y1597533D03*
Y1594533D03*
X821550Y1597533D03*
Y1600533D03*
X827550D03*
X824550D03*
X815550Y1606533D03*
X818550D03*
X821550Y1603533D03*
X818550D03*
X827550Y1606533D03*
X824550D03*
X821550D03*
X827550Y1603533D03*
X824550D03*
X836163Y279355D03*
X833077Y1577233D03*
Y1582363D03*
Y1587493D03*
X830550Y1597533D03*
X833550D03*
X830550Y1594533D03*
X833550D03*
X830550Y1600533D03*
X833550D03*
X830550Y1603533D03*
X836550Y1606533D03*
Y1603533D03*
X833550D03*
X830550Y1606533D03*
X833550D03*
X856397Y344669D03*
X857550Y1606533D03*
X865132Y333317D03*
X860152D03*
X861377Y344669D03*
X869406Y753541D03*
X863977Y1577233D03*
Y1582363D03*
X869577Y1577233D03*
X863977Y1587493D03*
X869577D03*
X863550Y1597533D03*
X866550Y1594533D03*
Y1597533D03*
X869550Y1594533D03*
Y1597533D03*
X863550Y1594533D03*
X872550D03*
Y1597533D03*
X866550Y1600533D03*
X869550D03*
X863550D03*
X872550D03*
Y1606533D03*
Y1603533D03*
X863550Y1606533D03*
X866550D03*
X869550D03*
X860550D03*
X869550Y1603533D03*
X866550D03*
X863550D03*
X860550D03*
X874617Y1084657D03*
X877817D03*
Y1088057D03*
X874617D03*
X881217Y1084657D03*
Y1088057D03*
X874617Y1100957D03*
X877817D03*
Y1097557D03*
X874617D03*
X881217Y1100957D03*
Y1097557D03*
X875077Y1577233D03*
Y1582363D03*
Y1587493D03*
X875550Y1597533D03*
Y1594533D03*
Y1600533D03*
Y1606533D03*
X878550D03*
Y1603533D03*
X875550D03*
X889057Y1053133D03*
X897754Y1156119D03*
X899550Y1606533D03*
X902550Y1603533D03*
Y1606533D03*
X916268Y277859D03*
X905977Y1577233D03*
Y1582363D03*
X911577Y1577233D03*
X917077D03*
Y1582363D03*
X905977Y1587493D03*
X911577D03*
X917077D03*
X914550Y1597533D03*
Y1594533D03*
X905550D03*
X911550Y1597533D03*
Y1594533D03*
X908550Y1597533D03*
Y1594533D03*
X905550Y1597533D03*
X917550D03*
Y1594533D03*
X914550Y1600533D03*
X905550D03*
X911550D03*
X908550D03*
X917550D03*
X914550Y1603533D03*
Y1606533D03*
X905550Y1603533D03*
X908550D03*
X911550D03*
Y1606533D03*
X908550D03*
X905550D03*
X917550Y1603533D03*
Y1606533D03*
X928224Y264072D03*
X920550Y1603533D03*
Y1606533D03*
X942763Y272340D03*
X944820Y1156119D03*
X957421Y157699D03*
X960421D03*
X962243Y179917D03*
X947748Y1146553D03*
X964743Y179917D03*
X963985Y177154D03*
X965520Y1567570D03*
X962520D03*
X968520D03*
X965520Y1582570D03*
X962520D03*
Y1579570D03*
X965520D03*
Y1576570D03*
X962520D03*
X965520Y1573570D03*
X962520D03*
Y1570570D03*
X965520D03*
X968520Y1582570D03*
Y1579570D03*
Y1576570D03*
Y1573570D03*
Y1570570D03*
X965520Y1588570D03*
X962520D03*
Y1585570D03*
X965520D03*
X968520Y1588570D03*
Y1585570D03*
X991553Y216809D03*
X988460Y354725D03*
X992233Y373679D03*
X986356Y1087508D03*
X983156D03*
Y1084108D03*
X986356D03*
X989556Y1087508D03*
Y1084108D03*
X986356Y1097008D03*
X983156D03*
Y1100408D03*
X986356D03*
X989556Y1097008D03*
Y1100408D03*
X1002736Y157943D03*
X999736D03*
X993306Y174953D03*
X993206Y178053D03*
X1006436Y176843D03*
X999916Y184548D03*
X996416D03*
X992506Y184553D03*
X993460Y354725D03*
X998460D03*
X997488Y370287D03*
X994160Y1567710D03*
X997160D03*
X1000160D03*
X994160Y1582710D03*
X997160D03*
Y1579710D03*
X994160D03*
X997160Y1570710D03*
X994160D03*
Y1573710D03*
X997160D03*
X994160Y1576710D03*
X997160D03*
X1000160Y1582710D03*
Y1579710D03*
Y1570710D03*
Y1573710D03*
Y1576710D03*
X994160Y1588710D03*
X997160D03*
Y1585710D03*
X994160D03*
X1000160Y1588710D03*
Y1585710D03*
X1021899Y61590D03*
Y127590D03*
X1011358Y195324D03*
X1008068Y198387D03*
X1019936Y207333D03*
Y210463D03*
X1013306Y528942D03*
X1032354Y538201D03*
X1022686D03*
X1027520Y552724D03*
X1025750Y1567710D03*
X1031750D03*
X1028750D03*
X1025750Y1576710D03*
Y1573710D03*
Y1570710D03*
Y1579710D03*
Y1582710D03*
X1028750Y1576710D03*
Y1573710D03*
Y1570710D03*
Y1579710D03*
Y1582710D03*
X1031750Y1576710D03*
Y1573710D03*
Y1570710D03*
Y1579710D03*
Y1582710D03*
X1025750Y1585710D03*
Y1588710D03*
X1028750Y1585710D03*
Y1588710D03*
X1031750Y1585710D03*
Y1588710D03*
X1059055Y492537D03*
X1057219Y1567883D03*
X1060219D03*
X1063219D03*
X1066219D03*
X1057219Y1576883D03*
Y1573883D03*
Y1570883D03*
Y1579883D03*
Y1582883D03*
X1060219Y1576883D03*
Y1573883D03*
Y1570883D03*
Y1579883D03*
Y1582883D03*
X1063219Y1576883D03*
Y1573883D03*
Y1570883D03*
X1066219Y1576883D03*
Y1573883D03*
Y1570883D03*
Y1579883D03*
X1063219D03*
Y1582883D03*
X1066219D03*
X1057219Y1585883D03*
Y1588883D03*
X1060219Y1585883D03*
Y1588883D03*
X1066219Y1585883D03*
X1063219D03*
Y1588883D03*
X1066219D03*
X1094399Y1568043D03*
X1091399D03*
X1085399D03*
X1088399D03*
X1091399Y1580043D03*
X1094399D03*
Y1571043D03*
Y1574043D03*
Y1577043D03*
X1091399Y1571043D03*
Y1574043D03*
Y1577043D03*
X1088399Y1580043D03*
X1085399D03*
X1088399Y1571043D03*
X1085399D03*
Y1574043D03*
X1088399D03*
X1085399Y1577043D03*
X1088399D03*
X1094399Y1583043D03*
X1091399D03*
X1085399D03*
X1088399D03*
X1094399Y1589043D03*
X1091399D03*
Y1586043D03*
X1094399D03*
X1085399Y1589043D03*
X1088399D03*
Y1586043D03*
X1085399D03*
X1092030Y1715841D03*
Y1725991D03*
X1097399Y1568043D03*
Y1580043D03*
Y1571043D03*
Y1574043D03*
Y1577043D03*
Y1583043D03*
Y1589043D03*
Y1586043D03*
X1170986Y1519190D03*
X1168386Y1517280D03*
Y1512500D03*
Y1534300D03*
Y1539080D03*
X1170986Y1540990D03*
X1173586Y1517280D03*
Y1512500D03*
Y1534300D03*
Y1539080D03*
X1181361Y1543800D03*
Y1547420D03*
Y1551040D03*
X1172603Y1554561D03*
X1188472Y80165D03*
X1197980Y1688270D03*
X1213072Y1682899D03*
X1207770Y1717011D03*
Y1731011D03*
X1226094Y297066D03*
X1288494Y1519682D03*
Y1533082D03*
X1304705Y79807D03*
X1303266Y533713D03*
Y530413D03*
X1300200Y590600D03*
X1299048Y1519190D03*
X1296448Y1517280D03*
Y1512500D03*
X1301648Y1517280D03*
Y1512500D03*
X1296448Y1534300D03*
X1301648D03*
X1296448Y1539080D03*
X1301648D03*
X1299048Y1540990D03*
X1309185Y74748D03*
X1316266Y564514D03*
X1317266Y589522D03*
X1318300Y640000D03*
Y643000D03*
Y649000D03*
Y646000D03*
X1318363Y1411404D03*
X1312700Y1579596D03*
X1319349Y1585567D03*
X1330820Y525165D03*
X1330758Y521749D03*
X1330820Y518265D03*
X1330658Y538749D03*
X1330758Y528649D03*
X1330773Y531776D03*
X1330758Y535449D03*
X1329673Y552509D03*
X1332673D03*
X1326673Y544909D03*
X1329673Y545909D03*
Y549309D03*
X1330658Y542949D03*
X1332673Y545909D03*
Y549309D03*
X1329673Y558709D03*
Y555709D03*
X1332673D03*
X1325366Y589522D03*
X1321300Y643000D03*
Y640000D03*
Y649000D03*
Y646000D03*
X1326433Y1214334D03*
X1335260Y236594D03*
Y246594D03*
Y241594D03*
Y251594D03*
X1348611Y1212963D03*
Y1218463D03*
X1364239Y1207949D03*
X1391460Y1032205D03*
X1388918Y1687878D03*
X1382045Y1712038D03*
Y1708038D03*
X1384604Y1728318D03*
X1393179Y1733118D03*
X1404917Y109037D03*
X1395060Y1009764D03*
Y1006024D03*
Y1013504D03*
Y1020985D03*
Y1024725D03*
Y1028465D03*
Y1017244D03*
X1397955Y1582178D03*
X1405058Y1639607D03*
X1417301Y1055140D03*
X1416556Y1519682D03*
Y1533082D03*
X1418740Y1622902D03*
X1427973Y60409D03*
X1438507Y1006024D03*
Y1009764D03*
Y1013504D03*
Y1024725D03*
Y1020985D03*
Y1017244D03*
Y1028465D03*
Y1032205D03*
X1435160Y1519190D03*
X1432560Y1517280D03*
Y1512500D03*
X1437760Y1517280D03*
Y1512500D03*
X1432560Y1534300D03*
X1437760D03*
X1432560Y1539080D03*
X1437760D03*
X1435160Y1540990D03*
X1433979Y1655655D03*
X1441141Y53699D03*
X1448505Y1579725D03*
X1455461Y1585567D03*
X1528993Y4115D03*
Y26115D03*
X1534067Y1582178D03*
X1552668Y1519682D03*
Y1533082D03*
X1568176Y568423D03*
X1570676D03*
X1565676D03*
X1561376Y572258D03*
X1566010Y673210D03*
X1562730Y675180D03*
X1563222Y1519190D03*
X1560622Y1517280D03*
Y1512500D03*
X1565822Y1517280D03*
Y1512500D03*
X1560622Y1534300D03*
X1565822D03*
X1560622Y1539080D03*
X1565822D03*
X1563222Y1540990D03*
X1586291Y306746D03*
X1584160Y558973D03*
X1576653Y1579333D03*
X1583523Y1585567D03*
X1606535Y553297D03*
X1607369Y561330D03*
X1631889Y521480D03*
X1618884Y533388D03*
X1632798Y544564D03*
X1622391Y564169D03*
X1627242Y1436148D03*
X1627181Y1448016D03*
X1636929Y524690D03*
Y528190D03*
Y531690D03*
Y535190D03*
Y538690D03*
X1639868Y542444D03*
X1636783Y542604D03*
X1635798Y545564D03*
X1638798D03*
Y548964D03*
Y552164D03*
X1635798D03*
Y548964D03*
Y555364D03*
X1638798D03*
X1635798Y558364D03*
X1648029Y1718759D03*
Y1733909D03*
X1652525Y141762D03*
X1662129Y1582178D03*
X1673100Y126762D03*
X1676971Y1668582D03*
X1686154Y434160D03*
X1685298Y1451231D03*
X1680730Y1519682D03*
Y1533082D03*
X1688243Y1663802D03*
X1682724Y1717701D03*
X1704444Y407045D03*
X1707444D03*
X1697914Y427155D03*
X1698014Y424055D03*
X1701124Y433650D03*
X1697214Y433655D03*
X1704624Y433650D03*
X1704822Y1694243D03*
X1702985Y1700328D03*
X1711144Y425945D03*
X1722149Y1715265D03*
X1719149Y1703190D03*
X1722149Y1730415D03*
X1724263Y1681465D03*
X1752250Y303850D03*
X1749329Y1662956D03*
X1743329Y1668956D03*
X1743153Y1662956D03*
X1749329Y1674956D03*
X1743329D03*
X1754850Y303930D03*
X1755329Y1668956D03*
Y1662956D03*
Y1674956D03*
X1763463Y1691465D03*
X1758963Y1691565D03*
X1787390Y161834D03*
X1800040Y164393D03*
X1797719Y186610D03*
X1811668Y218900D03*
X1811606Y222513D03*
X1808429Y218837D03*
X1811606Y226438D03*
X1808367Y222450D03*
X1810479Y211850D03*
X1810509Y214660D03*
X1808260Y213232D03*
X1808367Y226375D03*
X1825111Y164393D03*
X1813079Y211850D03*
X1813109Y214660D03*
G54D17*
X18960Y1598181D03*
X440029Y240381D03*
X434420Y239930D03*
X934302Y578318D03*
X1769420Y19506D03*
X1777420D03*
Y24506D03*
G54D19*
X35852Y673010D03*
Y675510D03*
Y697322D03*
Y694822D03*
Y705728D03*
X50138Y425810D03*
X45182D03*
X45022Y449106D03*
X50002D03*
X48626Y552365D03*
X50880Y1412563D03*
X51358Y1647717D03*
Y1650217D03*
X52052Y1684027D03*
X67257Y69340D03*
X62930Y282866D03*
Y312866D03*
X62833Y409597D03*
X62808Y418675D03*
X65380Y427810D03*
X60393D03*
X58349Y1403331D03*
X54449Y1641722D03*
X61415Y1661695D03*
X61374Y1669931D03*
X70127Y1687362D03*
X73015Y28406D03*
X80101D03*
X73015Y40020D03*
X80101D03*
X78253Y75343D03*
X74773Y790297D03*
Y800336D03*
Y827108D03*
Y837147D03*
Y863919D03*
Y873958D03*
Y900730D03*
Y910769D03*
Y937541D03*
Y947580D03*
Y1084785D03*
Y1094824D03*
Y1121596D03*
Y1131635D03*
Y1158407D03*
Y1168446D03*
Y1195218D03*
Y1205257D03*
Y1232029D03*
Y1242068D03*
X71511Y1444379D03*
X69486Y1661828D03*
X69589Y1669878D03*
X78127Y1687362D03*
X74127D03*
X94274Y28406D03*
X87188D03*
Y40020D03*
X94274D03*
X89257Y69340D03*
X90150Y1314560D03*
X86127Y1687362D03*
X92192Y1713741D03*
X92596Y1737117D03*
X108448Y28406D03*
X101361D03*
Y40020D03*
X108448D03*
X100257Y75340D03*
X111257Y69340D03*
X104474Y790297D03*
Y800336D03*
Y827108D03*
Y837147D03*
Y863919D03*
Y873958D03*
Y900730D03*
Y910769D03*
Y937541D03*
Y947580D03*
Y1084785D03*
Y1094824D03*
Y1121596D03*
Y1131635D03*
Y1158407D03*
Y1168446D03*
Y1195218D03*
Y1205257D03*
Y1232029D03*
Y1242068D03*
X112355Y1426064D03*
Y1433564D03*
Y1441064D03*
X110144Y1597831D03*
X110996Y1592018D03*
X122621Y28406D03*
X115534D03*
Y40020D03*
X122621D03*
X122257Y75340D03*
X119855Y1426064D03*
X127355Y1433564D03*
Y1426064D03*
X119855Y1441064D03*
X127355D03*
X127374Y1572749D03*
X127392Y1575524D03*
X125768Y1568744D03*
X127246Y1585801D03*
X127264Y1588576D03*
X113496Y1592018D03*
X116353Y1646612D03*
X120353D03*
X124353D03*
X123278Y1658587D03*
X119353Y1695941D03*
X115353D03*
X125107Y1702666D03*
X124461Y1726116D03*
X114596Y1737117D03*
X129708Y28406D03*
Y40020D03*
X133257Y69343D03*
X141642Y491434D03*
X134174Y790297D03*
Y800336D03*
Y837147D03*
Y827108D03*
Y863919D03*
Y873958D03*
Y900730D03*
Y910769D03*
Y937541D03*
Y947580D03*
Y1084785D03*
Y1094824D03*
Y1121596D03*
Y1131635D03*
Y1158407D03*
Y1168446D03*
Y1195218D03*
Y1205257D03*
Y1232029D03*
Y1242068D03*
X128617Y1561022D03*
X129892Y1575524D03*
X129874Y1572749D03*
X128268Y1568744D03*
X129764Y1588576D03*
X129746Y1585801D03*
X128353Y1646612D03*
X140353D03*
X136048Y1666851D03*
X133548Y1677351D03*
X131353Y1696062D03*
X135353D03*
X139353D03*
X136596Y1737117D03*
X151400Y28406D03*
Y40020D03*
X144257Y75340D03*
X155253Y69343D03*
X148353Y1646612D03*
X144353D03*
X155328Y1670087D03*
X146928Y1685087D03*
X143353Y1696062D03*
X158487Y28406D03*
X165574D03*
X158487Y40020D03*
X165574D03*
X167461Y75340D03*
X163875Y790297D03*
Y800336D03*
Y837147D03*
Y827108D03*
Y863919D03*
Y873958D03*
Y900730D03*
Y910769D03*
Y937541D03*
Y947580D03*
Y1084785D03*
Y1094824D03*
Y1121596D03*
Y1131635D03*
Y1158407D03*
Y1168446D03*
Y1195218D03*
Y1205257D03*
Y1232029D03*
Y1242068D03*
X163421Y1425171D03*
Y1427671D03*
Y1430171D03*
Y1432671D03*
X158596Y1737117D03*
X172660Y28406D03*
X179747D03*
X172660Y40020D03*
X179747D03*
X178461Y69340D03*
X173960Y400560D03*
X172721Y1425171D03*
Y1430171D03*
Y1427671D03*
Y1432671D03*
X175351Y1462595D03*
X182051Y1452895D03*
X181760Y1731351D03*
X180596Y1737117D03*
X195534Y28406D03*
Y40020D03*
X189457Y75343D03*
X200461Y69340D03*
X193576Y790297D03*
Y800336D03*
Y827108D03*
Y837147D03*
Y863919D03*
Y873958D03*
Y900730D03*
Y910769D03*
Y937541D03*
Y947580D03*
Y1084785D03*
Y1094824D03*
Y1121596D03*
Y1131635D03*
Y1158407D03*
Y1168446D03*
Y1205257D03*
Y1195218D03*
Y1232029D03*
Y1242068D03*
X202151Y1462595D03*
X195451Y1472295D03*
X202621Y28406D03*
X216794D03*
X209708D03*
X202621Y40020D03*
X209708D03*
X216794D03*
X211595Y75340D03*
X208851Y1452895D03*
X202596Y1737117D03*
X223881Y28406D03*
X230967D03*
X223881Y40020D03*
X230967D03*
X222591Y69343D03*
X223277Y790297D03*
Y800336D03*
Y837147D03*
Y827108D03*
Y863919D03*
Y873958D03*
Y900730D03*
Y910769D03*
Y937541D03*
Y947580D03*
Y1084785D03*
Y1094824D03*
Y1121596D03*
Y1131635D03*
Y1158407D03*
Y1168446D03*
Y1205257D03*
Y1195218D03*
Y1232029D03*
Y1242068D03*
X228951Y1462595D03*
X222251Y1472295D03*
X224596Y1737117D03*
X233595Y75340D03*
X242215Y151788D03*
X234727Y584030D03*
Y571211D03*
X245815Y672746D03*
X244565Y677846D03*
Y680446D03*
Y675246D03*
X242543Y691115D03*
X239443Y691015D03*
X239843Y709715D03*
X235651Y1452895D03*
X252996Y28365D03*
X256496D03*
X249496D03*
X259996D03*
X252195Y144320D03*
X259475Y657245D03*
X259426Y644830D03*
X259475Y662845D03*
X250312Y670080D03*
Y667180D03*
X250835Y672692D03*
X253279Y672708D03*
X258379Y666644D03*
Y669601D03*
Y672708D03*
X255779D03*
X260979Y666644D03*
Y669601D03*
Y672708D03*
X247165Y677846D03*
Y680446D03*
Y675246D03*
X254448Y692050D03*
X255751Y1462595D03*
X249051Y1472295D03*
X266601Y586578D03*
X271571Y644796D03*
X264335Y657245D03*
X261905D03*
Y662845D03*
X264335D03*
X263579Y669601D03*
X266179D03*
Y672708D03*
X263579D03*
X270857Y668515D03*
X263839Y692049D03*
X275851Y1452895D03*
X262451D03*
X266596Y1737117D03*
X278979Y28406D03*
X286066D03*
X279273Y99186D03*
X289553Y121806D03*
X291109Y700885D03*
X283062Y700979D03*
X279895Y709487D03*
X283565Y706933D03*
X286009Y706949D03*
X278545Y706987D03*
X279895Y712087D03*
Y714687D03*
X291109Y703842D03*
Y706949D03*
X288509D03*
X277295Y709487D03*
Y712087D03*
Y714687D03*
X283062Y703936D03*
X277055Y722649D03*
X279171Y724988D03*
X281992Y1342705D03*
X292705Y580275D03*
X292156Y679071D03*
X304301Y679037D03*
X292205Y691486D03*
X297065D03*
X294635D03*
X293709Y700885D03*
X297065Y697086D03*
X303657Y702815D03*
X292205Y697086D03*
X294635D03*
X293709Y703842D03*
Y706949D03*
X298909Y703842D03*
Y706949D03*
X296309Y703842D03*
Y706949D03*
X303413Y1462595D03*
X315912Y721039D03*
Y723996D03*
X321279Y727099D03*
X312665Y729637D03*
Y732237D03*
X310065Y729637D03*
Y732237D03*
X316335Y727083D03*
X311315Y727137D03*
X318779Y727099D03*
X313255Y746279D03*
X312665Y734837D03*
X310065D03*
X310113Y1452895D03*
X312596Y1737117D03*
X328966Y548030D03*
X324926Y699221D03*
X329835Y711636D03*
X324975D03*
X329835Y717236D03*
X327405Y711636D03*
X324975Y717236D03*
X327405D03*
X326479Y721035D03*
X323879D03*
Y727099D03*
X326479D03*
X329079D03*
X331679D03*
X323879Y723992D03*
X326479D03*
X329079D03*
X331679D03*
X330213Y1462595D03*
X323513Y1472295D03*
X334596Y1737117D03*
X350817Y558248D03*
X343182Y586415D03*
Y591335D03*
X348449Y720827D03*
Y723784D03*
X345725Y729369D03*
X343125D03*
X345725Y731969D03*
X343125D03*
X344375Y726869D03*
X349395Y726815D03*
X336457Y722815D03*
X339825Y746269D03*
X342425D03*
X349625D03*
X345725Y734569D03*
X343125D03*
X336913Y1452895D03*
X350313Y1472295D03*
X352418Y225329D03*
Y222329D03*
X355733Y275059D03*
X357986Y698953D03*
X362895Y716968D03*
X360465Y711368D03*
X362895D03*
X358035D03*
Y716968D03*
X360465D03*
X359539Y720767D03*
X356939D03*
X351839Y726831D03*
X354339D03*
X356939D03*
X362139D03*
X359539D03*
X364739D03*
X356939Y723724D03*
X362139D03*
X359539D03*
X364739D03*
X352225Y746269D03*
X360025D03*
X362625D03*
X352943Y1214510D03*
X363713Y1452895D03*
X357013Y1462595D03*
X356596Y1737117D03*
X379023Y225149D03*
X371318Y218629D03*
X379023Y228649D03*
X379028Y232559D03*
X369428Y231759D03*
X372528Y231859D03*
X369171Y562380D03*
X376671D03*
X369100Y577400D03*
X369171Y569880D03*
X376600Y577400D03*
X376165Y729437D03*
X378765D03*
X376165Y732037D03*
X378765D03*
X377415Y726937D03*
X369557Y722615D03*
X373425Y746169D03*
X370825D03*
X376165Y734637D03*
X378765D03*
X367836Y1209506D03*
X377190Y1387697D03*
X377113Y1472295D03*
X393287Y-9234D03*
X391635Y161091D03*
X384259Y562426D03*
X384301Y577446D03*
X385443Y597279D03*
X391026Y699021D03*
X395935Y717036D03*
Y711436D03*
X393505D03*
X391075D03*
Y717036D03*
X393505D03*
X392579Y720835D03*
X389979D03*
X381802Y720789D03*
Y723746D03*
X387379Y726899D03*
X384879D03*
X389979D03*
Y723792D03*
X382435Y726883D03*
X392579Y726899D03*
X395179D03*
X392579Y723792D03*
X395179D03*
X389981Y1015474D03*
Y1022560D03*
Y1019017D03*
X383813Y1462595D03*
X390513Y1452895D03*
X406243Y100076D03*
X402184Y507101D03*
X403133Y565415D03*
X403157Y569415D03*
X410415Y709137D03*
X409165Y711637D03*
Y714237D03*
Y716837D03*
X397779Y726899D03*
Y723792D03*
X402457Y722615D03*
X397461Y1015474D03*
X404941D03*
X397461Y1022560D03*
X404941Y1019017D03*
Y1022560D03*
X397461Y1019017D03*
X403913Y1452895D03*
X417617Y79073D03*
X423376Y96664D03*
X411952Y132751D03*
Y123051D03*
X422936Y228147D03*
Y232793D03*
X420288Y244184D03*
X415984Y507024D03*
X424026Y681221D03*
X424075Y693636D03*
X425579Y703035D03*
X422979D03*
X424075Y699236D03*
X414682Y703139D03*
X411765Y711637D03*
Y714237D03*
Y716837D03*
X415435Y709083D03*
X417879Y709099D03*
X425579D03*
X422979D03*
X420379D03*
X425579Y705992D03*
X422979D03*
X414682Y706096D03*
X423811Y1009400D03*
Y1028831D03*
X417098Y1533764D03*
Y1531264D03*
X422596Y1737117D03*
X429685Y88657D03*
X436090Y116007D03*
Y124007D03*
Y132007D03*
X440591Y684518D03*
X436130Y683281D03*
X426505Y693636D03*
X428935D03*
Y699236D03*
X426505D03*
X430779Y709099D03*
Y705992D03*
X428179Y709099D03*
Y705992D03*
X435457Y704915D03*
X439411Y733527D03*
X436811D03*
X439411Y736147D03*
X436811D03*
X436411Y738717D03*
X439011D03*
X436411Y743917D03*
X439011D03*
X436411Y741317D03*
X439011D03*
X431291Y1009400D03*
X438316Y1014745D03*
X427551Y1009400D03*
X435031D03*
X438771D03*
X428473Y1014745D03*
X438771Y1028831D03*
X438316Y1023013D03*
X427551Y1028831D03*
X435031D03*
X438316Y1018879D03*
X428473D03*
Y1023013D03*
X431291Y1028831D03*
X427251Y1291747D03*
X439524Y1462595D03*
X448090Y116007D03*
X444090Y132007D03*
X452480Y273420D03*
X441320Y298170D03*
X452565Y652837D03*
X455379Y678435D03*
X450279Y684499D03*
X455379D03*
X452779D03*
X455379Y681392D03*
X444165Y687037D03*
X441565D03*
X443235Y684637D03*
X447835Y684483D03*
X447162Y678409D03*
Y681366D03*
X444325Y702449D03*
X441725D03*
X444165Y689637D03*
Y692237D03*
X441565D03*
Y689637D03*
X446591Y716837D03*
X443991D03*
X446591Y719437D03*
X443991D03*
X441959Y993766D03*
Y997766D03*
X442034Y989766D03*
X442511Y1009400D03*
X449992D03*
X446252D03*
X453732D03*
X441959Y1001766D03*
X447174Y1014745D03*
X446252Y1028831D03*
X453732D03*
X449992D03*
X447174Y1023013D03*
X442511Y1028831D03*
X447174Y1018879D03*
X446224Y1452895D03*
X444596Y1737117D03*
X463402Y229970D03*
X457731Y237588D03*
X463653Y237390D03*
X462703Y242342D03*
X467644Y353417D03*
X469046Y657062D03*
X456426Y656621D03*
X458905Y669036D03*
X456475D03*
X461335D03*
X457979Y678435D03*
X460579Y684499D03*
X457979D03*
X460579Y681392D03*
X457979D03*
X467957Y680315D03*
X463179Y684499D03*
Y681392D03*
X461335Y674636D03*
X456475D03*
X458905D03*
X457472Y1009400D03*
X457410Y1014745D03*
Y1018879D03*
Y1023013D03*
X457472Y1028831D03*
X466324Y1462595D03*
X459624Y1472295D03*
X466596Y1737117D03*
X486682Y197516D03*
X483800Y270440D03*
X475415Y658037D03*
X482879Y657999D03*
X480435Y657983D03*
X485379Y657999D03*
X479822Y651989D03*
Y654946D03*
X476765Y660537D03*
X474165D03*
X476765Y663137D03*
X474165D03*
X476765Y665737D03*
X474165D03*
X473024Y1452895D03*
X495232Y189516D03*
X486600Y200800D03*
X495232Y197516D03*
X491635Y212577D03*
X487541Y226527D03*
X488076Y350420D03*
X501171Y630087D03*
X493935Y642536D03*
X489075D03*
X491505D03*
X489026Y630121D03*
X493935Y648136D03*
X487979Y651935D03*
X490579D03*
X493179Y654892D03*
Y657999D03*
X487979Y654892D03*
X490579D03*
Y657999D03*
X487979D03*
X495779Y654892D03*
Y657999D03*
X489075Y648136D03*
X491505D03*
X499824Y1452895D03*
X493124Y1462595D03*
X486424Y1472295D03*
X488596Y1737117D03*
X510810Y49193D03*
X510065Y626437D03*
X508715Y623937D03*
X507465Y626437D03*
X513735Y623883D03*
X513012Y620706D03*
Y617749D03*
X510065Y629037D03*
X507465D03*
X510065Y631637D03*
X507465D03*
X514771Y643138D03*
X500457Y653715D03*
X513224Y1472295D03*
X517915Y42257D03*
X525001D03*
X517896Y49193D03*
X524763Y49189D03*
X522418Y137171D03*
X526418D03*
X517973Y211998D03*
X522326Y596021D03*
X524805Y608436D03*
X522375D03*
X527235D03*
X526479Y620792D03*
Y623899D03*
X523879Y620792D03*
X521279D03*
X523879Y623899D03*
X521279D03*
X518679D03*
X516179D03*
X529079Y620792D03*
Y623899D03*
X523879Y617835D03*
X521279D03*
X527235Y614036D03*
X522375D03*
X524805D03*
X521771Y643138D03*
X528771D03*
X519924Y1462595D03*
X526624Y1452895D03*
X532070Y49193D03*
X539156D03*
X530418Y137171D03*
X541013Y222441D03*
X534471Y595987D03*
X533857Y619615D03*
X534271Y643138D03*
X540024Y1452895D03*
X532596Y1737117D03*
X557091Y114382D03*
X550505D03*
X553100Y227700D03*
X551200Y377650D03*
X551171Y1167678D03*
X554596Y1737117D03*
X564431Y45132D03*
X562475Y242721D03*
X571271Y1259488D03*
X567586Y1462595D03*
X574286Y1452895D03*
X578621Y45112D03*
X585296Y222954D03*
X586000Y808862D03*
X578830Y1218588D03*
X585501Y1229536D03*
X587686Y1472295D03*
X576596Y1737117D03*
X595682Y44842D03*
X603064Y44523D03*
X599284Y32866D03*
X593920Y49193D03*
X600793Y193185D03*
X596661Y188775D03*
X590300Y190660D03*
X595563Y239128D03*
X603283Y419744D03*
X597071Y799268D03*
X592761Y1220688D03*
X594386Y1462595D03*
X601086Y1452895D03*
X598596Y1737117D03*
X618427Y43432D03*
X615180Y49193D03*
X618600Y160750D03*
X613207Y182229D03*
X615464Y347522D03*
X607871Y359262D03*
X613761Y790418D03*
X605771Y1267098D03*
X614486Y1472295D03*
X624937Y44019D03*
X620390Y36794D03*
X630900Y118920D03*
X632695Y1366157D03*
Y1372257D03*
Y1378257D03*
X627886Y1452895D03*
X621186Y1462595D03*
X620596Y1737117D03*
X648487Y44106D03*
X638695Y1366157D03*
X644795D03*
X643395Y1372857D03*
X638695Y1378257D03*
X644795D03*
X647986Y1462595D03*
X641286Y1472295D03*
X642596Y1737117D03*
X654590Y49193D03*
X661676D03*
X652804Y790297D03*
Y800336D03*
Y837147D03*
Y827108D03*
Y863919D03*
Y873958D03*
Y900730D03*
Y910769D03*
Y937541D03*
Y947580D03*
Y1084785D03*
Y1094824D03*
Y1121596D03*
Y1131635D03*
Y1158407D03*
Y1168446D03*
Y1205257D03*
Y1195218D03*
Y1232029D03*
Y1242068D03*
X661685Y1367283D03*
X654686Y1452895D03*
X662153Y1727718D03*
X675849Y49193D03*
X668763D03*
X668086Y1452895D03*
X664596Y1737117D03*
X682505Y790297D03*
Y800336D03*
Y837147D03*
Y827108D03*
Y863919D03*
Y873958D03*
Y900730D03*
Y910769D03*
Y937541D03*
Y947580D03*
Y1084785D03*
Y1094824D03*
Y1121596D03*
Y1131635D03*
Y1158407D03*
Y1168446D03*
Y1205257D03*
Y1195218D03*
Y1232029D03*
Y1242068D03*
X688540Y1455140D03*
X697400Y345761D03*
X697300Y1454140D03*
X722581Y49182D03*
X713420Y102060D03*
X712206Y790297D03*
Y800336D03*
Y827108D03*
Y837147D03*
Y863919D03*
Y873958D03*
Y900730D03*
Y910769D03*
Y937541D03*
Y947580D03*
Y1084785D03*
Y1094824D03*
Y1121596D03*
Y1131635D03*
Y1158407D03*
Y1168446D03*
Y1195218D03*
Y1205257D03*
Y1232029D03*
Y1242068D03*
X731743Y-30584D03*
X734996Y-30570D03*
X731758Y-28069D03*
X735011Y-28055D03*
X728718Y-29264D03*
X735041Y-23025D03*
X735026Y-25540D03*
X731555Y83685D03*
X737009Y83169D03*
X724134Y141288D03*
X728500Y533862D03*
X736500D03*
X732500D03*
X738260Y553625D03*
X747637Y534874D03*
X740638Y549900D03*
X741907Y790297D03*
Y800336D03*
Y827108D03*
Y837147D03*
Y863919D03*
Y873958D03*
Y900730D03*
Y910769D03*
Y937541D03*
Y947580D03*
Y1084785D03*
Y1094824D03*
Y1121596D03*
Y1131635D03*
Y1158407D03*
Y1168446D03*
Y1195218D03*
Y1205257D03*
Y1232029D03*
Y1242068D03*
X751521Y1659158D03*
X752596Y1737117D03*
X762199Y126684D03*
Y129684D03*
X758111Y172636D03*
X762300Y188910D03*
X764500Y534424D03*
X760500Y534352D03*
X781242Y489574D03*
X771608Y790297D03*
Y800336D03*
Y837147D03*
Y827108D03*
Y863919D03*
Y873958D03*
Y900730D03*
Y910769D03*
Y937541D03*
Y947580D03*
Y1084785D03*
Y1094824D03*
Y1121596D03*
Y1131635D03*
Y1158407D03*
Y1168446D03*
Y1195218D03*
Y1205257D03*
Y1232029D03*
Y1242068D03*
X778030Y1310259D03*
X780530D03*
X773974Y1731920D03*
X796333Y439344D03*
X786030Y1310259D03*
X794030D03*
X796530D03*
X788530D03*
X791823Y1527404D03*
X795926Y1731918D03*
X807451Y763765D03*
X801308Y790297D03*
Y800336D03*
Y837147D03*
Y827108D03*
Y863919D03*
Y873958D03*
Y900730D03*
Y910769D03*
Y937541D03*
Y947580D03*
Y1084785D03*
Y1094824D03*
Y1121596D03*
Y1131635D03*
Y1158407D03*
Y1168446D03*
Y1195218D03*
Y1205257D03*
Y1232029D03*
Y1242068D03*
X802030Y1310259D03*
X804530D03*
X807601Y1307191D03*
X810246Y1351988D03*
X817974Y1731920D03*
X839974D03*
X844766Y-15374D03*
Y-5374D03*
Y24626D03*
X849711Y212062D03*
X845221Y216532D03*
X854707Y229878D03*
X852207D03*
X874295Y163862D03*
X863488Y176332D03*
X861974Y1731920D03*
X883974D03*
X898000Y1112336D03*
Y1109736D03*
Y1116544D03*
Y1119144D03*
Y1130160D03*
Y1132760D03*
Y1123352D03*
Y1125952D03*
X916880Y1138969D03*
X906473Y1158574D03*
X903980Y1268420D03*
X904024Y1272692D03*
X903947Y1276968D03*
X903899Y1281203D03*
X903945Y1285420D03*
X903923Y1289630D03*
X903651Y1293853D03*
X903690Y1298027D03*
X905974Y1731920D03*
X921477Y1134647D03*
X925525Y1135172D03*
X919880Y1146569D03*
Y1139969D03*
Y1143369D03*
Y1149769D03*
X922880Y1146569D03*
Y1139969D03*
Y1143369D03*
Y1149769D03*
X919077Y1136521D03*
X923125Y1137046D03*
X919880Y1152769D03*
X928751Y1266347D03*
X928901Y1270408D03*
X928852Y1274591D03*
X928979Y1278713D03*
X928827Y1283048D03*
X928928Y1287193D03*
X928906Y1291676D03*
X928983Y1295957D03*
X927974Y1731920D03*
X935497Y195925D03*
Y210098D03*
Y203012D03*
Y224272D03*
Y217185D03*
Y231358D03*
X935783Y634051D03*
X941000Y1110557D03*
Y1107957D03*
Y1117557D03*
Y1114957D03*
Y1124557D03*
Y1121957D03*
Y1131557D03*
Y1128957D03*
X953498Y1158574D03*
X949974Y1731920D03*
X967315Y1135550D03*
X972109Y1135149D03*
X966905Y1146569D03*
X969905D03*
X966905Y1139969D03*
Y1143369D03*
X969905Y1139969D03*
Y1143369D03*
X966905Y1149769D03*
X969905D03*
X963012Y1139511D03*
X964915Y1137424D03*
X969709Y1137023D03*
X966905Y1152769D03*
X968594Y1288193D03*
X971974Y1731920D03*
X991031Y528574D03*
X998056Y518214D03*
Y523874D03*
X999031Y528574D03*
X999894Y1267126D03*
X993974Y1731920D03*
X1021220Y243638D03*
X1012220D03*
X1007669Y268884D03*
Y258222D03*
X1007587Y767480D03*
Y769980D03*
Y780880D03*
Y778380D03*
Y789484D03*
Y791984D03*
X1010894Y1271743D03*
X1010865Y1275768D03*
X1010944Y1279751D03*
X1010650Y1310500D03*
X1015974Y1731920D03*
X1025493Y758819D03*
X1044012Y268659D03*
X1051495Y265133D03*
X1040097Y529508D03*
X1050915Y790296D03*
Y800335D03*
Y827107D03*
Y837146D03*
Y863918D03*
Y873957D03*
Y910768D03*
Y900729D03*
Y937540D03*
Y947579D03*
Y1084784D03*
Y1094823D03*
Y1131634D03*
Y1121595D03*
Y1158406D03*
Y1168445D03*
Y1205256D03*
Y1195217D03*
Y1232028D03*
Y1242067D03*
X1037974Y1731920D03*
X1054355Y258698D03*
X1065552Y271441D03*
X1056517Y512787D03*
X1061837Y519703D03*
X1060721Y1313954D03*
X1061974Y1731920D03*
X1080616Y790296D03*
Y800335D03*
Y827107D03*
Y837146D03*
Y863918D03*
Y873957D03*
Y910768D03*
Y900729D03*
Y937540D03*
Y947579D03*
Y1084784D03*
Y1094823D03*
Y1131634D03*
Y1121595D03*
Y1158406D03*
Y1168445D03*
Y1205256D03*
Y1195217D03*
Y1232028D03*
Y1242067D03*
X1081857Y269856D03*
X1089030Y1691229D03*
X1092980Y1696029D03*
X1095489Y1708519D03*
X1081974Y1731920D03*
X1110316Y790296D03*
Y800335D03*
Y827107D03*
Y837146D03*
Y863918D03*
Y873957D03*
Y910768D03*
Y900729D03*
Y937540D03*
Y947579D03*
Y1084784D03*
Y1094823D03*
Y1131634D03*
Y1121595D03*
Y1158406D03*
Y1168445D03*
Y1205256D03*
Y1195217D03*
Y1232028D03*
Y1242067D03*
X1103351Y1737117D03*
X1112001Y1718991D03*
X1125351Y1737117D03*
X1140017Y790296D03*
Y800335D03*
Y827107D03*
Y837146D03*
Y863918D03*
Y873957D03*
Y910768D03*
Y900729D03*
Y937540D03*
Y947579D03*
Y1084784D03*
Y1094823D03*
Y1131634D03*
Y1121595D03*
Y1158406D03*
Y1168445D03*
Y1205256D03*
Y1195217D03*
Y1232028D03*
Y1242067D03*
X1169718Y790296D03*
Y800335D03*
Y837146D03*
Y827107D03*
Y863918D03*
Y873957D03*
Y900729D03*
Y910768D03*
Y937540D03*
Y947579D03*
Y1084784D03*
Y1094823D03*
Y1121595D03*
Y1131634D03*
Y1158406D03*
Y1168445D03*
Y1205256D03*
Y1195217D03*
Y1232028D03*
Y1242067D03*
X1183050Y-20074D03*
Y-10074D03*
Y-74D03*
Y9926D03*
X1183224Y1495595D03*
X1186312Y-20074D03*
Y-10074D03*
Y-74D03*
Y9926D03*
X1200037Y164987D03*
Y160987D03*
X1189727Y177187D03*
X1200012Y185187D03*
X1199419Y790296D03*
Y800335D03*
Y837146D03*
Y827107D03*
Y863918D03*
Y873957D03*
Y900729D03*
Y910768D03*
Y937540D03*
Y947579D03*
Y1084784D03*
Y1094823D03*
Y1121595D03*
Y1131634D03*
Y1158406D03*
Y1168445D03*
Y1195217D03*
Y1205256D03*
Y1232028D03*
Y1242067D03*
X1189924Y1485895D03*
X1199612Y1700334D03*
X1199294Y1721143D03*
X1191351Y1737117D03*
X1215581Y91346D03*
X1202711Y87651D03*
X1215581Y94846D03*
X1213355Y1412564D03*
Y1427564D03*
Y1420064D03*
X1203324Y1505295D03*
X1210024Y1495595D03*
X1214954Y1700343D03*
X1204447Y1707143D03*
X1213351Y1737117D03*
X1223455Y91346D03*
X1230312Y88635D03*
X1215931Y141530D03*
X1218431D03*
X1231118Y142125D03*
X1228355Y1412564D03*
X1220855D03*
X1228355Y1427564D03*
Y1420064D03*
X1220855Y1427564D03*
X1216724Y1485895D03*
X1230124Y1505295D03*
X1235546Y75293D03*
X1232812Y88635D03*
X1239218Y128239D03*
Y137239D03*
Y132739D03*
Y123739D03*
X1238094Y280573D03*
X1233345Y300157D03*
X1242429Y443255D03*
Y447255D03*
X1243524Y1485895D03*
X1236824Y1495595D03*
X1235351Y1737117D03*
X1248286Y-15374D03*
Y-25374D03*
Y14626D03*
X1252561Y72675D03*
X1255185Y140053D03*
Y142553D03*
X1255175Y137553D03*
X1246094Y280573D03*
X1246748Y785752D03*
X1258121Y1342686D03*
X1256924Y1505295D03*
X1257351Y1737117D03*
X1270324Y1485895D03*
X1263624Y1495595D03*
X1278677Y808988D03*
X1283724Y1485895D03*
X1279351Y1737117D03*
X1295532Y539513D03*
X1301666Y555413D03*
X1301351Y1737117D03*
X1319667Y87587D03*
Y105227D03*
X1307857Y111353D03*
X1317986Y1485895D03*
X1311286Y1495595D03*
X1333878Y637721D03*
X1331386Y1505295D03*
X1323351Y1737117D03*
X1344958Y85358D03*
X1336558Y637721D03*
X1339238D03*
X1344438D03*
X1341838D03*
X1344786Y1485895D03*
X1338086Y1495595D03*
X1345351Y1737117D03*
X1356868Y85324D03*
X1360629Y120380D03*
X1363831Y642042D03*
X1361387Y642026D03*
X1356367Y642080D03*
X1352527Y638278D03*
X1360944Y638999D03*
Y636042D03*
X1357717Y647180D03*
Y649780D03*
X1355117D03*
Y647180D03*
X1357717Y644580D03*
X1355117D03*
X1364317Y661368D03*
X1357057Y661328D03*
X1364886Y1495595D03*
X1358186Y1505295D03*
X1369808Y87587D03*
X1382123Y614130D03*
X1374887Y626579D03*
X1372457D03*
X1370027D03*
X1369978Y614164D03*
X1366331Y642042D03*
X1376731Y638935D03*
Y642042D03*
X1371531Y638935D03*
Y642042D03*
Y635978D03*
X1374887Y632179D03*
X1374131Y638935D03*
Y642042D03*
X1368931Y638935D03*
Y642042D03*
Y635978D03*
X1370027Y632179D03*
X1372457D03*
X1371847Y661328D03*
X1366123Y1015473D03*
X1373603D03*
Y1019016D03*
Y1022559D03*
X1366123D03*
Y1019016D03*
X1371586Y1485895D03*
X1367351Y1737117D03*
X1381457Y637865D03*
X1380306Y664816D03*
X1380256Y667466D03*
X1393664Y671949D03*
Y668992D03*
X1390417Y677480D03*
X1389067Y674980D03*
X1387817Y677480D03*
X1394087Y674926D03*
X1390417Y680080D03*
X1387817D03*
X1390417Y682680D03*
X1387817D03*
X1388757Y693397D03*
Y690897D03*
X1381083Y1015473D03*
Y1022559D03*
Y1019016D03*
X1384986Y1505295D03*
X1391686Y1495595D03*
X1389351Y1737117D03*
X1403207Y118938D03*
X1402678Y647064D03*
X1404231Y671835D03*
X1406831D03*
X1409431D03*
X1404231Y668878D03*
X1407587Y665079D03*
X1405157Y659479D03*
X1407587D03*
X1401631Y671835D03*
Y668878D03*
X1402727Y659479D03*
Y665079D03*
X1405157D03*
X1404231Y674942D03*
X1409431D03*
X1406831D03*
X1396531D03*
X1399031D03*
X1401631D03*
X1403693Y1009399D03*
X1407433D03*
X1399953D03*
X1404615Y1014744D03*
X1399953Y1028830D03*
X1407433D03*
X1404615Y1023012D03*
Y1018878D03*
X1403693Y1028830D03*
X1406608Y1282606D03*
X1398386Y1485895D03*
X1414823Y647030D03*
X1414157Y670665D03*
X1416241Y700281D03*
X1416291Y697631D03*
X1420417Y712660D03*
Y715260D03*
Y710060D03*
X1423017Y712660D03*
Y715260D03*
Y710060D03*
X1421667Y707560D03*
X1422757Y726097D03*
Y723597D03*
X1418101Y997765D03*
Y993765D03*
X1418176Y989765D03*
X1418653Y1009399D03*
X1418101Y1001765D03*
X1422394Y1009399D03*
X1414913D03*
X1411173D03*
X1423316Y1014744D03*
X1414458D03*
Y1023012D03*
X1418653Y1028830D03*
X1411173D03*
X1414913D03*
X1423316Y1023012D03*
Y1018878D03*
X1422394Y1028830D03*
X1414458Y1018878D03*
X1411786Y1485895D03*
X1413199Y1643920D03*
X1411351Y1737117D03*
X1438883Y-15050D03*
Y-25050D03*
Y-5050D03*
Y14950D03*
Y4950D03*
X1438312Y152166D03*
X1435278Y679644D03*
X1436257Y676265D03*
X1436831Y701458D03*
X1435327Y692059D03*
X1437757D03*
X1434231Y701458D03*
X1435327Y697659D03*
X1437757D03*
X1426264Y701572D03*
X1436831Y704415D03*
Y707522D03*
X1439431Y704415D03*
Y707522D03*
X1431631D03*
X1429131D03*
X1426687Y707506D03*
X1434231Y704415D03*
Y707522D03*
X1426264Y704529D03*
X1433614Y1009399D03*
X1426134D03*
X1429874D03*
X1433552Y1014744D03*
X1429874Y1028830D03*
X1433552Y1018878D03*
Y1023012D03*
X1426134Y1028830D03*
X1433614D03*
X1433351Y1737117D03*
X1441908Y-26370D03*
X1445161Y-26356D03*
X1441908Y-16370D03*
X1441923Y-13855D03*
X1445161Y-16356D03*
X1445176Y-13841D03*
X1441923Y-23855D03*
X1445176Y-23841D03*
X1441908Y-6370D03*
X1441923Y-3855D03*
X1445161Y-6356D03*
X1445176Y-3841D03*
X1441908Y3630D03*
X1445161Y3644D03*
X1441908Y13630D03*
X1441923Y16145D03*
X1445161Y13644D03*
X1445176Y16159D03*
X1441923Y6145D03*
X1445176Y6159D03*
X1440871Y130118D03*
X1453667Y152166D03*
X1447423Y679610D03*
X1440187Y697659D03*
X1446757Y703265D03*
X1440187Y692059D03*
X1442031Y704415D03*
Y707522D03*
X1453335Y729637D03*
Y732237D03*
Y734837D03*
X1453757Y743597D03*
Y746097D03*
X1454098Y1485895D03*
X1447398Y1495595D03*
X1459177Y163796D03*
X1456282Y568977D03*
Y572977D03*
Y576977D03*
Y580977D03*
X1468196Y699221D03*
X1468245Y711636D03*
Y717236D03*
X1467149Y721035D03*
X1458599Y721045D03*
Y724002D03*
X1455935Y729637D03*
Y732237D03*
X1454585Y727137D03*
X1459605Y727083D03*
X1462049Y727099D03*
X1464549D03*
X1467149Y723992D03*
Y727099D03*
X1455935Y734837D03*
X1467498Y1505295D03*
X1455579Y1636114D03*
X1473105Y717236D03*
X1470675Y711636D03*
X1473105D03*
X1470675Y717236D03*
X1469749Y721035D03*
X1479757Y722865D03*
X1469749Y723992D03*
X1474949D03*
X1472349D03*
Y727099D03*
X1469749D03*
X1474949D03*
X1481665Y745809D03*
X1477177Y803488D03*
X1478177Y817013D03*
X1480898Y1485895D03*
X1474198Y1495595D03*
X1498543Y587841D03*
X1492264Y721149D03*
X1486417Y729637D03*
Y732237D03*
X1489017Y729687D03*
Y732237D03*
X1492264Y724106D03*
X1487667Y727137D03*
X1492687Y727083D03*
X1495131Y727099D03*
X1497631D03*
X1486417Y734837D03*
X1489017D03*
X1484265Y745809D03*
X1489177Y803488D03*
X1498177Y817013D03*
X1494298Y1505295D03*
X1501278Y699221D03*
X1506187Y717236D03*
Y711636D03*
X1501327D03*
X1503757D03*
X1501327Y717404D03*
X1503757D03*
X1502831Y721035D03*
X1500231D03*
X1512757Y722897D03*
X1500231Y723992D03*
X1502831D03*
X1505431D03*
X1508031D03*
X1500231Y727099D03*
X1502831D03*
X1505431D03*
X1508031D03*
X1505905Y746119D03*
X1508505D03*
X1507698Y1485895D03*
X1500998Y1495595D03*
X1499351Y1737117D03*
X1519930Y543470D03*
X1516357Y555318D03*
X1516257Y559977D03*
X1525064Y721149D03*
Y724106D03*
X1521817Y729637D03*
Y732237D03*
X1525487Y727083D03*
X1527931Y727099D03*
X1519217Y729637D03*
Y732237D03*
X1520467Y727137D03*
X1521817Y734837D03*
X1519217D03*
X1515895Y746119D03*
X1518495D03*
X1521098Y1505295D03*
X1527798Y1495595D03*
X1521351Y1737117D03*
X1541580Y-19575D03*
X1541666Y69340D03*
X1532853Y560264D03*
X1534078Y699221D03*
X1536557Y711636D03*
X1534127D03*
X1538987Y717236D03*
Y711636D03*
X1534127Y717236D03*
X1536557D03*
X1535631Y721035D03*
X1533031D03*
X1538231Y723992D03*
X1540831D03*
X1538231Y727099D03*
X1540831D03*
X1530431D03*
X1533031Y723992D03*
X1535631D03*
X1533031Y727099D03*
X1535631D03*
X1543563Y757803D03*
X1543585Y762919D03*
X1543574Y760361D03*
X1534317Y1216828D03*
X1531227Y1227648D03*
X1540227D03*
X1534498Y1485895D03*
X1543351Y1737117D03*
X1554510Y28406D03*
X1547424D03*
X1554510Y40020D03*
X1547424D03*
X1552662Y75343D03*
X1546257Y701097D03*
X1558194Y702166D03*
Y699209D03*
X1552347Y712897D03*
X1554947D03*
X1552347Y710297D03*
Y707697D03*
X1554947Y710297D03*
Y707697D03*
X1553597Y705197D03*
X1558617Y705143D03*
X1551250Y723840D03*
X1553750D03*
X1545557Y722897D03*
X1556555Y740617D03*
X1556544Y738059D03*
X1554055Y740617D03*
X1554044Y738059D03*
X1546965Y746119D03*
X1546954Y743561D03*
X1548119Y751952D03*
X1545619D03*
X1548119Y754832D03*
X1545619D03*
X1546063Y757803D03*
X1546085Y762919D03*
X1546074Y760361D03*
X1549877Y1217288D03*
Y1221288D03*
X1547898Y1485895D03*
X1561597Y28406D03*
X1568683D03*
Y40020D03*
X1561597D03*
X1563666Y69340D03*
X1567208Y677281D03*
X1572117Y695296D03*
X1568761Y702052D03*
X1571361D03*
X1568761Y699095D03*
X1566161Y702052D03*
Y699095D03*
X1569687Y689696D03*
X1572117D03*
X1567257D03*
Y695296D03*
X1569687D03*
X1563561Y705159D03*
X1561061D03*
X1568761D03*
X1571361D03*
X1566161D03*
X1568660Y1283460D03*
X1572036Y1306083D03*
X1565351Y1737117D03*
X1575770Y28406D03*
X1582857D03*
Y40020D03*
X1575770D03*
X1574666Y75340D03*
X1585666Y69340D03*
X1579748Y536344D03*
X1576843Y674425D03*
X1579807Y671268D03*
X1586367Y671428D03*
X1587717Y676528D03*
Y673928D03*
X1585117Y676528D03*
Y673928D03*
Y679128D03*
X1587717D03*
X1578757Y700965D03*
X1573961Y702052D03*
X1586070Y696830D03*
Y694330D03*
X1573961Y705159D03*
X1578904Y721340D03*
Y723840D03*
X1584849Y793506D03*
X1587028Y1307137D03*
X1582160Y1485895D03*
X1575460Y1495595D03*
X1587351Y1737117D03*
X1589943Y28406D03*
X1597030D03*
Y40020D03*
X1589943D03*
X1596666Y75340D03*
X1599837Y295328D03*
X1593214Y531226D03*
X1599978Y643512D03*
X1600027Y655927D03*
X1602457D03*
X1591387Y671374D03*
X1593831Y671390D03*
X1596331D03*
X1601531D03*
Y668283D03*
Y665326D03*
X1598931Y671390D03*
Y668283D03*
Y665326D03*
X1600027Y661527D03*
X1602457D03*
X1590964Y668397D03*
Y665440D03*
X1594539Y1295288D03*
X1595560Y1505295D03*
X1602260Y1495595D03*
X1604117Y28406D03*
Y40020D03*
X1607666Y69343D03*
X1609355Y592794D03*
X1615677Y648488D03*
X1604887Y655927D03*
X1618117Y657528D03*
Y654928D03*
X1611557Y667165D03*
X1606731Y671390D03*
Y668283D03*
X1604131Y671390D03*
Y668283D03*
X1604887Y661527D03*
X1618117Y660128D03*
X1613154Y688238D03*
Y690738D03*
X1605447Y1288748D03*
X1608960Y1485895D03*
X1609351Y1737117D03*
X1632896Y28406D03*
X1625809D03*
X1632896Y40020D03*
X1625809D03*
X1618666Y75340D03*
X1631558Y588513D03*
X1628756Y588591D03*
X1624067Y588474D03*
X1621187Y588591D03*
X1632978Y624512D03*
X1633027Y636927D03*
Y642527D03*
X1620717Y657528D03*
X1631931Y652390D03*
Y649283D03*
X1626831Y652390D03*
X1629331D03*
X1631931Y646326D03*
X1624387Y652374D03*
X1619367Y652428D03*
X1620717Y654928D03*
X1623964Y649397D03*
Y646440D03*
X1621050Y671768D03*
X1623550D03*
X1620717Y660128D03*
X1628946Y790296D03*
Y800335D03*
Y827107D03*
Y837146D03*
Y863918D03*
Y873957D03*
Y900729D03*
Y910768D03*
Y937540D03*
Y947579D03*
Y1084784D03*
Y1094823D03*
Y1121595D03*
Y1131634D03*
Y1158406D03*
Y1168445D03*
Y1195217D03*
Y1205256D03*
Y1232028D03*
Y1242067D03*
X1629060Y1495595D03*
X1622360Y1505295D03*
X1631351Y1737117D03*
X1647069Y28406D03*
X1639983D03*
X1647069Y40020D03*
X1639983D03*
X1641870Y75340D03*
X1645123Y624478D03*
X1637887Y642527D03*
Y636927D03*
X1635457D03*
Y642527D03*
X1644457Y648265D03*
X1639731Y652390D03*
X1634531D03*
X1637131D03*
X1639731Y649283D03*
X1634531D03*
X1637131D03*
X1634531Y646326D03*
X1643183Y1419441D03*
X1643283Y1431541D03*
X1635760Y1485895D03*
X1654156Y28406D03*
Y40020D03*
X1652870Y69340D03*
X1650917Y657528D03*
Y654928D03*
X1653517Y657528D03*
X1652167Y652428D03*
X1653517Y654928D03*
X1648604Y671768D03*
X1650917Y660128D03*
X1659618Y659021D03*
X1662298D03*
X1651104Y671768D03*
X1653517Y660128D03*
X1656938Y659021D03*
X1651959Y689800D03*
X1658647Y790296D03*
Y800335D03*
Y827107D03*
Y837146D03*
Y863918D03*
Y873957D03*
Y900729D03*
Y910768D03*
Y937540D03*
Y947579D03*
Y1084784D03*
Y1094823D03*
Y1121595D03*
Y1131634D03*
Y1158406D03*
Y1168445D03*
Y1205256D03*
Y1195217D03*
Y1232028D03*
Y1242067D03*
X1649283Y1419441D03*
Y1431541D03*
X1655383D03*
Y1419441D03*
X1655957Y1445116D03*
X1662560Y1485895D03*
X1649160Y1505295D03*
X1655860Y1495595D03*
X1653351Y1737117D03*
X1677030Y28406D03*
X1669943D03*
X1677030Y40020D03*
X1669943D03*
X1663866Y75343D03*
X1674870Y69340D03*
X1668516Y599956D03*
X1674516D03*
X1668516Y609450D03*
X1671516Y599956D03*
X1674516Y609450D03*
X1677516Y599956D03*
X1671516Y609450D03*
X1677516D03*
X1667498Y659021D03*
X1664898D03*
X1675960Y1485895D03*
X1668000Y1711759D03*
Y1726909D03*
X1675351Y1737117D03*
X1684117Y28406D03*
X1691203D03*
Y40020D03*
X1684117D03*
X1686004Y75340D03*
X1688348Y790296D03*
Y800335D03*
Y827107D03*
Y837146D03*
Y863918D03*
Y873957D03*
Y910768D03*
Y900729D03*
Y937540D03*
Y947579D03*
Y1084784D03*
Y1094823D03*
Y1131634D03*
Y1121595D03*
Y1158406D03*
Y1168445D03*
Y1205256D03*
Y1195217D03*
Y1232028D03*
Y1242067D03*
X1684677Y1440258D03*
X1687357Y1440268D03*
X1698290Y28406D03*
X1705376D03*
X1698290Y40020D03*
X1697000Y69343D03*
X1701121Y641658D03*
X1706101D03*
X1695529Y1545193D03*
X1703000Y1711759D03*
X1697351Y1737117D03*
X1708004Y75340D03*
X1708305Y679720D03*
X1718049Y790296D03*
Y800335D03*
Y827107D03*
Y837146D03*
Y863918D03*
Y873957D03*
Y910768D03*
Y900729D03*
Y937540D03*
Y947579D03*
Y1084784D03*
Y1094823D03*
Y1131634D03*
Y1121595D03*
Y1158406D03*
Y1168445D03*
Y1195217D03*
Y1205256D03*
Y1232028D03*
Y1242067D03*
X1719351Y1737117D03*
X1735375Y-40925D03*
X1732350Y-39605D03*
X1735390Y-38410D03*
X1738628Y-40911D03*
X1738658Y-35881D03*
X1738673Y-33366D03*
X1738643Y-38396D03*
X1749571Y255317D03*
Y252317D03*
X1745502Y660088D03*
X1747750Y790296D03*
Y800335D03*
Y827107D03*
Y837146D03*
Y863918D03*
Y873957D03*
Y910768D03*
Y900729D03*
Y937540D03*
Y947579D03*
Y1084784D03*
Y1094823D03*
Y1131634D03*
Y1121595D03*
Y1158406D03*
Y1168445D03*
Y1205256D03*
Y1195217D03*
Y1232028D03*
Y1242067D03*
X1742120Y1708265D03*
Y1723415D03*
X1741351Y1737117D03*
X1753388Y28406D03*
X1760475D03*
X1754364Y100353D03*
X1764644Y122973D03*
X1755969Y251524D03*
Y248524D03*
X1763509Y251341D03*
Y248341D03*
X1763351Y1737117D03*
X1771881Y128439D03*
Y125939D03*
Y123439D03*
X1781966Y128501D03*
Y126001D03*
Y123501D03*
X1775984Y253779D03*
Y256779D03*
X1777450Y790296D03*
Y800335D03*
Y827107D03*
Y837146D03*
Y863918D03*
Y873957D03*
Y910768D03*
Y900729D03*
Y937540D03*
Y947579D03*
Y1084784D03*
Y1094823D03*
Y1131634D03*
Y1121595D03*
Y1158406D03*
Y1168445D03*
Y1205256D03*
Y1195217D03*
Y1232028D03*
Y1242067D03*
X1785072Y53161D03*
X1789811Y178083D03*
X1794629Y193323D03*
X1791645Y193397D03*
X1795219Y185910D03*
X1795949Y205580D03*
X1795909Y209128D03*
X1795365Y197567D03*
X1796019Y202030D03*
X1791445Y197497D03*
X1783592Y763765D03*
X1804111Y178083D03*
X1807711D03*
Y175083D03*
X1803165Y196127D03*
X1797621Y193373D03*
X1800389Y193424D03*
X1803045Y193397D03*
X1798943Y204744D03*
Y209044D03*
X1802276Y209013D03*
X1805235Y208950D03*
X1802276Y204713D03*
X1800125Y201857D03*
X1805235Y204650D03*
X1799629Y198870D03*
X1803145Y198697D03*
X1817674Y188699D03*
X1829732Y367359D03*
G54D24*
X67725Y1538946D03*
X74912D03*
X72585D03*
X70155D03*
X103468D03*
X105898D03*
X108328D03*
X110655D03*
X1757438Y1571982D03*
X1755008D03*
X1762195D03*
X1759868D03*
X1793181D03*
X1790751D03*
X1795611D03*
X1797938D03*
G54D28*
X130000Y1719450D03*
X543277Y88632D03*
X538620Y93289D03*
G54D64*
X1156378Y133866D03*
X1183858Y207205D03*
X1173858D03*
X1193858D03*
X1351260Y164213D03*
Y174213D03*
X1361260Y164213D03*
Y174213D03*
X1371260Y164213D03*
X1381260D03*
X1371260Y174213D03*
X1381260D03*
X1391260Y164213D03*
Y174213D03*
G54D20*
X50880Y1415563D03*
Y1418963D03*
X58349Y1406331D03*
Y1409731D03*
X78265Y26477D03*
X74865D03*
X81970Y19541D03*
X85370D03*
X92438Y26477D03*
X89038D03*
X96143Y19541D03*
X90965Y960966D03*
X99543Y19541D03*
X106611Y26477D03*
X103211D03*
X110316Y19541D03*
X99024Y780257D03*
Y786950D03*
Y803682D03*
Y793643D03*
Y796989D03*
Y817068D03*
Y810375D03*
Y823761D03*
Y830454D03*
Y833800D03*
Y840493D03*
Y847186D03*
Y853879D03*
Y860572D03*
Y877304D03*
Y867265D03*
Y870611D03*
Y883997D03*
Y890690D03*
Y897383D03*
Y904076D03*
Y907423D03*
Y914115D03*
Y920808D03*
Y927501D03*
Y934194D03*
Y940887D03*
Y950926D03*
Y944234D03*
Y964312D03*
Y957619D03*
Y971005D03*
Y977698D03*
Y984391D03*
Y1001123D03*
Y997777D03*
Y991084D03*
Y1031241D03*
Y1037934D03*
Y1044627D03*
Y1058013D03*
Y1051320D03*
Y1074745D03*
Y1081438D03*
Y1088131D03*
Y1098171D03*
Y1104863D03*
Y1091478D03*
Y1111556D03*
Y1118249D03*
Y1134982D03*
Y1124942D03*
Y1128289D03*
Y1148367D03*
Y1141675D03*
Y1155060D03*
Y1161753D03*
Y1165100D03*
Y1171793D03*
Y1178486D03*
Y1185178D03*
Y1191871D03*
Y1208604D03*
Y1198564D03*
Y1201911D03*
Y1215297D03*
Y1221989D03*
Y1228682D03*
Y1235375D03*
Y1238722D03*
Y1245415D03*
Y1252108D03*
X112473Y1660235D03*
X109073D03*
X107569Y1685763D03*
X110969D03*
X113716Y19541D03*
X120785Y26477D03*
X117385D03*
X124490Y19541D03*
X115166Y776911D03*
Y783604D03*
Y790297D03*
Y800336D03*
Y807029D03*
Y793643D03*
Y813722D03*
Y820415D03*
Y837147D03*
Y830454D03*
Y827108D03*
Y843840D03*
Y850533D03*
Y857226D03*
Y863919D03*
Y873958D03*
Y880651D03*
Y867265D03*
Y887344D03*
Y894037D03*
Y910769D03*
Y904076D03*
Y900730D03*
Y924155D03*
Y917462D03*
Y930848D03*
Y940887D03*
Y937541D03*
Y947580D03*
Y954273D03*
Y967659D03*
Y974352D03*
Y981045D03*
Y987737D03*
Y994430D03*
Y1001123D03*
Y1027895D03*
Y1034588D03*
Y1041281D03*
Y1047974D03*
Y1054667D03*
Y1061360D03*
Y1071399D03*
Y1064706D03*
Y1078092D03*
Y1088131D03*
Y1084785D03*
Y1094824D03*
Y1101517D03*
Y1108210D03*
Y1114903D03*
Y1131635D03*
Y1124942D03*
Y1121596D03*
Y1138328D03*
Y1145021D03*
Y1151714D03*
Y1161753D03*
Y1158407D03*
Y1168446D03*
Y1175139D03*
Y1181832D03*
Y1188525D03*
Y1205257D03*
Y1198564D03*
Y1195218D03*
Y1211950D03*
Y1218643D03*
Y1225336D03*
Y1235375D03*
Y1232029D03*
Y1242068D03*
Y1248761D03*
X127890Y19541D03*
X128724Y780257D03*
Y786950D03*
Y803682D03*
Y793643D03*
Y796989D03*
Y817068D03*
Y810375D03*
Y823761D03*
Y830454D03*
Y833800D03*
Y840493D03*
Y847186D03*
Y853879D03*
Y860572D03*
Y877304D03*
Y867265D03*
Y870611D03*
Y883997D03*
Y890690D03*
Y897383D03*
Y904076D03*
Y907423D03*
Y914115D03*
Y920808D03*
Y927501D03*
Y934194D03*
Y940887D03*
Y950926D03*
Y944234D03*
Y964312D03*
Y957619D03*
Y971005D03*
Y977698D03*
Y984391D03*
Y1001123D03*
Y997777D03*
Y991084D03*
Y1031241D03*
Y1037934D03*
Y1044627D03*
Y1058013D03*
Y1051320D03*
Y1074745D03*
Y1081438D03*
Y1088131D03*
Y1098171D03*
Y1104863D03*
Y1091478D03*
Y1111556D03*
Y1118249D03*
Y1134982D03*
Y1124942D03*
Y1128289D03*
Y1148367D03*
Y1141675D03*
Y1155060D03*
Y1161753D03*
Y1165100D03*
Y1171793D03*
Y1178486D03*
Y1185178D03*
Y1191871D03*
Y1208604D03*
Y1198564D03*
Y1201911D03*
Y1215297D03*
Y1221989D03*
Y1228682D03*
Y1235375D03*
Y1238722D03*
Y1245415D03*
Y1252108D03*
X156651Y26477D03*
X153251D03*
X144866Y776911D03*
Y783604D03*
Y790297D03*
Y800336D03*
Y807029D03*
Y793643D03*
Y813722D03*
Y820415D03*
Y837147D03*
Y830454D03*
Y827108D03*
Y843840D03*
Y850533D03*
Y857226D03*
Y863919D03*
Y873958D03*
Y880651D03*
Y867265D03*
Y887344D03*
Y894037D03*
Y910769D03*
Y904076D03*
Y900730D03*
Y924155D03*
Y917462D03*
Y930848D03*
Y940887D03*
Y937541D03*
Y947580D03*
Y954273D03*
Y967659D03*
Y974352D03*
Y981045D03*
Y987737D03*
Y994430D03*
Y1001123D03*
Y1027895D03*
Y1034588D03*
Y1041281D03*
Y1047974D03*
Y1054667D03*
Y1061360D03*
Y1071399D03*
Y1064706D03*
Y1078092D03*
Y1088131D03*
Y1084785D03*
Y1094824D03*
Y1101517D03*
Y1108210D03*
Y1114903D03*
Y1131635D03*
Y1124942D03*
Y1121596D03*
Y1138328D03*
Y1145021D03*
Y1151714D03*
Y1161753D03*
Y1158407D03*
Y1168446D03*
Y1175139D03*
Y1181832D03*
Y1188525D03*
Y1205257D03*
Y1198564D03*
Y1195218D03*
Y1211950D03*
Y1218643D03*
Y1225336D03*
Y1235375D03*
Y1232029D03*
Y1242068D03*
Y1248761D03*
X170824Y26477D03*
X163756Y19541D03*
X167424Y26477D03*
X160356Y19541D03*
X158425Y780257D03*
Y786950D03*
Y803682D03*
Y793643D03*
Y796989D03*
Y817068D03*
Y810375D03*
Y823761D03*
Y830454D03*
Y833800D03*
Y840493D03*
Y847186D03*
Y853879D03*
Y860572D03*
Y877304D03*
Y867265D03*
Y870611D03*
Y883997D03*
Y890690D03*
Y897383D03*
Y904076D03*
Y907423D03*
Y914115D03*
Y920808D03*
Y927501D03*
Y934194D03*
Y940887D03*
Y950926D03*
Y944234D03*
Y964312D03*
Y957619D03*
Y971005D03*
Y977698D03*
Y984391D03*
Y1001123D03*
Y997777D03*
Y991084D03*
Y1031241D03*
Y1037934D03*
Y1044627D03*
Y1058013D03*
Y1051320D03*
Y1074745D03*
Y1081438D03*
Y1088131D03*
Y1098171D03*
Y1104863D03*
Y1091478D03*
Y1111556D03*
Y1118249D03*
Y1134982D03*
Y1124942D03*
Y1128289D03*
Y1148367D03*
Y1141675D03*
Y1155060D03*
Y1161753D03*
Y1165100D03*
Y1171793D03*
Y1178486D03*
Y1185178D03*
Y1191871D03*
Y1208604D03*
Y1198564D03*
Y1201911D03*
Y1215297D03*
Y1221989D03*
Y1228682D03*
Y1235375D03*
Y1238722D03*
Y1245415D03*
Y1252108D03*
X169351Y1462595D03*
X163113Y1483590D03*
Y1480190D03*
Y1501990D03*
Y1505390D03*
X177929Y19541D03*
X174529D03*
X174567Y776911D03*
Y783604D03*
Y790297D03*
Y800336D03*
Y807029D03*
Y793643D03*
Y813722D03*
Y820415D03*
Y837147D03*
Y830454D03*
Y827108D03*
Y843840D03*
Y850533D03*
Y857226D03*
Y863919D03*
Y873958D03*
Y880651D03*
Y867265D03*
Y887344D03*
Y894037D03*
Y910769D03*
Y904076D03*
Y900730D03*
Y924155D03*
Y917462D03*
Y930848D03*
Y940887D03*
Y937541D03*
Y947580D03*
Y954273D03*
Y967659D03*
Y974352D03*
Y981045D03*
Y987737D03*
Y994430D03*
Y1001123D03*
Y1027895D03*
Y1034588D03*
Y1041281D03*
Y1047974D03*
Y1054667D03*
Y1061360D03*
Y1071399D03*
Y1064706D03*
Y1078092D03*
Y1088131D03*
Y1084785D03*
Y1094824D03*
Y1101517D03*
Y1108210D03*
Y1114903D03*
Y1131635D03*
Y1124942D03*
Y1121596D03*
Y1138328D03*
Y1145021D03*
Y1151714D03*
Y1161753D03*
Y1158407D03*
Y1168446D03*
Y1175139D03*
Y1181832D03*
Y1188525D03*
Y1205257D03*
Y1198564D03*
Y1195218D03*
Y1211950D03*
Y1218643D03*
Y1225336D03*
Y1235375D03*
Y1232029D03*
Y1242068D03*
Y1248761D03*
X172751Y1462595D03*
X179451Y1452895D03*
X176051D03*
X200785Y26477D03*
X197385D03*
X199551Y1462595D03*
X196151D03*
X192851Y1472295D03*
X189451D03*
X188166Y1592380D03*
X200226D03*
X191566D03*
X194196Y1602380D03*
X197596D03*
X207890Y19541D03*
X214958Y26477D03*
X204490Y19541D03*
X211558Y26477D03*
X209768Y960966D03*
X206251Y1452895D03*
X202851D03*
X216251Y1472295D03*
X212286Y1592380D03*
X203626D03*
X215686D03*
X206256Y1602380D03*
X209656D03*
X222063Y19541D03*
X218663D03*
X226351Y1462595D03*
X222951D03*
X229651Y1452895D03*
X219651Y1472295D03*
X224346Y1592380D03*
X227746D03*
X218316Y1602380D03*
X230376D03*
X221716D03*
X233051Y1452895D03*
X246451Y1472295D03*
X243051D03*
X236406Y1592380D03*
X239806D03*
X242436Y1602380D03*
X233776D03*
X245836D03*
X253151Y1462595D03*
X259851Y1452895D03*
X249751Y1462595D03*
X256451Y1452895D03*
X248466Y1592380D03*
X260526D03*
X251866D03*
X254496Y1602380D03*
X257896D03*
X269851Y1452895D03*
X273251D03*
X272586Y1592380D03*
X263926D03*
X275986D03*
X266556Y1602380D03*
X269956D03*
X280621Y1484082D03*
Y1480682D03*
X291175Y1483590D03*
Y1480190D03*
X280621Y1497482D03*
Y1494082D03*
X291175Y1501990D03*
Y1505390D03*
X284646Y1592380D03*
X288046D03*
X278616Y1602380D03*
X290676D03*
X282016D03*
X300813Y1462595D03*
X297413D03*
X304113Y1452895D03*
X296706Y1592380D03*
X300106D03*
X302736Y1602380D03*
X294076D03*
X306136D03*
X307513Y1452895D03*
X320913Y1472295D03*
X317513D03*
X308766Y1592380D03*
X320826D03*
X312166D03*
X314796Y1602380D03*
X318196D03*
X327613Y1462595D03*
X334313Y1452895D03*
X324213Y1462595D03*
X330913Y1452895D03*
X332886Y1592380D03*
X324226D03*
X326856Y1602380D03*
X330256D03*
X351013Y1462595D03*
X347713Y1472295D03*
X344313D03*
X344946Y1592380D03*
X336286D03*
X348346D03*
X338916Y1602380D03*
X350976D03*
X342316D03*
X354413Y1462595D03*
X361113Y1452895D03*
X357713D03*
X357006Y1592380D03*
X360406D03*
X363036Y1602380D03*
X354376D03*
X371999Y819527D03*
X372000Y831797D03*
Y835197D03*
X371999Y822927D03*
X372000Y846427D03*
Y843027D03*
X377813Y1462595D03*
X374513Y1472295D03*
X371113D03*
X369066Y1592380D03*
X372466D03*
X375096Y1602380D03*
X366436D03*
X378496D03*
X390841Y-25571D03*
Y-22171D03*
Y-15571D03*
Y-12171D03*
X385001Y816927D03*
Y813527D03*
X381213Y1462595D03*
X387913Y1452895D03*
X384513D03*
X400426Y112815D03*
Y116215D03*
X405606Y125815D03*
Y129715D03*
X401313Y1452895D03*
X397913D03*
X408683Y1480682D03*
Y1484082D03*
Y1497482D03*
Y1494082D03*
X455502Y88711D03*
X452102D03*
X448414Y94684D03*
X445014D03*
X452339Y1592380D03*
X464399D03*
X455739D03*
X467799D03*
X476295Y130020D03*
X472895D03*
X476459Y1592380D03*
X479859D03*
X488519D03*
X491919D03*
X514240Y97146D03*
X500579Y1592380D03*
X512639D03*
X503979D03*
X526460Y100895D03*
Y97495D03*
X517640Y97146D03*
X524699Y1592380D03*
X516039D03*
X528099D03*
X536759D03*
X540159D03*
X559069Y105385D03*
Y101985D03*
X548819Y1592380D03*
X552219D03*
X572939D03*
X560879D03*
X564279D03*
X584999D03*
X576339D03*
X588399D03*
X597059D03*
X600459D03*
X609119D03*
X612519D03*
X621179D03*
X633239D03*
X624579D03*
X636639D03*
X653999Y1426757D03*
Y1423357D03*
X687697Y960966D03*
X691276Y1455112D03*
X704771Y179599D03*
Y182999D03*
Y194810D03*
Y191410D03*
Y206621D03*
Y203221D03*
Y218432D03*
Y215032D03*
X706756Y780257D03*
Y786950D03*
Y803682D03*
Y793643D03*
Y796989D03*
Y817068D03*
Y810375D03*
Y823761D03*
Y830454D03*
Y833800D03*
Y840493D03*
Y847186D03*
Y853879D03*
Y860572D03*
Y877304D03*
Y867265D03*
Y870611D03*
Y883997D03*
Y890690D03*
Y897383D03*
Y904076D03*
Y907423D03*
Y914115D03*
Y920808D03*
Y927501D03*
Y934194D03*
Y940887D03*
Y950926D03*
Y944234D03*
Y964312D03*
Y957619D03*
Y971005D03*
Y977698D03*
Y984391D03*
Y1001123D03*
Y997777D03*
Y991084D03*
Y1031241D03*
Y1037934D03*
Y1044627D03*
Y1058013D03*
Y1051320D03*
Y1074745D03*
Y1081438D03*
Y1088131D03*
Y1098171D03*
Y1104863D03*
Y1091478D03*
Y1111556D03*
Y1118249D03*
Y1134982D03*
Y1124942D03*
Y1128289D03*
Y1148367D03*
Y1141675D03*
Y1155060D03*
Y1161753D03*
Y1165100D03*
Y1171793D03*
Y1178486D03*
Y1185178D03*
Y1191871D03*
Y1208604D03*
Y1198564D03*
Y1201911D03*
Y1215297D03*
Y1221989D03*
Y1228682D03*
Y1235375D03*
Y1238722D03*
Y1245415D03*
Y1252108D03*
X694676Y1455112D03*
X716699Y177087D03*
Y173687D03*
Y189087D03*
Y185687D03*
Y200587D03*
Y197187D03*
Y209021D03*
Y212421D03*
X722898Y776911D03*
Y783604D03*
Y790297D03*
Y800336D03*
Y807029D03*
Y793643D03*
Y813722D03*
Y820415D03*
Y837147D03*
Y830454D03*
Y827108D03*
Y843840D03*
Y850533D03*
Y857226D03*
Y863919D03*
Y873958D03*
Y880651D03*
Y867265D03*
Y887344D03*
Y894037D03*
Y910769D03*
Y904076D03*
Y900730D03*
Y924155D03*
Y917462D03*
Y930848D03*
Y940887D03*
Y937541D03*
Y947580D03*
Y954273D03*
Y967659D03*
Y974352D03*
Y981045D03*
Y987737D03*
Y994430D03*
Y1001123D03*
Y1027895D03*
Y1034588D03*
Y1041281D03*
Y1047974D03*
Y1054667D03*
Y1061360D03*
Y1071399D03*
Y1064706D03*
Y1078092D03*
Y1088131D03*
Y1084785D03*
Y1094824D03*
Y1101517D03*
Y1108210D03*
Y1114903D03*
Y1131635D03*
Y1124942D03*
Y1121596D03*
Y1138328D03*
Y1145021D03*
Y1151714D03*
Y1161753D03*
Y1158407D03*
Y1168446D03*
Y1175139D03*
Y1181832D03*
Y1188525D03*
Y1205257D03*
Y1198564D03*
Y1195218D03*
Y1211950D03*
Y1218643D03*
Y1225336D03*
Y1235375D03*
Y1232029D03*
Y1242068D03*
Y1248761D03*
X725925Y-25571D03*
Y-22171D03*
Y-15571D03*
Y-12171D03*
X736457Y780257D03*
Y786950D03*
Y803682D03*
Y793643D03*
Y796989D03*
Y817068D03*
Y810375D03*
Y823761D03*
Y830454D03*
Y833800D03*
Y840493D03*
Y847186D03*
Y853879D03*
Y860572D03*
Y877304D03*
Y867265D03*
Y870611D03*
Y883997D03*
Y890690D03*
Y897383D03*
Y904076D03*
Y907423D03*
Y914115D03*
Y920808D03*
Y927501D03*
Y934194D03*
Y940887D03*
Y950926D03*
Y944234D03*
Y964312D03*
Y957619D03*
Y971005D03*
Y977698D03*
Y984391D03*
Y1001123D03*
Y997777D03*
Y991084D03*
Y1031241D03*
Y1037934D03*
Y1044627D03*
Y1058013D03*
Y1051320D03*
Y1074745D03*
Y1081438D03*
Y1088131D03*
Y1098171D03*
Y1104863D03*
Y1091478D03*
Y1111556D03*
Y1118249D03*
Y1134982D03*
Y1124942D03*
Y1128289D03*
Y1148367D03*
Y1141675D03*
Y1155060D03*
Y1161753D03*
Y1165100D03*
Y1171793D03*
Y1178486D03*
Y1185178D03*
Y1191871D03*
Y1208604D03*
Y1198564D03*
Y1201911D03*
Y1215297D03*
Y1221989D03*
Y1228682D03*
Y1235375D03*
Y1238722D03*
Y1245415D03*
Y1252108D03*
X752599Y776911D03*
Y783604D03*
Y790297D03*
Y800336D03*
Y807029D03*
Y793643D03*
Y813722D03*
Y820415D03*
Y837147D03*
Y830454D03*
Y827108D03*
Y843840D03*
Y850533D03*
Y857226D03*
Y863919D03*
Y873958D03*
Y880651D03*
Y867265D03*
Y887344D03*
Y894037D03*
Y910769D03*
Y904076D03*
Y900730D03*
Y924155D03*
Y917462D03*
Y930848D03*
Y940887D03*
Y937541D03*
Y947580D03*
Y954273D03*
Y967659D03*
Y974352D03*
Y981045D03*
Y987737D03*
Y994430D03*
Y1001123D03*
Y1027895D03*
Y1034588D03*
Y1041281D03*
Y1047974D03*
Y1054667D03*
Y1061360D03*
Y1071399D03*
Y1064706D03*
Y1078092D03*
Y1088131D03*
Y1084785D03*
Y1094824D03*
Y1101517D03*
Y1108210D03*
Y1114903D03*
Y1131635D03*
Y1124942D03*
Y1121596D03*
Y1138328D03*
Y1145021D03*
Y1151714D03*
Y1161753D03*
Y1158407D03*
Y1168446D03*
Y1175139D03*
Y1181832D03*
Y1188525D03*
Y1205257D03*
Y1198564D03*
Y1195218D03*
Y1211950D03*
Y1218643D03*
Y1225336D03*
Y1235375D03*
Y1232029D03*
Y1242068D03*
Y1248761D03*
X766158Y780257D03*
Y786950D03*
Y803682D03*
Y793643D03*
Y796989D03*
Y817068D03*
Y810375D03*
Y823761D03*
Y830454D03*
Y833800D03*
Y840493D03*
Y847186D03*
Y853879D03*
Y860572D03*
Y877304D03*
Y867265D03*
Y870611D03*
Y883997D03*
Y890690D03*
Y897383D03*
Y904076D03*
Y907423D03*
Y914115D03*
Y920808D03*
Y927501D03*
Y934194D03*
Y940887D03*
Y950926D03*
Y944234D03*
Y964312D03*
Y957619D03*
Y971005D03*
Y977698D03*
Y984391D03*
Y1001123D03*
Y997777D03*
Y991084D03*
Y1031241D03*
Y1037934D03*
Y1044627D03*
Y1058013D03*
Y1051320D03*
Y1074745D03*
Y1081438D03*
Y1088131D03*
Y1098171D03*
Y1104863D03*
Y1091478D03*
Y1111556D03*
Y1118249D03*
Y1134982D03*
Y1124942D03*
Y1128289D03*
Y1148367D03*
Y1141675D03*
Y1155060D03*
Y1161753D03*
Y1165100D03*
Y1171793D03*
Y1178486D03*
Y1185178D03*
Y1191871D03*
Y1208604D03*
Y1198564D03*
Y1201911D03*
Y1215297D03*
Y1221989D03*
Y1228682D03*
Y1235375D03*
Y1238722D03*
Y1245415D03*
Y1252108D03*
X782300Y776911D03*
Y783604D03*
Y790297D03*
Y800336D03*
Y807029D03*
Y793643D03*
Y813722D03*
Y820415D03*
Y837147D03*
Y830454D03*
Y827108D03*
Y843840D03*
Y850533D03*
Y857226D03*
Y863919D03*
Y873958D03*
Y880651D03*
Y867265D03*
Y887344D03*
Y894037D03*
Y910769D03*
Y904076D03*
Y900730D03*
Y924155D03*
Y917462D03*
Y930848D03*
Y940887D03*
Y937541D03*
Y947580D03*
Y954273D03*
Y967659D03*
Y974352D03*
Y981045D03*
Y987737D03*
Y994430D03*
Y1001123D03*
Y1027895D03*
Y1034588D03*
Y1041281D03*
Y1047974D03*
Y1054667D03*
Y1061360D03*
Y1071399D03*
Y1064706D03*
Y1078092D03*
Y1088131D03*
Y1084785D03*
Y1094824D03*
Y1101517D03*
Y1108210D03*
Y1114903D03*
Y1131635D03*
Y1124942D03*
Y1121596D03*
Y1138328D03*
Y1145021D03*
Y1151714D03*
Y1161753D03*
Y1158407D03*
Y1168446D03*
Y1175139D03*
Y1181832D03*
Y1188525D03*
Y1205257D03*
Y1198564D03*
Y1195218D03*
Y1211950D03*
Y1218643D03*
Y1225336D03*
Y1235375D03*
Y1232029D03*
Y1242068D03*
Y1248761D03*
X806500Y960966D03*
X814296Y1384045D03*
Y1387445D03*
X842320Y-21711D03*
Y-18311D03*
Y-11711D03*
Y-8311D03*
Y11689D03*
Y8289D03*
Y18289D03*
Y21689D03*
X1007587Y805418D03*
Y816352D03*
Y819752D03*
Y808818D03*
Y827354D03*
Y830754D03*
Y838356D03*
Y841756D03*
X1075166Y780256D03*
Y786949D03*
Y803681D03*
Y793642D03*
Y796988D03*
Y817067D03*
Y810374D03*
Y823760D03*
Y830453D03*
Y833799D03*
Y840492D03*
Y847185D03*
Y853878D03*
Y860571D03*
Y877303D03*
Y867264D03*
Y870610D03*
Y883996D03*
Y890689D03*
Y897382D03*
Y904075D03*
Y907422D03*
Y914114D03*
Y920807D03*
Y927500D03*
Y934193D03*
Y940886D03*
Y950925D03*
Y944233D03*
Y964311D03*
Y957618D03*
Y971004D03*
X1067107Y960965D03*
X1075166Y977697D03*
Y984390D03*
Y1001122D03*
Y997776D03*
Y991083D03*
Y1031240D03*
Y1037933D03*
Y1044626D03*
Y1058012D03*
Y1051319D03*
Y1074744D03*
Y1081437D03*
Y1088130D03*
Y1098170D03*
Y1104862D03*
Y1091477D03*
Y1111555D03*
Y1118248D03*
Y1134981D03*
Y1124941D03*
Y1128288D03*
Y1148366D03*
Y1141674D03*
Y1155059D03*
Y1161752D03*
Y1165099D03*
Y1171792D03*
Y1178485D03*
Y1185177D03*
Y1191870D03*
Y1208603D03*
Y1198563D03*
Y1201910D03*
Y1215296D03*
Y1221988D03*
Y1228681D03*
Y1235374D03*
Y1238721D03*
Y1245414D03*
Y1252107D03*
X1091308Y776910D03*
Y783603D03*
Y790296D03*
Y800335D03*
Y807028D03*
Y793642D03*
Y813721D03*
Y820414D03*
Y837146D03*
Y830453D03*
Y827107D03*
Y843839D03*
Y850532D03*
Y857225D03*
Y863918D03*
Y873957D03*
Y880650D03*
Y867264D03*
Y887343D03*
Y894036D03*
Y910768D03*
Y904075D03*
Y900729D03*
Y924154D03*
Y917461D03*
Y930847D03*
Y940886D03*
Y937540D03*
Y947579D03*
Y954272D03*
Y967658D03*
Y974351D03*
Y981044D03*
Y987736D03*
Y994429D03*
Y1001122D03*
Y1027894D03*
Y1034587D03*
Y1041280D03*
Y1047973D03*
Y1054666D03*
Y1061359D03*
Y1071398D03*
Y1064705D03*
Y1078091D03*
Y1088130D03*
Y1084784D03*
Y1094823D03*
Y1101516D03*
Y1108209D03*
Y1114902D03*
Y1131634D03*
Y1124941D03*
Y1121595D03*
Y1138327D03*
Y1145020D03*
Y1151713D03*
Y1161752D03*
Y1158406D03*
Y1168445D03*
Y1175138D03*
Y1181831D03*
Y1188524D03*
Y1205256D03*
Y1198563D03*
Y1195217D03*
Y1211949D03*
Y1218642D03*
Y1225335D03*
Y1235374D03*
Y1232028D03*
Y1242067D03*
Y1248760D03*
X1104866Y780256D03*
Y786949D03*
Y803681D03*
Y793642D03*
Y796988D03*
Y817067D03*
Y810374D03*
Y823760D03*
Y830453D03*
Y833799D03*
Y840492D03*
Y847185D03*
Y853878D03*
Y860571D03*
Y877303D03*
Y867264D03*
Y870610D03*
Y883996D03*
Y890689D03*
Y897382D03*
Y904075D03*
Y907422D03*
Y914114D03*
Y920807D03*
Y927500D03*
Y934193D03*
Y940886D03*
Y950925D03*
Y944233D03*
Y964311D03*
Y957618D03*
Y971004D03*
Y977697D03*
Y984390D03*
Y1001122D03*
Y997776D03*
Y991083D03*
Y1031240D03*
Y1037933D03*
Y1044626D03*
Y1058012D03*
Y1051319D03*
Y1074744D03*
Y1081437D03*
Y1088130D03*
Y1098170D03*
Y1104862D03*
Y1091477D03*
Y1111555D03*
Y1118248D03*
Y1134981D03*
Y1124941D03*
Y1128288D03*
Y1148366D03*
Y1141674D03*
Y1155059D03*
Y1161752D03*
Y1165099D03*
Y1171792D03*
Y1178485D03*
Y1185177D03*
Y1191870D03*
Y1208603D03*
Y1198563D03*
Y1201910D03*
Y1215296D03*
Y1221988D03*
Y1228681D03*
Y1235374D03*
Y1238721D03*
Y1245414D03*
Y1252107D03*
X1121008Y776910D03*
Y783603D03*
Y790296D03*
Y800335D03*
Y807028D03*
Y793642D03*
Y813721D03*
Y820414D03*
Y837146D03*
Y830453D03*
Y827107D03*
Y843839D03*
Y850532D03*
Y857225D03*
Y863918D03*
Y873957D03*
Y880650D03*
Y867264D03*
Y887343D03*
Y894036D03*
Y910768D03*
Y904075D03*
Y900729D03*
Y924154D03*
Y917461D03*
Y930847D03*
Y940886D03*
Y937540D03*
Y947579D03*
Y954272D03*
Y967658D03*
Y974351D03*
Y981044D03*
Y987736D03*
Y994429D03*
Y1001122D03*
Y1027894D03*
Y1034587D03*
Y1041280D03*
Y1047973D03*
Y1054666D03*
Y1061359D03*
Y1071398D03*
Y1064705D03*
Y1078091D03*
Y1088130D03*
Y1084784D03*
Y1094823D03*
Y1101516D03*
Y1108209D03*
Y1114902D03*
Y1131634D03*
Y1124941D03*
Y1121595D03*
Y1138327D03*
Y1145020D03*
Y1151713D03*
Y1161752D03*
Y1158406D03*
Y1168445D03*
Y1175138D03*
Y1181831D03*
Y1188524D03*
Y1205256D03*
Y1198563D03*
Y1195217D03*
Y1211949D03*
Y1218642D03*
Y1225335D03*
Y1235374D03*
Y1232028D03*
Y1242067D03*
Y1248760D03*
X1134567Y780256D03*
Y786949D03*
Y803681D03*
Y793642D03*
Y796988D03*
Y817067D03*
Y810374D03*
Y823760D03*
Y830453D03*
Y833799D03*
Y840492D03*
Y847185D03*
Y853878D03*
Y860571D03*
Y877303D03*
Y867264D03*
Y870610D03*
Y883996D03*
Y890689D03*
Y897382D03*
Y904075D03*
Y907422D03*
Y914114D03*
Y920807D03*
Y927500D03*
Y934193D03*
Y940886D03*
Y950925D03*
Y944233D03*
Y964311D03*
Y957618D03*
Y971004D03*
Y977697D03*
Y984390D03*
Y1001122D03*
Y997776D03*
Y991083D03*
Y1031240D03*
Y1037933D03*
Y1044626D03*
Y1058012D03*
Y1051319D03*
Y1074744D03*
Y1081437D03*
Y1088130D03*
Y1098170D03*
Y1104862D03*
Y1091477D03*
Y1111555D03*
Y1118248D03*
Y1134981D03*
Y1124941D03*
Y1128288D03*
Y1148366D03*
Y1141674D03*
Y1155059D03*
Y1161752D03*
Y1165099D03*
Y1171792D03*
Y1178485D03*
Y1185177D03*
Y1191870D03*
Y1208603D03*
Y1198563D03*
Y1201910D03*
Y1215296D03*
Y1221988D03*
Y1228681D03*
Y1235374D03*
Y1238721D03*
Y1245414D03*
Y1252107D03*
X1150709Y776910D03*
Y783603D03*
Y790296D03*
Y800335D03*
Y807028D03*
Y793642D03*
Y813721D03*
Y820414D03*
Y837146D03*
Y830453D03*
Y827107D03*
Y843839D03*
Y850532D03*
Y857225D03*
Y863918D03*
Y873957D03*
Y880650D03*
Y867264D03*
Y887343D03*
Y894036D03*
Y910768D03*
Y904075D03*
Y900729D03*
Y924154D03*
Y917461D03*
Y930847D03*
Y940886D03*
Y937540D03*
Y947579D03*
Y954272D03*
Y967658D03*
Y974351D03*
Y981044D03*
Y987736D03*
Y994429D03*
Y1001122D03*
Y1027894D03*
Y1034587D03*
Y1041280D03*
Y1047973D03*
Y1054666D03*
Y1061359D03*
Y1071398D03*
Y1064705D03*
Y1078091D03*
Y1088130D03*
Y1084784D03*
Y1094823D03*
Y1101516D03*
Y1108209D03*
Y1114902D03*
Y1131634D03*
Y1124941D03*
Y1121595D03*
Y1138327D03*
Y1145020D03*
Y1151713D03*
Y1161752D03*
Y1158406D03*
Y1168445D03*
Y1175138D03*
Y1181831D03*
Y1188524D03*
Y1205256D03*
Y1198563D03*
Y1195217D03*
Y1211949D03*
Y1218642D03*
Y1225335D03*
Y1235374D03*
Y1232028D03*
Y1242067D03*
Y1248760D03*
X1170986Y1516590D03*
Y1513190D03*
Y1534990D03*
Y1538390D03*
X1177404Y-21711D03*
Y-18311D03*
Y-11711D03*
Y-8311D03*
Y11689D03*
Y8289D03*
Y18289D03*
Y21689D03*
X1183924Y1485895D03*
X1180624Y1495595D03*
X1177224D03*
X1185910Y960965D03*
X1187324Y1485895D03*
X1200724Y1505295D03*
X1197324D03*
X1196039Y1625380D03*
X1199439D03*
X1214124Y1485895D03*
X1210724D03*
X1207424Y1495595D03*
X1204024D03*
X1208099Y1625380D03*
X1211499D03*
X1227524Y1505295D03*
X1224124D03*
X1230824Y1495595D03*
X1220159Y1625380D03*
X1223559D03*
X1240924Y1485895D03*
X1237524D03*
X1234224Y1495595D03*
X1232219Y1625380D03*
X1244279D03*
X1235619D03*
X1245840Y-28311D03*
Y-31711D03*
Y-18311D03*
Y-21711D03*
Y1689D03*
Y-1711D03*
Y11689D03*
Y8289D03*
X1254324Y1505295D03*
X1250924D03*
X1257624Y1495595D03*
X1256339Y1625380D03*
X1247679D03*
X1259739D03*
X1267724Y1485895D03*
X1264324D03*
X1261024Y1495595D03*
X1268399Y1625380D03*
X1271799D03*
X1277724Y1485895D03*
X1281124D03*
X1288494Y1517082D03*
Y1513682D03*
Y1530482D03*
Y1527082D03*
X1280459Y1625380D03*
X1283859D03*
X1305286Y1495595D03*
X1299048Y1516590D03*
Y1513190D03*
Y1534990D03*
Y1538390D03*
X1292519Y1625380D03*
X1304579D03*
X1295919D03*
X1315386Y1485895D03*
X1311986D03*
X1308686Y1495595D03*
X1316639Y1625380D03*
X1320039D03*
X1307979D03*
X1328786Y1505295D03*
X1325386D03*
X1332086Y1495595D03*
X1328699Y1625380D03*
X1332099D03*
X1342186Y1485895D03*
X1338786D03*
X1335486Y1495595D03*
X1340759Y1625380D03*
X1344159D03*
X1355586Y1505295D03*
X1362286Y1495595D03*
X1352186Y1505295D03*
X1358886Y1495595D03*
X1352819Y1625380D03*
X1356219D03*
X1368986Y1485895D03*
X1365586D03*
X1378986Y1505295D03*
X1364879Y1625380D03*
X1376939D03*
X1368279D03*
X1392386Y1485895D03*
X1382386Y1505295D03*
X1389086Y1495595D03*
X1385686D03*
X1380339Y1625380D03*
X1395786Y1485895D03*
X1409186D03*
X1405786D03*
X1416556Y1513682D03*
Y1517082D03*
Y1530482D03*
Y1527082D03*
X1436263Y-28311D03*
Y-31711D03*
Y-18311D03*
Y-21711D03*
Y1689D03*
Y-1711D03*
Y11689D03*
Y8289D03*
X1460213Y1625380D03*
X1463613D03*
X1472273D03*
X1475673D03*
X1484333D03*
X1496393D03*
X1487733D03*
X1508453D03*
X1499793D03*
X1511853D03*
X1520513D03*
X1523913D03*
X1539134Y-35912D03*
Y-32512D03*
Y-22512D03*
Y-25912D03*
X1535566Y69340D03*
X1538966D03*
X1532573Y1625380D03*
X1535973D03*
X1557566Y69340D03*
X1546562Y75343D03*
X1549962D03*
X1544633Y1625380D03*
X1556693D03*
X1548033D03*
X1568566Y75340D03*
X1571966D03*
X1560966Y69340D03*
X1568753Y1625380D03*
X1560093D03*
X1572153D03*
X1579566Y69340D03*
X1582966D03*
X1580813Y1625380D03*
X1584213D03*
X1590566Y75340D03*
X1601562Y69343D03*
X1593966Y75340D03*
X1592873Y1625380D03*
X1596273D03*
X1612566Y75340D03*
X1615966D03*
X1604962Y69343D03*
X1604933Y1625380D03*
X1616993D03*
X1608333D03*
X1623562Y69343D03*
X1626962D03*
X1629053Y1625380D03*
X1620393D03*
X1632453D03*
X1646770Y69340D03*
X1635770Y75340D03*
X1639170D03*
X1641113Y1625380D03*
X1644513D03*
X1657766Y75343D03*
X1661166D03*
X1650170Y69340D03*
X1668770D03*
X1672170D03*
X1663839Y960965D03*
X1690900Y69343D03*
X1679904Y75340D03*
X1683304D03*
X1682898Y780256D03*
Y786949D03*
Y803681D03*
Y793642D03*
Y796988D03*
Y817067D03*
Y810374D03*
Y823760D03*
Y830453D03*
Y833799D03*
Y840492D03*
Y847185D03*
Y853878D03*
Y860571D03*
Y877303D03*
Y867264D03*
Y870610D03*
Y883996D03*
Y890689D03*
Y897382D03*
Y904075D03*
Y907422D03*
Y914114D03*
Y920807D03*
Y927500D03*
Y934193D03*
Y940886D03*
Y950925D03*
Y944233D03*
Y964311D03*
Y957618D03*
Y971004D03*
Y977697D03*
Y984390D03*
Y1001122D03*
Y997776D03*
Y991083D03*
Y1031240D03*
Y1037933D03*
Y1044626D03*
Y1058012D03*
Y1051319D03*
Y1074744D03*
Y1081437D03*
Y1088130D03*
Y1098170D03*
Y1104862D03*
Y1091477D03*
Y1111555D03*
Y1118248D03*
Y1134981D03*
Y1124941D03*
Y1128288D03*
Y1148366D03*
Y1141674D03*
Y1155059D03*
Y1161752D03*
Y1165099D03*
Y1171792D03*
Y1178485D03*
Y1185177D03*
Y1191870D03*
Y1208603D03*
Y1198563D03*
Y1201910D03*
Y1215296D03*
Y1221988D03*
Y1228681D03*
Y1235374D03*
Y1238721D03*
Y1245414D03*
Y1252107D03*
X1701904Y75340D03*
X1705304D03*
X1694300Y69343D03*
X1699040Y776910D03*
Y783603D03*
Y790296D03*
Y800335D03*
Y807028D03*
Y793642D03*
Y813721D03*
Y820414D03*
Y837146D03*
Y830453D03*
Y827107D03*
Y843839D03*
Y850532D03*
Y857225D03*
Y863918D03*
Y873957D03*
Y880650D03*
Y867264D03*
Y887343D03*
Y894036D03*
Y910768D03*
Y904075D03*
Y900729D03*
Y924154D03*
Y917461D03*
Y930847D03*
Y940886D03*
Y937540D03*
Y947579D03*
Y954272D03*
Y967658D03*
Y974351D03*
Y981044D03*
Y987736D03*
Y994429D03*
Y1001122D03*
Y1027894D03*
Y1034587D03*
Y1041280D03*
Y1047973D03*
Y1054666D03*
Y1061359D03*
Y1071398D03*
Y1064705D03*
Y1078091D03*
Y1088130D03*
Y1084784D03*
Y1094823D03*
Y1101516D03*
Y1108209D03*
Y1114902D03*
Y1131634D03*
Y1124941D03*
Y1121595D03*
Y1138327D03*
Y1145020D03*
Y1151713D03*
Y1161752D03*
Y1158406D03*
Y1168445D03*
Y1175138D03*
Y1181831D03*
Y1188524D03*
Y1205256D03*
Y1198563D03*
Y1195217D03*
Y1211949D03*
Y1218642D03*
Y1225335D03*
Y1235374D03*
Y1232028D03*
Y1242067D03*
Y1248760D03*
X1712599Y780256D03*
Y786949D03*
Y803681D03*
Y793642D03*
Y796988D03*
Y817067D03*
Y810374D03*
Y823760D03*
Y830453D03*
Y833799D03*
Y840492D03*
Y847185D03*
Y853878D03*
Y860571D03*
Y877303D03*
Y867264D03*
Y870610D03*
Y883996D03*
Y890689D03*
Y897382D03*
Y904075D03*
Y907422D03*
Y914114D03*
Y920807D03*
Y927500D03*
Y934193D03*
Y940886D03*
Y950925D03*
Y944233D03*
Y964311D03*
Y957618D03*
Y971004D03*
Y977697D03*
Y984390D03*
Y1001122D03*
Y997776D03*
Y991083D03*
Y1031240D03*
Y1037933D03*
Y1044626D03*
Y1058012D03*
Y1051319D03*
Y1074744D03*
Y1081437D03*
Y1088130D03*
Y1098170D03*
Y1104862D03*
Y1091477D03*
Y1111555D03*
Y1118248D03*
Y1134981D03*
Y1124941D03*
Y1128288D03*
Y1148366D03*
Y1141674D03*
Y1155059D03*
Y1161752D03*
Y1165099D03*
Y1171792D03*
Y1178485D03*
Y1185177D03*
Y1191870D03*
Y1208603D03*
Y1198563D03*
Y1201910D03*
Y1215296D03*
Y1221988D03*
Y1228681D03*
Y1235374D03*
Y1238721D03*
Y1245414D03*
Y1252107D03*
X1729557Y-35912D03*
Y-32512D03*
Y-22512D03*
Y-25912D03*
X1728741Y776910D03*
Y783603D03*
Y790296D03*
Y800335D03*
Y807028D03*
Y793642D03*
Y813721D03*
Y820414D03*
Y837146D03*
Y830453D03*
Y827107D03*
Y843839D03*
Y850532D03*
Y857225D03*
Y863918D03*
Y873957D03*
Y880650D03*
Y867264D03*
Y887343D03*
Y894036D03*
Y910768D03*
Y904075D03*
Y900729D03*
Y924154D03*
Y917461D03*
Y930847D03*
Y940886D03*
Y937540D03*
Y947579D03*
Y954272D03*
Y967658D03*
Y974351D03*
Y981044D03*
Y987736D03*
Y994429D03*
Y1001122D03*
Y1027894D03*
Y1034587D03*
Y1041280D03*
Y1047973D03*
Y1054666D03*
Y1061359D03*
Y1071398D03*
Y1064705D03*
Y1078091D03*
Y1088130D03*
Y1084784D03*
Y1094823D03*
Y1101516D03*
Y1108209D03*
Y1114902D03*
Y1131634D03*
Y1124941D03*
Y1121595D03*
Y1138327D03*
Y1145020D03*
Y1151713D03*
Y1161752D03*
Y1158406D03*
Y1168445D03*
Y1175138D03*
Y1181831D03*
Y1188524D03*
Y1205256D03*
Y1198563D03*
Y1195217D03*
Y1211949D03*
Y1218642D03*
Y1225335D03*
Y1235374D03*
Y1232028D03*
Y1242067D03*
Y1248760D03*
X1742300Y780256D03*
Y786949D03*
Y803681D03*
Y793642D03*
Y796988D03*
Y817067D03*
Y810374D03*
Y823760D03*
Y830453D03*
Y833799D03*
Y840492D03*
Y847185D03*
Y853878D03*
Y860571D03*
Y877303D03*
Y867264D03*
Y870610D03*
Y883996D03*
Y890689D03*
Y897382D03*
Y904075D03*
Y907422D03*
Y914114D03*
Y920807D03*
Y927500D03*
Y934193D03*
Y940886D03*
Y950925D03*
Y944233D03*
Y964311D03*
Y957618D03*
Y971004D03*
Y977697D03*
Y984390D03*
Y1001122D03*
Y997776D03*
Y991083D03*
Y1031240D03*
Y1037933D03*
Y1044626D03*
Y1058012D03*
Y1051319D03*
Y1074744D03*
Y1081437D03*
Y1088130D03*
Y1098170D03*
Y1104862D03*
Y1091477D03*
Y1111555D03*
Y1118248D03*
Y1134981D03*
Y1124941D03*
Y1128288D03*
Y1148366D03*
Y1141674D03*
Y1155059D03*
Y1161752D03*
Y1165099D03*
Y1171792D03*
Y1178485D03*
Y1185177D03*
Y1191870D03*
Y1208603D03*
Y1198563D03*
Y1201910D03*
Y1215296D03*
Y1221988D03*
Y1228681D03*
Y1235374D03*
Y1238721D03*
Y1245414D03*
Y1252107D03*
X1758442Y776910D03*
Y783603D03*
Y790296D03*
Y800335D03*
Y807028D03*
Y793642D03*
Y813721D03*
Y820414D03*
Y837146D03*
Y830453D03*
Y827107D03*
Y843839D03*
Y850532D03*
Y857225D03*
Y863918D03*
Y873957D03*
Y880650D03*
Y867264D03*
Y887343D03*
Y894036D03*
Y910768D03*
Y904075D03*
Y900729D03*
Y924154D03*
Y917461D03*
Y930847D03*
Y940886D03*
Y937540D03*
Y947579D03*
Y954272D03*
Y967658D03*
Y974351D03*
Y981044D03*
Y987736D03*
Y994429D03*
Y1001122D03*
Y1027894D03*
Y1034587D03*
Y1041280D03*
Y1047973D03*
Y1054666D03*
Y1061359D03*
Y1071398D03*
Y1064705D03*
Y1078091D03*
Y1088130D03*
Y1084784D03*
Y1094823D03*
Y1101516D03*
Y1108209D03*
Y1114902D03*
Y1131634D03*
Y1124941D03*
Y1121595D03*
Y1138327D03*
Y1145020D03*
Y1151713D03*
Y1161752D03*
Y1158406D03*
Y1168445D03*
Y1175138D03*
Y1181831D03*
Y1188524D03*
Y1205256D03*
Y1198563D03*
Y1195217D03*
Y1211949D03*
Y1218642D03*
Y1225335D03*
Y1235374D03*
Y1232028D03*
Y1242067D03*
Y1248760D03*
X1782642Y960965D03*
G54D22*
X60303Y20354D03*
X312921Y24291D03*
X505185Y41141D03*
X757803Y45078D03*
X929331Y160413D03*
X922441Y237697D03*
X1534712Y20354D03*
X1787330Y24291D03*
G54D32*
X205478Y1536063D03*
X210202D03*
X219651D03*
X229100D03*
X233824D03*
X243273D03*
X253002Y1514243D03*
X252722Y1536063D03*
X302413Y906182D03*
Y912560D03*
Y918938D03*
Y925316D03*
Y931694D03*
Y938072D03*
Y944450D03*
Y950828D03*
Y957206D03*
Y963584D03*
Y969962D03*
Y976340D03*
Y982718D03*
Y989096D03*
Y995474D03*
Y1008230D03*
Y1001852D03*
X303594Y1030198D03*
Y1036576D03*
Y1042954D03*
Y1055710D03*
Y1049332D03*
Y1062088D03*
Y1074844D03*
Y1068466D03*
Y1081222D03*
Y1087600D03*
Y1093978D03*
Y1100356D03*
Y1106734D03*
Y1113112D03*
Y1119490D03*
Y1125868D03*
Y1132246D03*
Y1138623D03*
Y1145001D03*
Y1157757D03*
Y1151379D03*
X333540Y1536063D03*
X338264D03*
X347713D03*
X357162D03*
X361886D03*
X380784D03*
X371335D03*
X381064Y1514243D03*
X408614Y997608D03*
X410464Y1007175D03*
X404923Y1010366D03*
X423417Y997608D03*
X416015D03*
X430819D03*
X445622D03*
X453023D03*
X467826D03*
X460425D03*
X469651Y1536063D03*
X483824D03*
X474375D03*
X497997D03*
X493273D03*
X507446D03*
X526370Y1165290D03*
X515268D03*
X518969D03*
X522670D03*
X517175Y1514243D03*
X516895Y1536063D03*
X533772Y1165290D03*
X530071D03*
X602437Y1536063D03*
X597713D03*
X611886D03*
X626059D03*
X621335D03*
X645237Y1514243D03*
X644957Y1536063D03*
X635508D03*
X1213351Y1569063D03*
X1227524D03*
X1218075D03*
X1241697D03*
X1236973D03*
X1251146D03*
X1260875Y1547243D03*
X1260595Y1569063D03*
X1278555Y906181D03*
Y912559D03*
Y918937D03*
Y925315D03*
Y931693D03*
Y938071D03*
Y950827D03*
Y944449D03*
Y957205D03*
Y963583D03*
Y969961D03*
Y976339D03*
Y982717D03*
Y995473D03*
Y989095D03*
Y1008229D03*
Y1001851D03*
X1279736Y1030197D03*
Y1042953D03*
Y1036575D03*
Y1055709D03*
Y1049331D03*
Y1062087D03*
Y1068465D03*
Y1074843D03*
Y1081221D03*
Y1087599D03*
Y1093977D03*
Y1100355D03*
Y1106733D03*
Y1113111D03*
Y1119489D03*
Y1125867D03*
Y1132245D03*
Y1138622D03*
Y1145000D03*
Y1151378D03*
Y1157756D03*
X1346137Y1569063D03*
X1341413D03*
X1355586D03*
X1379208D03*
X1369759D03*
X1365035D03*
X1384756Y997607D03*
X1392157D03*
X1386606Y1007174D03*
X1381065Y1010365D03*
X1388937Y1547243D03*
X1388657Y1569063D03*
X1406961Y997607D03*
X1399559D03*
X1421764D03*
X1436567D03*
X1429165D03*
X1443968D03*
X1482249Y1569063D03*
X1477525D03*
X1491698D03*
X1502512Y1165289D03*
X1505871Y1569063D03*
X1501147D03*
X1525049Y1547243D03*
X1524769Y1569063D03*
X1515320D03*
X1610311D03*
X1605587D03*
X1629209D03*
X1619760D03*
X1643382D03*
X1633933D03*
X1653111Y1547243D03*
X1652831Y1569063D03*
G54D44*
X381770Y-30570D03*
X385023Y-30584D03*
X388048Y-29264D03*
X381755Y-28055D03*
X385008Y-28069D03*
X381740Y-25540D03*
X381725Y-23025D03*
X723479Y-19234D03*
Y-9234D03*
X833421Y-36647D03*
X839699Y-35341D03*
X833406Y-34132D03*
X836674Y-36661D03*
X836659Y-34146D03*
X833391Y-31617D03*
X833376Y-29102D03*
X836644Y-31631D03*
X836629Y-29116D03*
X1174958Y-15374D03*
Y-5374D03*
Y24626D03*
X1433817Y-25374D03*
Y-15374D03*
Y14626D03*
X1530063Y-40911D03*
X1530033Y-35881D03*
X1530018Y-33366D03*
X1530048Y-38396D03*
X1533316Y-40925D03*
X1536341Y-39605D03*
X1533301Y-38410D03*
X1727111Y-19575D03*
G54D82*
X1898799Y1198198D03*
X1908799D03*
X1921395Y-39963D03*
X1931395D03*
X1942395Y572417D03*
X1940886Y1198170D03*
X1963362Y-39821D03*
X1952395Y572417D03*
X1950886Y1198170D03*
X1973362Y-39821D03*
X1984482Y572389D03*
X1982856Y1198350D03*
X1992856D03*
X2005452Y-39811D03*
X1994482Y572389D03*
X2015452Y-39811D03*
X2026452Y572569D03*
X2036452D03*
X2047419Y-39669D03*
X2057419D03*
X2068539Y572541D03*
X2078539D03*
G54D48*
X539016Y274272D03*
X559016D03*
X569016D03*
X579016D03*
X589016D03*
X599016D03*
X609016D03*
G54D62*
X918780Y1684890D03*
Y1694890D03*
Y1714890D03*
X928780Y1684890D03*
Y1694890D03*
Y1704890D03*
Y1714890D03*
X938780Y1684890D03*
Y1694890D03*
Y1704890D03*
Y1714890D03*
G54D67*
X1225530Y67471D03*
X1454797Y80345D03*
G54D80*
X1900275Y-29973D03*
Y562227D03*
X1898799Y1208198D03*
Y1800398D03*
X1910275Y-29973D03*
Y562227D03*
X1908799Y1208198D03*
Y1800398D03*
X1921395Y-29963D03*
X1931395D03*
Y562237D03*
X1921395D03*
X1931395Y582237D03*
X1921395D03*
Y1174437D03*
X1931395D03*
X1929766Y1208160D03*
X1919766D03*
Y1800360D03*
X1929766D03*
X1942395Y-29783D03*
Y562417D03*
Y582417D03*
Y1174617D03*
X1940886Y1208170D03*
Y1800370D03*
X1952395Y-29783D03*
Y562417D03*
Y582417D03*
Y1174617D03*
X1950886Y1208170D03*
X1961856D03*
X1950886Y1800370D03*
X1961856D03*
X1963362Y-29821D03*
X1973362D03*
Y562379D03*
X1963362D03*
X1973362Y582379D03*
X1963362D03*
Y1174579D03*
X1973362D03*
X1971856Y1208170D03*
Y1800370D03*
X1984482Y-29811D03*
Y562389D03*
Y582389D03*
Y1174589D03*
X1982856Y1208350D03*
Y1800550D03*
X1994482Y-29811D03*
X2005452D03*
X1994482Y562389D03*
X2005452D03*
Y582389D03*
X1994482D03*
Y1174589D03*
X2005452D03*
X1992856Y1208350D03*
X2003823Y1208312D03*
X1992856Y1800550D03*
X2003823Y1800512D03*
X2015452Y-29811D03*
Y562389D03*
Y582389D03*
Y1174589D03*
X2013823Y1208312D03*
Y1800512D03*
X2036452Y-29631D03*
X2026452D03*
Y562569D03*
X2036452D03*
X2026452Y582569D03*
X2036452D03*
Y1174769D03*
X2026452D03*
X2047419Y-29669D03*
Y562531D03*
Y582531D03*
Y1174731D03*
X2057419Y-29669D03*
Y562531D03*
Y582531D03*
Y1174731D03*
X2068539Y582541D03*
X2078539D03*
Y1174741D03*
X2068539D03*
G54D81*
X1900275Y572227D03*
X1910275D03*
X1921395Y1184437D03*
X1931395D03*
X1919766Y1810360D03*
X1929766D03*
X1942395Y572417D03*
X1952395D03*
X1963362Y1184579D03*
X1961856Y1810370D03*
X1973362Y1184579D03*
X1971856Y1810370D03*
X1984482Y572389D03*
X1994482D03*
X2005452Y1184589D03*
X2003823Y1810512D03*
X2015452Y1184589D03*
X2013823Y1810512D03*
X2026452Y572569D03*
X2036452D03*
X2047419Y1184731D03*
X2057419D03*
G54D51*
X676509Y224606D03*
G54D31*
X188155Y1530608D03*
X192879D03*
X197604D03*
X189730Y1533336D03*
X194454D03*
X199178D03*
X202328Y1530608D03*
X207052D03*
X211777D03*
X216501D03*
X203903Y1533336D03*
X208627D03*
X213352D03*
X221226Y1530608D03*
X225950D03*
X230674D03*
X218076Y1533336D03*
X222800D03*
X227525D03*
X235399Y1530608D03*
X240123D03*
X244848D03*
X236974Y1533336D03*
X241698D03*
X246422D03*
X232249D03*
X249572Y1530608D03*
X254297D03*
X259021D03*
X251147Y1533336D03*
X255871D03*
X260596D03*
X317957Y886002D03*
X319807Y889191D03*
Y895569D03*
X317957Y892380D03*
X319807Y908325D03*
X317957Y898758D03*
X319807Y901947D03*
X317957Y905135D03*
Y911513D03*
Y917891D03*
X319807Y921080D03*
X317957Y924269D03*
X319807Y914702D03*
Y927458D03*
X317957Y937025D03*
X319807Y940214D03*
Y933836D03*
X317957Y930647D03*
Y943403D03*
X319807Y946592D03*
X317957Y956159D03*
X319807Y952970D03*
X317957Y949781D03*
Y962537D03*
X319807Y965726D03*
Y959348D03*
X317957Y968915D03*
Y975293D03*
X319807Y978482D03*
Y972104D03*
X317957Y994427D03*
X319807Y997616D03*
X317957Y1000805D03*
X319807Y991238D03*
Y1010372D03*
X317957Y1007183D03*
X319807Y1003994D03*
X320988Y1034434D03*
X319138Y1037623D03*
X320988Y1040812D03*
X319138Y1044001D03*
X320988Y1059946D03*
X319138Y1050379D03*
X320988Y1053568D03*
Y1072702D03*
X319138Y1063135D03*
Y1069513D03*
X320988Y1066324D03*
X319138Y1075891D03*
X320988Y1079080D03*
X319138Y1082269D03*
Y1088647D03*
X320988Y1085458D03*
X319138Y1101403D03*
X320988Y1091836D03*
X319138Y1095025D03*
X320988Y1098214D03*
Y1104592D03*
Y1110970D03*
X319138Y1114159D03*
X320988Y1117348D03*
X319138Y1107781D03*
Y1120537D03*
X320988Y1130103D03*
X319138Y1133293D03*
Y1126915D03*
X320988Y1123726D03*
Y1136481D03*
X319138Y1139670D03*
X320988Y1149237D03*
X319138Y1146048D03*
X320988Y1142859D03*
X319138Y1152426D03*
X323508Y889191D03*
X325358Y892380D03*
X323508Y895569D03*
X325358Y911513D03*
X323508Y901947D03*
X325358Y905135D03*
X323508Y908325D03*
X325358Y898758D03*
X323508Y921080D03*
X325358Y924269D03*
X323508Y914702D03*
X325358Y917891D03*
X323508Y927458D03*
X325358Y930647D03*
X323508Y940214D03*
Y933836D03*
X325358Y937025D03*
Y943403D03*
X323508Y946592D03*
X325358Y949781D03*
X323508Y952970D03*
X325358Y956159D03*
X323508Y965726D03*
X325358Y968915D03*
X323508Y959348D03*
X325358Y962537D03*
X323508Y984860D03*
Y978482D03*
X325358Y981671D03*
X323508Y972104D03*
X325358Y975293D03*
Y988049D03*
X323508Y997616D03*
X325358Y1000805D03*
Y994427D03*
X323508Y1003994D03*
X325358Y1007183D03*
X326539Y1031245D03*
X324689Y1034434D03*
X326539Y1037623D03*
X324689Y1040812D03*
X326539Y1050379D03*
X324689Y1047190D03*
X326539Y1063135D03*
X324689Y1066324D03*
X326539Y1069513D03*
X324689Y1072702D03*
X326539Y1075891D03*
X324689Y1079080D03*
X326539Y1082269D03*
X324689Y1085458D03*
X326539Y1088647D03*
X324689Y1104592D03*
X326539Y1095025D03*
X324689Y1098214D03*
X326539Y1101403D03*
X324689Y1091836D03*
X326539Y1114159D03*
X324689Y1117348D03*
X326539Y1107781D03*
X324689Y1110970D03*
X326539Y1120537D03*
X324689Y1123726D03*
X326539Y1133293D03*
Y1126915D03*
X324689Y1130103D03*
Y1136481D03*
X326539Y1139670D03*
X324689Y1142859D03*
X326539Y1146048D03*
X324689Y1149237D03*
X326539Y1152426D03*
X324689Y1155615D03*
X358665Y886002D03*
X364217Y889191D03*
X356815D03*
X362366Y892380D03*
X356815Y895569D03*
X364217D03*
X358665Y892380D03*
X356815Y908325D03*
X362366Y911513D03*
X358665Y898758D03*
X364217Y901947D03*
X356815D03*
X362366Y905135D03*
X358665D03*
X364217Y908325D03*
X358665Y911513D03*
X362366Y898758D03*
X358665Y917891D03*
X364217Y921080D03*
X356815D03*
X362366Y924269D03*
X358665D03*
X356815Y914702D03*
X364217D03*
X362366Y917891D03*
X364217Y927458D03*
X356815D03*
X362366Y930647D03*
X358665Y937025D03*
X364217Y940214D03*
X356815D03*
Y933836D03*
X364217D03*
X358665Y930647D03*
X362366Y937025D03*
Y943403D03*
X358665D03*
X364217Y946592D03*
X356815D03*
X362366Y949781D03*
X358665Y956159D03*
X356815Y952970D03*
X364217D03*
X358665Y949781D03*
X362366Y956159D03*
X358665Y962537D03*
X364217Y965726D03*
X356815D03*
X362366Y968915D03*
X364217Y959348D03*
X356815D03*
X362366Y962537D03*
X358665Y968915D03*
X364217Y984860D03*
X358665Y975293D03*
X364217Y978482D03*
X356815D03*
X362366Y981671D03*
X356815Y972104D03*
X364217D03*
X362366Y975293D03*
Y988049D03*
X358665Y994427D03*
X356815Y997616D03*
X364217D03*
X362366Y1000805D03*
X358665D03*
X356815Y991238D03*
X362366Y994427D03*
X356815Y1010372D03*
X358665Y1007183D03*
X356815Y1003994D03*
X364217D03*
X362366Y1007183D03*
X363547Y1031245D03*
X365398Y1034434D03*
X357996D03*
X359847Y1037623D03*
X363547D03*
X365398Y1040812D03*
X357996D03*
X359847Y1044001D03*
X363547Y1050379D03*
X357996Y1059946D03*
X365398Y1047190D03*
X359847Y1050379D03*
X357996Y1053568D03*
Y1072702D03*
X363547Y1063135D03*
X359847D03*
X365398Y1066324D03*
X363547Y1069513D03*
X359847D03*
X365398Y1072702D03*
X357996Y1066324D03*
X363547Y1075891D03*
X359847D03*
X365398Y1079080D03*
X357996D03*
X363547Y1082269D03*
X359847D03*
X365398Y1085458D03*
X359847Y1088647D03*
X363547D03*
X357996Y1085458D03*
X359847Y1101403D03*
X365398Y1104592D03*
X357996Y1091836D03*
X363547Y1095025D03*
X359847D03*
X365398Y1098214D03*
X357996D03*
X363547Y1101403D03*
X357996Y1104592D03*
X365398Y1091836D03*
X357996Y1110970D03*
X363547Y1114159D03*
X359847D03*
X365398Y1117348D03*
X357996D03*
X359847Y1107781D03*
X363547D03*
X365398Y1110970D03*
X363547Y1120537D03*
X359847D03*
X365398Y1123726D03*
X357996Y1130103D03*
X363547Y1133293D03*
X359847D03*
Y1126915D03*
X363547D03*
X357996Y1123726D03*
X365398Y1130103D03*
Y1136481D03*
X357996D03*
X363547Y1139670D03*
X359847D03*
X365398Y1142859D03*
X357996Y1149237D03*
X359847Y1146048D03*
X363547D03*
X357996Y1142859D03*
X365398Y1149237D03*
X363547Y1152426D03*
X359847D03*
X357996Y1155615D03*
X369768Y886002D03*
X375319Y889191D03*
X371618D03*
X377169Y892380D03*
X371618Y895569D03*
X375319D03*
X369768Y892380D03*
X371618Y908325D03*
X377169Y911513D03*
X369768Y898758D03*
X375319Y901947D03*
X371618D03*
X377169Y905135D03*
X369768D03*
X375319Y908325D03*
X369768Y911513D03*
X377169Y898758D03*
X369768Y917891D03*
X375319Y921080D03*
X371618D03*
X377169Y924269D03*
X369768D03*
X371618Y914702D03*
X375319D03*
X377169Y917891D03*
X375319Y927458D03*
X371618D03*
X377169Y930647D03*
X369768Y937025D03*
X375319Y940214D03*
X371618D03*
Y933836D03*
X375319D03*
X369768Y930647D03*
X377169Y937025D03*
Y943403D03*
X369768D03*
X375319Y946592D03*
X371618D03*
X377169Y949781D03*
X369768Y956159D03*
X371618Y952970D03*
X375319D03*
X369768Y949781D03*
X377169Y956159D03*
X369768Y962537D03*
X375319Y965726D03*
X371618D03*
X377169Y968915D03*
X375319Y959348D03*
X371618D03*
X377169Y962537D03*
X369768Y968915D03*
X375319Y984860D03*
X369768Y975293D03*
X375319Y978482D03*
X371618D03*
X377169Y981671D03*
X371618Y972104D03*
X375319D03*
X377169Y975293D03*
Y988049D03*
X369768Y994427D03*
X371618Y997616D03*
X375319D03*
X377169Y1000805D03*
X369768D03*
X371618Y991238D03*
X377169Y994427D03*
X371618Y1010372D03*
X369768Y1007183D03*
X371618Y1003994D03*
X375319D03*
X377169Y1007183D03*
X378351Y1031245D03*
X376500Y1034434D03*
X372799D03*
X370949Y1037623D03*
X378351D03*
X376500Y1040812D03*
X372799D03*
X370949Y1044001D03*
X378351Y1050379D03*
X372799Y1059946D03*
X376500Y1047190D03*
X370949Y1050379D03*
X372799Y1053568D03*
Y1072702D03*
X378351Y1063135D03*
X370949D03*
X376500Y1066324D03*
X378351Y1069513D03*
X370949D03*
X376500Y1072702D03*
X372799Y1066324D03*
X378351Y1075891D03*
X370949D03*
X376500Y1079080D03*
X372799D03*
X378351Y1082269D03*
X370949D03*
X376500Y1085458D03*
X370949Y1088647D03*
X378351D03*
X372799Y1085458D03*
X370949Y1101403D03*
X376500Y1104592D03*
X372799Y1091836D03*
X378351Y1095025D03*
X370949D03*
X376500Y1098214D03*
X372799D03*
X378351Y1101403D03*
X372799Y1104592D03*
X376500Y1091836D03*
X372799Y1110970D03*
X378351Y1114159D03*
X370949D03*
X376500Y1117348D03*
X372799D03*
X370949Y1107781D03*
X378351D03*
X376500Y1110970D03*
X378351Y1120537D03*
X370949D03*
X376500Y1123726D03*
X372799Y1130103D03*
X378351Y1133293D03*
X370949D03*
Y1126915D03*
X378351D03*
X372799Y1123726D03*
X376500Y1130103D03*
Y1136481D03*
X372799D03*
X378351Y1139670D03*
X370949D03*
X376500Y1142859D03*
X372799Y1149237D03*
X370949Y1146048D03*
X378351D03*
X372799Y1142859D03*
X376500Y1149237D03*
X378351Y1152426D03*
X370949D03*
X376500Y1155615D03*
X388272Y892380D03*
X384571D03*
X395673D03*
X388272Y911513D03*
Y898758D03*
Y905135D03*
X384571Y911513D03*
Y898758D03*
Y905135D03*
X395673Y898758D03*
Y905135D03*
Y911513D03*
X388272Y924269D03*
Y917891D03*
X384571Y924269D03*
Y917891D03*
X395673Y924269D03*
Y917891D03*
X388272Y930647D03*
X384571D03*
X395673D03*
X384571Y949781D03*
Y943403D03*
Y956159D03*
X395673Y949781D03*
Y943403D03*
Y956159D03*
X388272Y949781D03*
Y943403D03*
Y956159D03*
X389453Y1114159D03*
Y1107781D03*
X385752Y1114159D03*
Y1107781D03*
X389453Y1120537D03*
X385752D03*
X389453Y1126915D03*
Y1133293D03*
X385752Y1126915D03*
Y1133293D03*
X389453Y1139670D03*
Y1146048D03*
X385752Y1139670D03*
Y1146048D03*
Y1158804D03*
X382051D03*
X393154D03*
X389453Y1152426D03*
X385752D03*
X399374Y892380D03*
X410477D03*
X406776D03*
X399374Y898758D03*
Y905135D03*
X410477Y898758D03*
Y905135D03*
X406776Y898758D03*
Y905135D03*
X399374Y911513D03*
X410477D03*
X406776D03*
X399374Y924269D03*
Y917891D03*
X410477D03*
Y924269D03*
X406776Y917891D03*
Y924269D03*
X399374Y930647D03*
X406776Y949781D03*
Y943403D03*
Y956159D03*
X399374Y949781D03*
Y943403D03*
Y956159D03*
X410477Y949781D03*
Y943403D03*
Y956159D03*
X400555Y1114159D03*
Y1107781D03*
X396855Y1114159D03*
Y1107781D03*
X407957Y1114159D03*
X400555Y1120537D03*
Y1126915D03*
X396855Y1120537D03*
Y1126915D03*
X407957Y1120537D03*
Y1126915D03*
X400555Y1133293D03*
X396855D03*
X407957D03*
X400555Y1139670D03*
Y1146048D03*
X396855Y1139670D03*
Y1146048D03*
X407957Y1139670D03*
Y1146048D03*
X396855Y1158804D03*
X407957D03*
X404256D03*
X400555Y1152426D03*
X396855D03*
X407957D03*
X421579Y892380D03*
X417878D03*
X421579Y898758D03*
Y905135D03*
X417878Y898758D03*
Y905135D03*
X421579Y911513D03*
X417878D03*
X421579Y917891D03*
Y924269D03*
X417878Y917891D03*
Y924269D03*
Y937025D03*
X421579D03*
X417878Y943403D03*
Y956159D03*
Y949781D03*
X421579Y943403D03*
Y956159D03*
Y949781D03*
X422760Y1114159D03*
X411658D03*
X419059D03*
X422760Y1120537D03*
Y1126915D03*
X411658Y1120537D03*
Y1126915D03*
X419059Y1120537D03*
Y1126915D03*
X422760Y1133293D03*
X411658D03*
X419059D03*
X422760Y1139670D03*
Y1146048D03*
X411658Y1139670D03*
Y1146048D03*
X419059Y1139670D03*
Y1146048D03*
Y1158804D03*
X415358D03*
X411658Y1152426D03*
X422760D03*
X419059D03*
X430831Y895569D03*
X427130D03*
X430831Y901947D03*
Y908325D03*
X427130Y901947D03*
Y908325D03*
X430831Y914702D03*
Y921080D03*
X427130Y914702D03*
Y921080D03*
X430831Y927458D03*
X427130D03*
Y940214D03*
X430831D03*
X427130Y946592D03*
Y952970D03*
X430831Y946592D03*
Y952970D03*
X432012Y1117348D03*
Y1110970D03*
X428311Y1117348D03*
Y1110970D03*
X432012Y1123726D03*
X428311D03*
X432012Y1130103D03*
X428311D03*
X432012Y1142859D03*
Y1136481D03*
X428311Y1142859D03*
Y1136481D03*
X449310Y895569D03*
X453011D03*
X449310Y908325D03*
Y901947D03*
X453011Y908325D03*
Y901947D03*
X450491Y1110970D03*
Y1117348D03*
X454192Y1110970D03*
Y1117348D03*
X450491Y1123726D03*
X454192D03*
X450491Y1130103D03*
X454192D03*
X450491Y1136481D03*
Y1142859D03*
X454192Y1136481D03*
Y1142859D03*
X452328Y1516970D03*
X453903Y1519698D03*
X452328Y1530608D03*
X453903Y1533336D03*
X458562Y892380D03*
X469664D03*
X462263D03*
X458562Y905135D03*
Y898758D03*
X469664Y905135D03*
Y898758D03*
X462263Y905135D03*
Y898758D03*
X459743Y1114159D03*
X463444D03*
X459743Y1126915D03*
Y1120537D03*
X463444Y1126915D03*
Y1120537D03*
X459743Y1133293D03*
X463444D03*
X459743Y1146048D03*
Y1139670D03*
X463444Y1146048D03*
Y1139670D03*
X457052Y1516970D03*
X461777D03*
X466501D03*
X458627Y1519698D03*
X463351D03*
X468076D03*
X457052Y1530608D03*
X461777D03*
X466501D03*
X458627Y1533336D03*
X463351D03*
X468076D03*
X480767Y892380D03*
X484467D03*
X473365D03*
X480767Y898758D03*
Y905135D03*
X484467Y898758D03*
X473365Y905135D03*
Y898758D03*
X484467Y905135D03*
X481948Y1114159D03*
X470845D03*
X481948Y1107781D03*
X474546Y1114159D03*
X481948Y1126915D03*
Y1120537D03*
X470845Y1126915D03*
Y1120537D03*
X474546Y1126915D03*
Y1120537D03*
X470845Y1133293D03*
X481948D03*
X474546D03*
X481948Y1146048D03*
Y1139670D03*
X470845Y1146048D03*
Y1139670D03*
X474546Y1146048D03*
Y1139670D03*
X471225Y1516970D03*
X475950D03*
X480674D03*
X472800Y1519698D03*
X477525D03*
X482249D03*
X471225Y1530608D03*
X475950D03*
X480674D03*
X472800Y1533336D03*
X477525D03*
X482249D03*
X491869Y892380D03*
X495570D03*
X491869Y905135D03*
Y898758D03*
Y911513D03*
X495570Y905135D03*
Y898758D03*
Y911513D03*
X493050Y1107781D03*
Y1114159D03*
X485649D03*
X496751Y1107781D03*
Y1114159D03*
X485649Y1107781D03*
X493050Y1120537D03*
X485649Y1126915D03*
Y1120537D03*
X496751D03*
X493050Y1133293D03*
Y1126915D03*
X496751Y1133293D03*
Y1126915D03*
X485649Y1133293D03*
X493050Y1146048D03*
Y1139670D03*
X485649Y1146048D03*
Y1139670D03*
X496751Y1146048D03*
Y1139670D03*
X499572Y1516970D03*
X485399D03*
X490123D03*
X494847D03*
X486973Y1519698D03*
X491698D03*
X496422D03*
X499572Y1530608D03*
X485399D03*
X490123D03*
X494847D03*
X486973Y1533336D03*
X491698D03*
X496422D03*
X510373Y886002D03*
X504822Y889191D03*
X508523D03*
X502971Y892380D03*
X508523Y895569D03*
X504822D03*
X510373Y892380D03*
X508523Y908325D03*
X502971Y911513D03*
X510373Y898758D03*
X504822Y901947D03*
X508523D03*
X502971Y905135D03*
X510373D03*
X504822Y908325D03*
X510373Y911513D03*
X502971Y898758D03*
X510373Y917891D03*
X504822Y921080D03*
X508523D03*
X502971Y924269D03*
X510373D03*
X508523Y914702D03*
X504822D03*
X502971Y917891D03*
X504822Y927458D03*
X508523D03*
X502971Y930647D03*
X510373Y937025D03*
X504822Y940214D03*
X508523D03*
Y933836D03*
X504822D03*
X510373Y930647D03*
X502971Y937025D03*
Y943403D03*
X510373D03*
X504822Y946592D03*
X508523D03*
X502971Y949781D03*
X510373Y956159D03*
X508523Y952970D03*
X504822D03*
X510373Y949781D03*
X502971Y956159D03*
X510373Y962537D03*
X504822Y965726D03*
X508523D03*
X502971Y968915D03*
X504822Y959348D03*
X508523D03*
X502971Y962537D03*
X510373Y968915D03*
X504822Y984860D03*
X510373Y975293D03*
X504822Y978482D03*
X508523D03*
X502971Y981671D03*
X508523Y972104D03*
X504822D03*
X502971Y975293D03*
Y988049D03*
X510373Y994427D03*
X508523Y997616D03*
X504822D03*
X502971Y1000805D03*
X510373D03*
Y988049D03*
X504822Y991238D03*
X508523Y1010372D03*
X510373Y1007183D03*
X508523Y1003994D03*
X504822D03*
X502971Y1007183D03*
X504153Y1031245D03*
X506003Y1034434D03*
X509704D03*
X511554Y1037623D03*
X504153D03*
X506003Y1040812D03*
X509704D03*
X504153Y1044001D03*
Y1050379D03*
X509704Y1059946D03*
X506003Y1047190D03*
X511554Y1050379D03*
X509704Y1053568D03*
Y1072702D03*
X504153Y1063135D03*
X511554D03*
X506003Y1066324D03*
X504153Y1069513D03*
X511554D03*
X506003Y1072702D03*
X509704Y1066324D03*
X504153Y1075891D03*
X511554D03*
X506003Y1079080D03*
X509704D03*
X504153Y1082269D03*
X511554D03*
X506003Y1085458D03*
X511554Y1088647D03*
X504153D03*
X509704Y1085458D03*
X511554Y1101403D03*
X506003Y1104592D03*
X509704Y1091836D03*
X504153Y1095025D03*
X511554D03*
X506003Y1098214D03*
X509704D03*
X504153Y1101403D03*
X509704Y1104592D03*
X506003Y1091836D03*
X509704Y1110970D03*
X504153Y1114159D03*
X511554D03*
X506003Y1117348D03*
X509704D03*
X511554Y1107781D03*
X504153D03*
X506003Y1110970D03*
X504153Y1120537D03*
X511554D03*
X506003Y1123726D03*
X509704Y1130103D03*
X504153Y1133293D03*
X511554D03*
Y1126915D03*
X504153D03*
X509704Y1123726D03*
X506003Y1130103D03*
Y1136481D03*
X509704D03*
X504153Y1139670D03*
X511554D03*
X506003Y1142859D03*
X509704Y1149237D03*
X511554Y1146048D03*
X504153D03*
X509704Y1142859D03*
X506003Y1149237D03*
X504153Y1152426D03*
X511554D03*
X506003Y1155615D03*
X504296Y1516970D03*
X509021D03*
X513745D03*
X501147Y1519698D03*
X505871D03*
X510595D03*
X504296Y1530608D03*
X509021D03*
X513745D03*
X501147Y1533336D03*
X505871D03*
X510595D03*
X521475Y886002D03*
X515924Y889191D03*
X523326D03*
X517775Y892380D03*
X523326Y895569D03*
X515924D03*
X521475Y892380D03*
X523326Y908325D03*
X517775Y911513D03*
X521475Y898758D03*
X515924Y901947D03*
X523326D03*
X517775Y905135D03*
X521475D03*
X515924Y908325D03*
X521475Y911513D03*
X517775Y898758D03*
X521475Y917891D03*
X515924Y921080D03*
X523326D03*
X517775Y924269D03*
X521475D03*
X523326Y914702D03*
X515924D03*
X517775Y917891D03*
X515924Y927458D03*
X523326D03*
X517775Y930647D03*
X521475Y937025D03*
X515924Y940214D03*
X523326D03*
Y933836D03*
X515924D03*
X521475Y930647D03*
X517775Y937025D03*
Y943403D03*
X521475D03*
X515924Y946592D03*
X523326D03*
X517775Y949781D03*
X521475Y956159D03*
X523326Y952970D03*
X515924D03*
X521475Y949781D03*
X517775Y956159D03*
X521475Y962537D03*
X515924Y965726D03*
X523326D03*
X517775Y968915D03*
X515924Y959348D03*
X523326D03*
X517775Y962537D03*
X521475Y968915D03*
X515924Y984860D03*
X521475Y975293D03*
X515924Y978482D03*
X523326D03*
X517775Y981671D03*
X523326Y972104D03*
X515924D03*
X517775Y975293D03*
Y988049D03*
X521475Y994427D03*
X523326Y997616D03*
X515924D03*
X517775Y1000805D03*
X521475D03*
Y988049D03*
X515924Y991238D03*
X523326Y1010372D03*
X521475Y1007183D03*
X523326Y1003994D03*
X515924D03*
X517775Y1007183D03*
X518956Y1031245D03*
X517105Y1034434D03*
X524507D03*
X522657Y1037623D03*
X518956D03*
X517105Y1040812D03*
X524507D03*
X518956Y1044001D03*
Y1050379D03*
X524507Y1059946D03*
X517105Y1047190D03*
X522657Y1050379D03*
X524507Y1053568D03*
Y1072702D03*
X518956Y1063135D03*
X522657D03*
X517105Y1066324D03*
X518956Y1069513D03*
X522657D03*
X517105Y1072702D03*
X524507Y1066324D03*
X518956Y1075891D03*
X522657D03*
X517105Y1079080D03*
X524507D03*
X518956Y1082269D03*
X522657D03*
X517105Y1085458D03*
X522657Y1088647D03*
X518956D03*
X524507Y1085458D03*
X522657Y1101403D03*
X517105Y1104592D03*
X524507Y1091836D03*
X518956Y1095025D03*
X522657D03*
X517105Y1098214D03*
X524507D03*
X518956Y1101403D03*
X524507Y1104592D03*
X517105Y1091836D03*
X524507Y1110970D03*
X518956Y1114159D03*
X522657D03*
X517105Y1117348D03*
X524507D03*
X522657Y1107781D03*
X518956D03*
X517105Y1110970D03*
X518956Y1120537D03*
X522657D03*
X517105Y1123726D03*
X524507Y1130103D03*
X518956Y1133293D03*
X522657D03*
Y1126915D03*
X518956D03*
X524507Y1123726D03*
X517105Y1130103D03*
Y1136481D03*
X524507D03*
X518956Y1139670D03*
X522657D03*
X517105Y1142859D03*
X524507Y1149237D03*
X522657Y1146048D03*
X518956D03*
X524507Y1142859D03*
X517105Y1149237D03*
X518956Y1152426D03*
X522657D03*
X524507Y1155615D03*
X518470Y1516970D03*
X523194D03*
X515320Y1519698D03*
X520044D03*
X524769D03*
X518470Y1530608D03*
X523194D03*
X515320Y1533336D03*
X520044D03*
X524769D03*
X556633Y889191D03*
X554783Y892380D03*
X556633Y895569D03*
X554783Y911513D03*
X556633Y901947D03*
X554783Y905135D03*
X556633Y908325D03*
X554783Y898758D03*
X556633Y921080D03*
X554783Y924269D03*
X556633Y914702D03*
X554783Y917891D03*
X556633Y927458D03*
X554783Y930647D03*
X556633Y940214D03*
Y933836D03*
X554783Y937025D03*
Y943403D03*
X556633Y946592D03*
X554783Y949781D03*
X556633Y952970D03*
X554783Y956159D03*
X556633Y965726D03*
X554783Y968915D03*
X556633Y959348D03*
X554783Y962537D03*
X556633Y984860D03*
Y978482D03*
X554783Y981671D03*
X556633Y972104D03*
X554783Y975293D03*
Y988049D03*
X556633Y997616D03*
X554783Y1000805D03*
X556633Y991238D03*
Y1003994D03*
X554783Y1007183D03*
X555964Y1031245D03*
X557814Y1034434D03*
X555964Y1037623D03*
X557814Y1040812D03*
X555964Y1044001D03*
Y1050379D03*
X557814Y1047190D03*
X555964Y1063135D03*
X557814Y1066324D03*
X555964Y1069513D03*
X557814Y1072702D03*
X555964Y1075891D03*
X557814Y1079080D03*
X555964Y1082269D03*
X557814Y1085458D03*
X555964Y1088647D03*
X557814Y1104592D03*
X555964Y1095025D03*
X557814Y1098214D03*
X555964Y1101403D03*
X557814Y1091836D03*
X555964Y1114159D03*
X557814Y1117348D03*
X555964Y1107781D03*
X557814Y1110970D03*
X555964Y1120537D03*
X557814Y1123726D03*
X555964Y1133293D03*
Y1126915D03*
X557814Y1130103D03*
Y1136481D03*
X555964Y1139670D03*
X557814Y1142859D03*
X555964Y1146048D03*
X557814Y1149237D03*
X555964Y1152426D03*
X557814Y1155615D03*
X562184Y886002D03*
X560334Y889191D03*
Y895569D03*
X562184Y892380D03*
X560334Y908325D03*
X562184Y898758D03*
X560334Y901947D03*
X562184Y905135D03*
Y911513D03*
Y917891D03*
X560334Y921080D03*
X562184Y924269D03*
X560334Y914702D03*
Y927458D03*
X562184Y937025D03*
X560334Y940214D03*
Y933836D03*
X562184Y930647D03*
Y943403D03*
X560334Y946592D03*
X562184Y956159D03*
X560334Y952970D03*
X562184Y949781D03*
Y962537D03*
X560334Y965726D03*
Y959348D03*
X562184Y968915D03*
Y975293D03*
X560334Y978482D03*
Y972104D03*
X562184Y994427D03*
X560334Y997616D03*
X562184Y1000805D03*
Y988049D03*
X560334Y1010372D03*
X562184Y1007183D03*
X560334Y1003994D03*
X561515Y1034434D03*
X563365Y1037623D03*
X561515Y1040812D03*
Y1059946D03*
X563365Y1050379D03*
X561515Y1053568D03*
Y1072702D03*
X563365Y1063135D03*
Y1069513D03*
X561515Y1066324D03*
X563365Y1075891D03*
X561515Y1079080D03*
X563365Y1082269D03*
Y1088647D03*
X561515Y1085458D03*
X563365Y1101403D03*
X561515Y1091836D03*
X563365Y1095025D03*
X561515Y1098214D03*
Y1104592D03*
Y1110970D03*
X563365Y1114159D03*
X561515Y1117348D03*
X563365Y1107781D03*
Y1120537D03*
X561515Y1130103D03*
X563365Y1133293D03*
Y1126915D03*
X561515Y1123726D03*
Y1136481D03*
X563365Y1139670D03*
X561515Y1149237D03*
X563365Y1146048D03*
X561515Y1142859D03*
X563365Y1152426D03*
X580390Y1516970D03*
X585114D03*
X581965Y1519698D03*
X586689D03*
X580390Y1530608D03*
X585114D03*
X581965Y1533336D03*
X586689D03*
X589839Y1516970D03*
X594563D03*
X599287D03*
X604012D03*
X591413Y1519698D03*
X596138D03*
X600862D03*
X589839Y1530608D03*
X594563D03*
X599287D03*
X604012D03*
X591413Y1533336D03*
X596138D03*
X600862D03*
X608736Y1516970D03*
X613461D03*
X618185D03*
X605587Y1519698D03*
X610311D03*
X615035D03*
X608736Y1530608D03*
X613461D03*
X618185D03*
X605587Y1533336D03*
X610311D03*
X615035D03*
X627634Y1516970D03*
X632358D03*
X622909D03*
X629209Y1519698D03*
X633933D03*
X619760D03*
X624484D03*
X627634Y1530608D03*
X632358D03*
X622909D03*
X629209Y1533336D03*
X633933D03*
X619760D03*
X624484D03*
X637083Y1516970D03*
X641807D03*
X646532D03*
X638657Y1519698D03*
X643382D03*
X648106D03*
X637083Y1530608D03*
X641807D03*
X646532D03*
X638657Y1533336D03*
X643382D03*
X648106D03*
X651256Y1516970D03*
X652831Y1519698D03*
X651256Y1530608D03*
X652831Y1533336D03*
X1196028Y1563608D03*
X1197603Y1566336D03*
X1200752Y1563608D03*
X1205477D03*
X1210201D03*
X1214925D03*
X1202327Y1566336D03*
X1207051D03*
X1211776D03*
X1219650Y1563608D03*
X1224374D03*
X1229099D03*
X1216500Y1566336D03*
X1221225D03*
X1225949D03*
X1243272Y1563608D03*
X1233823D03*
X1238547D03*
X1244847Y1566336D03*
X1230673D03*
X1235398D03*
X1240122D03*
X1247996Y1563608D03*
X1252721D03*
X1257445D03*
X1249571Y1566336D03*
X1254295D03*
X1259020D03*
X1262170Y1563608D03*
X1266894D03*
X1263744Y1566336D03*
X1268469D03*
X1294099Y886001D03*
X1299650Y889190D03*
X1295949D03*
X1301500Y892379D03*
X1295949Y895568D03*
X1299650D03*
X1294099Y892379D03*
X1295949Y908324D03*
X1301500Y911512D03*
X1294099Y898757D03*
X1299650Y901946D03*
X1295949D03*
X1301500Y905134D03*
X1294099D03*
X1299650Y908324D03*
X1294099Y911512D03*
X1301500Y898757D03*
X1294099Y917890D03*
X1299650Y921079D03*
X1295949D03*
X1301500Y924268D03*
X1294099D03*
X1295949Y914701D03*
X1299650D03*
X1301500Y917890D03*
X1299650Y927457D03*
X1295949D03*
X1301500Y930646D03*
X1294099Y937024D03*
X1299650Y940213D03*
X1295949D03*
Y933835D03*
X1299650D03*
X1294099Y930646D03*
X1301500Y937024D03*
Y943402D03*
X1294099D03*
X1299650Y946591D03*
X1295949D03*
X1301500Y949780D03*
X1294099Y956158D03*
X1295949Y952969D03*
X1299650D03*
X1294099Y949780D03*
X1301500Y956158D03*
X1294099Y962536D03*
X1299650Y965725D03*
X1295949D03*
X1301500Y968914D03*
X1299650Y959347D03*
X1295949D03*
X1301500Y962536D03*
X1294099Y968914D03*
X1299650Y984859D03*
X1294099Y975292D03*
X1299650Y978481D03*
X1295949D03*
X1301500Y981670D03*
X1295949Y972103D03*
X1299650D03*
X1301500Y975292D03*
Y988048D03*
X1294099Y994426D03*
X1295949Y997615D03*
X1299650D03*
X1301500Y1000804D03*
X1294099D03*
X1295949Y991237D03*
X1301500Y994426D03*
X1295949Y1010371D03*
X1294099Y1007182D03*
X1295949Y1003993D03*
X1299650D03*
X1301500Y1007182D03*
X1302681Y1031244D03*
X1300831Y1034433D03*
X1297130D03*
X1295280Y1037622D03*
X1302681D03*
X1300831Y1040811D03*
X1297130D03*
X1295280Y1044000D03*
X1302681Y1050378D03*
X1297130Y1059945D03*
X1300831Y1047189D03*
X1295280Y1050378D03*
X1297130Y1053567D03*
Y1072701D03*
X1302681Y1063134D03*
X1295280D03*
X1300831Y1066323D03*
X1302681Y1069512D03*
X1295280D03*
X1300831Y1072701D03*
X1297130Y1066323D03*
X1302681Y1075890D03*
X1295280D03*
X1300831Y1079079D03*
X1297130D03*
X1302681Y1082268D03*
X1295280D03*
X1300831Y1085457D03*
X1295280Y1088646D03*
X1302681D03*
X1297130Y1085457D03*
X1295280Y1101402D03*
X1300831Y1104591D03*
X1297130Y1091835D03*
X1302681Y1095024D03*
X1295280D03*
X1300831Y1098213D03*
X1297130D03*
X1302681Y1101402D03*
X1297130Y1104591D03*
X1300831Y1091835D03*
X1297130Y1110969D03*
X1302681Y1114158D03*
X1295280D03*
X1300831Y1117347D03*
X1297130D03*
X1295280Y1107780D03*
X1302681D03*
X1300831Y1110969D03*
X1302681Y1120536D03*
X1295280D03*
X1300831Y1123725D03*
X1297130Y1130102D03*
X1302681Y1133292D03*
X1295280D03*
Y1126914D03*
X1302681D03*
X1297130Y1123725D03*
X1300831Y1130102D03*
Y1136480D03*
X1297130D03*
X1302681Y1139669D03*
X1295280D03*
X1300831Y1142858D03*
X1297130Y1149236D03*
X1295280Y1146047D03*
X1302681D03*
X1297130Y1142858D03*
X1300831Y1149236D03*
X1302681Y1152425D03*
X1295280D03*
X1300831Y1155614D03*
X1334807Y886001D03*
X1332957Y889190D03*
Y895568D03*
X1334807Y892379D03*
X1332957Y908324D03*
X1334807Y898757D03*
X1332957Y901946D03*
X1334807Y905134D03*
Y911512D03*
Y917890D03*
X1332957Y921079D03*
X1334807Y924268D03*
X1332957Y914701D03*
Y927457D03*
X1334807Y937024D03*
X1332957Y940213D03*
Y933835D03*
X1334807Y930646D03*
Y943402D03*
X1332957Y946591D03*
X1334807Y956158D03*
X1332957Y952969D03*
X1334807Y949780D03*
Y962536D03*
X1332957Y965725D03*
Y959347D03*
X1334807Y968914D03*
Y975292D03*
X1332957Y978481D03*
Y972103D03*
X1334807Y994426D03*
X1332957Y997615D03*
X1334807Y1000804D03*
X1332957Y991237D03*
Y1010371D03*
X1334807Y1007182D03*
X1332957Y1003993D03*
X1334138Y1034433D03*
Y1040811D03*
Y1059945D03*
Y1053567D03*
Y1072701D03*
Y1066323D03*
Y1079079D03*
Y1085457D03*
Y1091835D03*
Y1098213D03*
Y1104591D03*
Y1110969D03*
Y1117347D03*
Y1130102D03*
Y1123725D03*
Y1136480D03*
Y1149236D03*
Y1142858D03*
Y1155614D03*
X1324090Y1563608D03*
X1328814D03*
X1333539D03*
X1325665Y1566336D03*
X1330389D03*
X1345910Y886001D03*
X1347760Y889190D03*
Y895568D03*
X1345910Y892379D03*
X1340359Y889190D03*
X1338508Y892379D03*
X1340359Y895568D03*
X1347760Y908324D03*
X1345910Y898757D03*
X1347760Y901946D03*
X1345910Y905134D03*
Y911512D03*
X1338508D03*
X1340359Y901946D03*
X1338508Y905134D03*
X1340359Y908324D03*
X1338508Y898757D03*
X1345910Y917890D03*
X1347760Y921079D03*
X1345910Y924268D03*
X1347760Y914701D03*
X1340359Y921079D03*
X1338508Y924268D03*
X1340359Y914701D03*
X1338508Y917890D03*
X1347760Y927457D03*
X1345910Y937024D03*
X1347760Y940213D03*
Y933835D03*
X1345910Y930646D03*
X1340359Y927457D03*
X1338508Y930646D03*
X1340359Y940213D03*
Y933835D03*
X1338508Y937024D03*
X1345910Y943402D03*
X1347760Y946591D03*
X1345910Y956158D03*
X1347760Y952969D03*
X1345910Y949780D03*
X1338508Y943402D03*
X1340359Y946591D03*
X1338508Y949780D03*
X1340359Y952969D03*
X1338508Y956158D03*
X1345910Y962536D03*
X1347760Y965725D03*
Y959347D03*
X1345910Y968914D03*
X1340359Y965725D03*
X1338508Y968914D03*
X1340359Y959347D03*
X1338508Y962536D03*
X1345910Y975292D03*
X1347760Y978481D03*
Y972103D03*
X1340359Y984859D03*
Y978481D03*
X1338508Y981670D03*
X1340359Y972103D03*
X1338508Y975292D03*
X1345910Y994426D03*
X1347760Y997615D03*
X1345910Y1000804D03*
X1347760Y991237D03*
X1338508Y988048D03*
X1340359Y997615D03*
X1338508Y1000804D03*
Y994426D03*
X1347760Y1010371D03*
X1345910Y1007182D03*
X1347760Y1003993D03*
X1340359D03*
X1338508Y1007182D03*
X1348941Y1034433D03*
X1347091Y1037622D03*
X1348941Y1040811D03*
X1347091Y1044000D03*
X1339689Y1031244D03*
X1341540Y1034433D03*
X1335989Y1037622D03*
X1339689D03*
X1341540Y1040811D03*
X1335989Y1044000D03*
X1348941Y1059945D03*
X1347091Y1050378D03*
X1348941Y1053567D03*
X1339689Y1050378D03*
X1341540Y1047189D03*
X1335989Y1050378D03*
X1348941Y1072701D03*
X1347091Y1063134D03*
Y1069512D03*
X1348941Y1066323D03*
X1339689Y1063134D03*
X1335989D03*
X1341540Y1066323D03*
X1339689Y1069512D03*
X1335989D03*
X1341540Y1072701D03*
X1347091Y1075890D03*
X1348941Y1079079D03*
X1347091Y1082268D03*
Y1088646D03*
X1348941Y1085457D03*
X1339689Y1075890D03*
X1335989D03*
X1341540Y1079079D03*
X1339689Y1082268D03*
X1335989D03*
X1341540Y1085457D03*
X1335989Y1088646D03*
X1339689D03*
X1347091Y1101402D03*
X1348941Y1091835D03*
X1347091Y1095024D03*
X1348941Y1098213D03*
Y1104591D03*
X1335989Y1101402D03*
X1341540Y1104591D03*
X1339689Y1095024D03*
X1335989D03*
X1341540Y1098213D03*
X1339689Y1101402D03*
X1341540Y1091835D03*
X1348941Y1110969D03*
X1347091Y1114158D03*
X1348941Y1117347D03*
X1347091Y1107780D03*
X1339689Y1114158D03*
X1335989D03*
X1341540Y1117347D03*
X1335989Y1107780D03*
X1339689D03*
X1341540Y1110969D03*
X1347091Y1120536D03*
X1348941Y1130102D03*
X1347091Y1133292D03*
Y1126914D03*
X1348941Y1123725D03*
X1339689Y1120536D03*
X1335989D03*
X1341540Y1123725D03*
X1339689Y1133292D03*
X1335989D03*
Y1126914D03*
X1339689D03*
X1341540Y1130102D03*
X1348941Y1136480D03*
X1347091Y1139669D03*
X1348941Y1149236D03*
X1347091Y1146047D03*
X1348941Y1142858D03*
X1341540Y1136480D03*
X1339689Y1139669D03*
X1335989D03*
X1341540Y1142858D03*
X1335989Y1146047D03*
X1339689D03*
X1341540Y1149236D03*
X1347091Y1152425D03*
X1339689D03*
X1335989D03*
X1338263Y1563608D03*
X1342987D03*
X1347712D03*
X1335113Y1566336D03*
X1339838D03*
X1344562D03*
X1349287D03*
X1364414Y892379D03*
X1360713D03*
X1351461Y889190D03*
X1353311Y892379D03*
X1351461Y895568D03*
X1364414Y905134D03*
Y898757D03*
Y911512D03*
X1360713Y905134D03*
Y898757D03*
Y911512D03*
X1353311D03*
X1351461Y901946D03*
X1353311Y905134D03*
X1351461Y908324D03*
X1353311Y898757D03*
X1351461Y921079D03*
X1353311Y924268D03*
X1351461Y914701D03*
X1353311Y917890D03*
X1351461Y927457D03*
X1353311Y930646D03*
X1351461Y940213D03*
Y933835D03*
X1353311Y937024D03*
Y943402D03*
X1351461Y946591D03*
X1353311Y949780D03*
X1351461Y952969D03*
X1353311Y956158D03*
X1351461Y965725D03*
X1353311Y968914D03*
X1351461Y959347D03*
X1353311Y962536D03*
X1351461Y984859D03*
Y978481D03*
X1353311Y981670D03*
X1351461Y972103D03*
X1353311Y975292D03*
Y988048D03*
X1351461Y997615D03*
X1353311Y1000804D03*
Y994426D03*
X1351461Y1003993D03*
X1353311Y1007182D03*
X1354493Y1031244D03*
X1352642Y1034433D03*
X1354493Y1037622D03*
X1352642Y1040811D03*
X1354493Y1050378D03*
X1352642Y1047189D03*
X1354493Y1063134D03*
X1352642Y1066323D03*
X1354493Y1069512D03*
X1352642Y1072701D03*
X1354493Y1075890D03*
X1352642Y1079079D03*
X1354493Y1082268D03*
X1352642Y1085457D03*
X1354493Y1088646D03*
X1352642Y1104591D03*
X1354493Y1095024D03*
X1352642Y1098213D03*
X1354493Y1101402D03*
X1352642Y1091835D03*
X1354493Y1114158D03*
X1352642Y1117347D03*
X1354493Y1107780D03*
X1352642Y1110969D03*
X1361894Y1114158D03*
Y1107780D03*
X1354493Y1120536D03*
X1352642Y1123725D03*
X1354493Y1133292D03*
Y1126914D03*
X1352642Y1130102D03*
X1361894Y1120536D03*
Y1126914D03*
Y1133292D03*
X1352642Y1136480D03*
X1354493Y1139669D03*
X1352642Y1142858D03*
X1354493Y1146047D03*
X1352642Y1149236D03*
X1361894Y1139669D03*
Y1146047D03*
X1354493Y1152425D03*
X1352642Y1155614D03*
X1361894Y1158803D03*
X1358193D03*
X1361894Y1152425D03*
X1352436Y1563608D03*
X1357161D03*
X1361885D03*
X1354011Y1566336D03*
X1358735D03*
X1363460D03*
X1375516Y892379D03*
X1371815D03*
X1375516Y898757D03*
Y905134D03*
X1371815Y898757D03*
Y905134D03*
X1365595Y1114158D03*
Y1107780D03*
X1376697Y1114158D03*
Y1107780D03*
X1372997Y1114158D03*
Y1107780D03*
X1365595Y1120536D03*
X1376697D03*
Y1126914D03*
X1372997Y1120536D03*
Y1126914D03*
X1365595D03*
Y1133292D03*
X1376697D03*
X1372997D03*
X1365595Y1139669D03*
Y1146047D03*
X1376697Y1139669D03*
Y1146047D03*
X1372997Y1139669D03*
Y1146047D03*
Y1158803D03*
X1369296D03*
X1365595Y1152425D03*
X1376697D03*
X1372997D03*
X1371334Y1563608D03*
X1376058D03*
X1366609D03*
X1372909Y1566336D03*
X1377633D03*
X1368184D03*
X1386619Y892379D03*
X1394020D03*
X1382918D03*
X1386619Y905134D03*
Y898757D03*
X1394020Y905134D03*
Y898757D03*
X1382918Y905134D03*
Y898757D03*
X1387800Y1114158D03*
X1384099D03*
X1387800Y1120536D03*
Y1126914D03*
X1384099Y1120536D03*
Y1126914D03*
X1387800Y1133292D03*
X1384099D03*
X1387800Y1139669D03*
Y1146047D03*
X1384099Y1139669D03*
Y1146047D03*
Y1158803D03*
X1380398D03*
X1391500D03*
X1387800Y1152425D03*
X1384099D03*
X1380783Y1563608D03*
X1385507D03*
X1390232D03*
X1382357Y1566336D03*
X1387082D03*
X1391806D03*
X1406973Y895568D03*
X1397721Y892379D03*
X1403272Y895568D03*
X1406973Y908324D03*
Y901946D03*
X1397721Y905134D03*
Y898757D03*
X1403272Y908324D03*
Y901946D03*
X1398902Y1114158D03*
X1408154Y1117347D03*
Y1110969D03*
X1395201Y1114158D03*
X1404453Y1117347D03*
Y1110969D03*
X1398902Y1120536D03*
Y1126914D03*
X1408154Y1123725D03*
X1395201Y1120536D03*
Y1126914D03*
X1404453Y1123725D03*
X1398902Y1133292D03*
X1408154Y1130102D03*
X1395201Y1133292D03*
X1404453Y1130102D03*
X1398902Y1139669D03*
Y1146047D03*
X1408154Y1142858D03*
Y1136480D03*
X1395201Y1139669D03*
Y1146047D03*
X1404453Y1142858D03*
Y1136480D03*
X1395201Y1158803D03*
X1398902Y1152425D03*
X1395201D03*
X1394956Y1563608D03*
X1396531Y1566336D03*
X1434704Y892379D03*
X1425452Y895568D03*
X1438405Y892379D03*
X1429153Y895568D03*
X1434704Y898757D03*
Y905134D03*
X1425452Y901946D03*
Y908324D03*
X1438405Y898757D03*
Y905134D03*
X1429153Y901946D03*
Y908324D03*
X1434704Y911512D03*
X1438405D03*
X1434704Y917890D03*
Y924268D03*
X1425452Y914701D03*
Y921079D03*
X1438405Y917890D03*
Y924268D03*
X1429153Y914701D03*
Y921079D03*
X1438405Y937024D03*
X1429153Y940213D03*
X1434704Y937024D03*
X1425452Y940213D03*
Y927457D03*
X1429153D03*
X1438405Y943402D03*
Y956158D03*
X1429153Y946591D03*
Y952969D03*
X1438405Y949780D03*
X1434704Y943402D03*
Y956158D03*
X1425452Y946591D03*
Y952969D03*
X1434704Y949780D03*
X1426633Y1110969D03*
Y1117347D03*
X1435885Y1114158D03*
X1430334Y1110969D03*
Y1117347D03*
Y1130102D03*
X1426633D03*
Y1123725D03*
X1435885Y1126914D03*
Y1120536D03*
X1430334Y1123725D03*
X1435885Y1133292D03*
Y1146047D03*
Y1139669D03*
X1426633Y1136480D03*
Y1142858D03*
X1430334Y1136480D03*
Y1142858D03*
X1445806Y892379D03*
X1449507D03*
X1445806Y898757D03*
Y905134D03*
X1449507Y898757D03*
Y905134D03*
X1445806Y911512D03*
X1449507D03*
X1445806Y917890D03*
Y924268D03*
X1449507Y917890D03*
Y924268D03*
Y949780D03*
Y943402D03*
Y956158D03*
X1445806Y949780D03*
Y943402D03*
Y956158D03*
X1446987Y1114158D03*
X1439586D03*
X1450688D03*
X1446987Y1126914D03*
Y1120536D03*
X1439586Y1126914D03*
Y1120536D03*
X1450688Y1126914D03*
Y1120536D03*
X1446987Y1133292D03*
X1450688D03*
X1439586D03*
X1446987Y1139669D03*
X1450688D03*
X1446987Y1146047D03*
X1439586D03*
Y1139669D03*
X1450688Y1146047D03*
X1468011Y892379D03*
X1456909D03*
X1460609D03*
X1468011Y911512D03*
Y898757D03*
Y905134D03*
X1456909Y898757D03*
Y905134D03*
X1460609Y898757D03*
Y905134D03*
X1456909Y911512D03*
X1460609D03*
X1468011Y924268D03*
Y917890D03*
X1456909Y924268D03*
Y917890D03*
X1460609Y924268D03*
Y917890D03*
X1468011Y930646D03*
X1456909D03*
X1460609D03*
Y949780D03*
Y943402D03*
Y956158D03*
X1468011Y949780D03*
Y943402D03*
Y956158D03*
X1456909Y949780D03*
Y943402D03*
Y956158D03*
X1458090Y1114158D03*
Y1107780D03*
X1461791Y1114158D03*
Y1107780D03*
X1458090Y1133292D03*
X1461791D03*
X1458090Y1126914D03*
Y1120536D03*
X1461791Y1126914D03*
Y1120536D03*
X1458090Y1146047D03*
Y1139669D03*
X1461791Y1146047D03*
Y1139669D03*
X1461777Y1552698D03*
X1460202Y1549970D03*
X1464926D03*
X1466501Y1552698D03*
X1460202Y1563608D03*
X1464926D03*
X1461777Y1566336D03*
X1466501D03*
X1471712Y892379D03*
X1480964Y889190D03*
X1479113Y892379D03*
X1480964Y895568D03*
X1471712Y911512D03*
Y898757D03*
Y905134D03*
X1479113Y911512D03*
X1480964Y901946D03*
X1479113Y905134D03*
X1480964Y908324D03*
X1479113Y898757D03*
X1480964Y921079D03*
X1479113Y924268D03*
X1480964Y914701D03*
X1479113Y917890D03*
X1471712Y924268D03*
Y917890D03*
X1480964Y927457D03*
X1479113Y930646D03*
X1480964Y940213D03*
Y933835D03*
X1479113Y937024D03*
X1471712Y930646D03*
Y949780D03*
Y943402D03*
Y956158D03*
X1479113Y943402D03*
X1480964Y946591D03*
X1479113Y949780D03*
X1480964Y952969D03*
X1479113Y956158D03*
X1480964Y965725D03*
X1479113Y968914D03*
X1480964Y959347D03*
X1479113Y962536D03*
X1480964Y984859D03*
Y978481D03*
X1479113Y981670D03*
X1480964Y972103D03*
X1479113Y975292D03*
Y988048D03*
X1480964Y997615D03*
X1479113Y1000804D03*
X1480964Y991237D03*
Y1003993D03*
X1479113Y1007182D03*
X1480295Y1031244D03*
X1482145Y1034433D03*
X1480295Y1037622D03*
X1482145Y1040811D03*
X1480295Y1044000D03*
Y1050378D03*
X1482145Y1047189D03*
X1480295Y1063134D03*
X1482145Y1066323D03*
X1480295Y1069512D03*
X1482145Y1072701D03*
X1480295Y1075890D03*
X1482145Y1079079D03*
X1480295Y1082268D03*
X1482145Y1085457D03*
X1480295Y1088646D03*
X1482145Y1104591D03*
X1480295Y1095024D03*
X1482145Y1098213D03*
X1480295Y1101402D03*
X1482145Y1091835D03*
X1480295Y1114158D03*
X1482145Y1117347D03*
X1480295Y1107780D03*
X1482145Y1110969D03*
X1469192Y1107780D03*
Y1114158D03*
X1472893Y1107780D03*
Y1114158D03*
X1480295Y1120536D03*
X1482145Y1123725D03*
X1480295Y1133292D03*
Y1126914D03*
X1482145Y1130102D03*
X1469192Y1120536D03*
X1472893D03*
X1469192Y1133292D03*
Y1126914D03*
X1472893Y1133292D03*
Y1126914D03*
X1482145Y1136480D03*
X1480295Y1139669D03*
X1482145Y1142858D03*
X1480295Y1146047D03*
X1482145Y1149236D03*
X1469192Y1146047D03*
Y1139669D03*
X1472893Y1146047D03*
Y1139669D03*
X1480295Y1152425D03*
X1482145Y1155614D03*
X1479099Y1549970D03*
X1483824D03*
X1480674Y1552698D03*
X1469651Y1549970D03*
X1474375D03*
X1471225Y1552698D03*
X1475950D03*
X1469651Y1563608D03*
X1474375D03*
X1479099D03*
X1483824D03*
X1471225Y1566336D03*
X1475950D03*
X1480674D03*
X1486515Y886001D03*
X1484665Y889190D03*
Y895568D03*
X1486515Y892379D03*
X1497617Y886001D03*
X1492066Y889190D03*
X1493917Y892379D03*
X1492066Y895568D03*
X1497617Y892379D03*
X1484665Y908324D03*
X1486515Y898757D03*
X1484665Y901946D03*
X1486515Y905134D03*
Y911512D03*
X1493917D03*
X1497617Y898757D03*
X1492066Y901946D03*
X1493917Y905134D03*
X1497617D03*
X1492066Y908324D03*
X1497617Y911512D03*
X1493917Y898757D03*
X1486515Y917890D03*
X1484665Y921079D03*
X1486515Y924268D03*
X1484665Y914701D03*
X1497617Y917890D03*
X1492066Y921079D03*
X1493917Y924268D03*
X1497617D03*
X1492066Y914701D03*
X1493917Y917890D03*
X1484665Y927457D03*
X1486515Y937024D03*
X1484665Y940213D03*
Y933835D03*
X1486515Y930646D03*
X1492066Y927457D03*
X1493917Y930646D03*
X1497617Y937024D03*
X1492066Y940213D03*
Y933835D03*
X1497617Y930646D03*
X1493917Y937024D03*
X1486515Y943402D03*
X1484665Y946591D03*
X1486515Y956158D03*
X1484665Y952969D03*
X1486515Y949780D03*
X1493917Y943402D03*
X1497617D03*
X1492066Y946591D03*
X1493917Y949780D03*
X1497617Y956158D03*
X1492066Y952969D03*
X1497617Y949780D03*
X1493917Y956158D03*
X1486515Y962536D03*
X1484665Y965725D03*
Y959347D03*
X1486515Y968914D03*
X1497617Y962536D03*
X1492066Y965725D03*
X1493917Y968914D03*
X1492066Y959347D03*
X1493917Y962536D03*
X1497617Y968914D03*
X1486515Y975292D03*
X1484665Y978481D03*
Y972103D03*
X1492066Y984859D03*
X1497617Y975292D03*
X1492066Y978481D03*
X1493917Y981670D03*
X1492066Y972103D03*
X1493917Y975292D03*
X1486515Y994426D03*
X1484665Y997615D03*
X1486515Y1000804D03*
Y988048D03*
X1493917D03*
X1497617Y994426D03*
X1492066Y997615D03*
X1493917Y1000804D03*
X1497617D03*
Y988048D03*
X1492066Y991237D03*
X1484665Y1010371D03*
X1486515Y1007182D03*
X1484665Y1003993D03*
X1497617Y1007182D03*
X1492066Y1003993D03*
X1493917Y1007182D03*
X1485846Y1034433D03*
X1487696Y1037622D03*
X1485846Y1040811D03*
X1495098Y1031244D03*
X1493247Y1034433D03*
X1498799Y1037622D03*
X1495098D03*
X1493247Y1040811D03*
X1495098Y1044000D03*
X1485846Y1059945D03*
X1487696Y1050378D03*
X1485846Y1053567D03*
X1495098Y1050378D03*
X1493247Y1047189D03*
X1498799Y1050378D03*
X1485846Y1072701D03*
X1487696Y1063134D03*
Y1069512D03*
X1485846Y1066323D03*
X1495098Y1063134D03*
X1498799D03*
X1493247Y1066323D03*
X1495098Y1069512D03*
X1498799D03*
X1493247Y1072701D03*
X1487696Y1075890D03*
X1485846Y1079079D03*
X1487696Y1082268D03*
Y1088646D03*
X1485846Y1085457D03*
X1495098Y1075890D03*
X1498799D03*
X1493247Y1079079D03*
X1495098Y1082268D03*
X1498799D03*
X1493247Y1085457D03*
X1498799Y1088646D03*
X1495098D03*
X1487696Y1101402D03*
X1485846Y1091835D03*
X1487696Y1095024D03*
X1485846Y1098213D03*
Y1104591D03*
X1498799Y1101402D03*
X1493247Y1104591D03*
X1495098Y1095024D03*
X1498799D03*
X1493247Y1098213D03*
X1495098Y1101402D03*
X1493247Y1091835D03*
X1485846Y1110969D03*
X1487696Y1114158D03*
X1485846Y1117347D03*
X1487696Y1107780D03*
X1495098Y1114158D03*
X1498799D03*
X1493247Y1117347D03*
X1498799Y1107780D03*
X1495098D03*
X1493247Y1110969D03*
X1487696Y1120536D03*
X1485846Y1130102D03*
X1487696Y1133292D03*
Y1126914D03*
X1485846Y1123725D03*
X1495098Y1120536D03*
X1498799D03*
X1493247Y1123725D03*
X1495098Y1133292D03*
X1498799D03*
Y1126914D03*
X1495098D03*
X1493247Y1130102D03*
X1485846Y1136480D03*
X1487696Y1139669D03*
X1485846Y1149236D03*
X1487696Y1146047D03*
X1485846Y1142858D03*
X1493247Y1136480D03*
X1495098Y1139669D03*
X1498799D03*
X1493247Y1142858D03*
X1498799Y1146047D03*
X1495098D03*
X1493247Y1149236D03*
X1487696Y1152425D03*
X1495098D03*
X1498799D03*
X1497997Y1549970D03*
X1488548D03*
X1493273D03*
X1485399Y1552698D03*
X1490123D03*
X1494847D03*
X1488548Y1563608D03*
X1493273D03*
X1497997D03*
X1485399Y1566336D03*
X1490123D03*
X1494847D03*
X1499468Y889190D03*
Y895568D03*
Y908324D03*
Y901946D03*
Y921079D03*
Y914701D03*
Y927457D03*
Y940213D03*
Y933835D03*
Y946591D03*
Y952969D03*
Y965725D03*
Y959347D03*
Y978481D03*
Y972103D03*
Y997615D03*
Y1010371D03*
Y1003993D03*
X1500649Y1034433D03*
Y1040811D03*
Y1059945D03*
Y1053567D03*
Y1072701D03*
Y1066323D03*
Y1079079D03*
Y1085457D03*
Y1091835D03*
Y1098213D03*
Y1104591D03*
Y1110969D03*
Y1117347D03*
Y1130102D03*
Y1123725D03*
Y1136480D03*
Y1149236D03*
Y1142858D03*
Y1155614D03*
X1507446Y1549970D03*
X1512170D03*
X1502721D03*
X1509021Y1552698D03*
X1513745D03*
X1499572D03*
X1504296D03*
X1507446Y1563608D03*
X1512170D03*
X1502721D03*
X1509021Y1566336D03*
X1513745D03*
X1499572D03*
X1504296D03*
X1516895Y1549970D03*
X1521619D03*
X1526344D03*
X1518469Y1552698D03*
X1523194D03*
X1527918D03*
X1516895Y1563608D03*
X1521619D03*
X1526344D03*
X1518469Y1566336D03*
X1523194D03*
X1527918D03*
X1538326Y886001D03*
X1532775Y889190D03*
X1536476D03*
X1530925Y892379D03*
X1536476Y895568D03*
X1532775D03*
X1538326Y892379D03*
X1536476Y908324D03*
X1530925Y911512D03*
X1538326Y898757D03*
X1532775Y901946D03*
X1536476D03*
X1530925Y905134D03*
X1538326D03*
X1532775Y908324D03*
X1538326Y911512D03*
X1530925Y898757D03*
X1538326Y917890D03*
X1532775Y921079D03*
X1536476D03*
X1530925Y924268D03*
X1538326D03*
X1536476Y914701D03*
X1532775D03*
X1530925Y917890D03*
X1532775Y927457D03*
X1536476D03*
X1530925Y930646D03*
X1538326Y937024D03*
X1532775Y940213D03*
X1536476D03*
Y933835D03*
X1532775D03*
X1538326Y930646D03*
X1530925Y937024D03*
Y943402D03*
X1538326D03*
X1532775Y946591D03*
X1536476D03*
X1530925Y949780D03*
X1538326Y956158D03*
X1536476Y952969D03*
X1532775D03*
X1538326Y949780D03*
X1530925Y956158D03*
X1538326Y962536D03*
X1532775Y965725D03*
X1536476D03*
X1530925Y968914D03*
X1532775Y959347D03*
X1536476D03*
X1530925Y962536D03*
X1538326Y968914D03*
X1532775Y984859D03*
X1538326Y975292D03*
X1532775Y978481D03*
X1536476D03*
X1530925Y981670D03*
X1536476Y972103D03*
X1532775D03*
X1530925Y975292D03*
Y988048D03*
X1538326Y994426D03*
X1536476Y997615D03*
X1532775D03*
X1530925Y1000804D03*
X1538326D03*
Y988048D03*
X1532775Y991237D03*
X1536476Y1010371D03*
X1538326Y1007182D03*
X1536476Y1003993D03*
X1532775D03*
X1530925Y1007182D03*
X1532106Y1031244D03*
X1533956Y1034433D03*
X1537657D03*
X1539507Y1037622D03*
X1532106D03*
X1533956Y1040811D03*
X1537657D03*
X1532106Y1044000D03*
Y1050378D03*
X1537657Y1059945D03*
X1533956Y1047189D03*
X1539507Y1050378D03*
X1537657Y1053567D03*
Y1072701D03*
X1532106Y1063134D03*
X1539507D03*
X1533956Y1066323D03*
X1532106Y1069512D03*
X1539507D03*
X1533956Y1072701D03*
X1537657Y1066323D03*
X1532106Y1075890D03*
X1539507D03*
X1533956Y1079079D03*
X1537657D03*
X1532106Y1082268D03*
X1539507D03*
X1533956Y1085457D03*
X1539507Y1088646D03*
X1532106D03*
X1537657Y1085457D03*
X1539507Y1101402D03*
X1533956Y1104591D03*
X1537657Y1091835D03*
X1532106Y1095024D03*
X1539507D03*
X1533956Y1098213D03*
X1537657D03*
X1532106Y1101402D03*
X1537657Y1104591D03*
X1533956Y1091835D03*
X1537657Y1110969D03*
X1532106Y1114158D03*
X1539507D03*
X1533956Y1117347D03*
X1537657D03*
X1539507Y1107780D03*
X1532106D03*
X1533956Y1110969D03*
X1532106Y1120536D03*
X1539507D03*
X1533956Y1123725D03*
X1537657Y1130102D03*
X1532106Y1133292D03*
X1539507D03*
Y1126914D03*
X1532106D03*
X1537657Y1123725D03*
X1533956Y1130102D03*
Y1136480D03*
X1537657D03*
X1532106Y1139669D03*
X1539507D03*
X1533956Y1142858D03*
X1537657Y1149236D03*
X1539507Y1146047D03*
X1532106D03*
X1537657Y1142858D03*
X1533956Y1149236D03*
X1532106Y1152425D03*
X1539507D03*
X1533956Y1155614D03*
X1531068Y1549970D03*
X1532643Y1552698D03*
X1531068Y1563608D03*
X1532643Y1566336D03*
X1588264Y1549970D03*
Y1563608D03*
X1592988Y1549970D03*
X1597713D03*
X1602437D03*
X1589839Y1552698D03*
X1594563D03*
X1599287D03*
X1592988Y1563608D03*
X1597713D03*
X1602437D03*
X1589839Y1566336D03*
X1594563D03*
X1599287D03*
X1607161Y1549970D03*
X1611886D03*
X1616610D03*
X1604012Y1552698D03*
X1608736D03*
X1613461D03*
X1607161Y1563608D03*
X1611886D03*
X1616610D03*
X1604012Y1566336D03*
X1608736D03*
X1613461D03*
X1621335Y1549970D03*
X1626059D03*
X1630783D03*
X1618185Y1552698D03*
X1622909D03*
X1627634D03*
X1632358D03*
X1621335Y1563608D03*
X1626059D03*
X1630783D03*
X1618185Y1566336D03*
X1622909D03*
X1627634D03*
X1632358D03*
X1635508Y1549970D03*
X1640232D03*
X1644957D03*
X1637083Y1552698D03*
X1641807D03*
X1646531D03*
X1635508Y1563608D03*
X1640232D03*
X1644957D03*
X1637083Y1566336D03*
X1641807D03*
X1646531D03*
X1649681Y1549970D03*
X1654406D03*
X1659130D03*
X1651256Y1552698D03*
X1655980D03*
X1660705D03*
X1649681Y1563608D03*
X1654406D03*
X1659130D03*
X1651256Y1566336D03*
X1655980D03*
X1660705D03*
G54D34*
X230905Y1649173D03*
Y1653897D03*
Y1663346D03*
Y1668070D03*
Y1677519D03*
Y1682244D03*
X238779Y1653110D03*
Y1657834D03*
X246653Y1663346D03*
Y1668070D03*
Y1677519D03*
Y1682244D03*
X238779Y1681456D03*
Y1686180D03*
X254527Y1667283D03*
Y1672007D03*
Y1681456D03*
Y1686180D03*
X270275Y1653110D03*
Y1657834D03*
Y1667283D03*
Y1672007D03*
X262401Y1677519D03*
X270275Y1681456D03*
X262401Y1682244D03*
X270275Y1686180D03*
X278149Y1649173D03*
X286023Y1653110D03*
X278149Y1653897D03*
X286023Y1657834D03*
X278149Y1663346D03*
X286023Y1667283D03*
X278149Y1668070D03*
X286023Y1672007D03*
X278149Y1677519D03*
X286023Y1681456D03*
X278149Y1682244D03*
X286023Y1686180D03*
X297835Y1677519D03*
X305709Y1681456D03*
X297835Y1682244D03*
X305709Y1686180D03*
X313583Y1677519D03*
X321457Y1681456D03*
X313583Y1682244D03*
X321457Y1686180D03*
X329331Y1677519D03*
Y1682244D03*
X345079Y1677519D03*
Y1682244D03*
X337205Y1681456D03*
Y1686180D03*
X352953Y1681456D03*
Y1686180D03*
X495078Y1677519D03*
Y1682244D03*
X510826Y1677519D03*
Y1682244D03*
X502952Y1681456D03*
Y1686180D03*
X518700Y1681456D03*
Y1686180D03*
X526574Y1677519D03*
Y1682244D03*
X542322Y1677519D03*
Y1682244D03*
X534448Y1681456D03*
Y1686180D03*
X550196Y1681456D03*
Y1686180D03*
X562008Y1677519D03*
X569882Y1681456D03*
X562008Y1682244D03*
X569882Y1686180D03*
X577756Y1677519D03*
X585630Y1681456D03*
X577756Y1682244D03*
X585630Y1686180D03*
X593504Y1677519D03*
X601378Y1681456D03*
X593504Y1682244D03*
X601378Y1686180D03*
X609252Y1677519D03*
X617126Y1681456D03*
X609252Y1682244D03*
X617126Y1686180D03*
X1238778Y1677519D03*
Y1682244D03*
X1254526Y1677519D03*
Y1682244D03*
X1246652Y1681456D03*
Y1686180D03*
X1262400Y1681456D03*
Y1686180D03*
X1270274Y1677519D03*
Y1682244D03*
X1286022Y1677519D03*
Y1682244D03*
X1278148Y1681456D03*
Y1686180D03*
X1293896Y1681456D03*
Y1686180D03*
X1305708Y1677519D03*
X1313582Y1681456D03*
X1305708Y1682244D03*
X1313582Y1686180D03*
X1321456Y1677519D03*
X1329330Y1681456D03*
X1321456Y1682244D03*
X1329330Y1686180D03*
X1337204Y1677519D03*
X1345078Y1681456D03*
X1337204Y1682244D03*
X1345078Y1686180D03*
X1352952Y1677519D03*
X1360826Y1681456D03*
X1352952Y1682244D03*
X1360826Y1686180D03*
X1502952Y1677519D03*
X1510826Y1681456D03*
X1502952Y1682244D03*
X1510826Y1686180D03*
X1518700Y1677519D03*
X1526574Y1681456D03*
X1518700Y1682244D03*
X1526574Y1686180D03*
X1534448Y1677519D03*
X1542322Y1681456D03*
X1534448Y1682244D03*
X1542322Y1686180D03*
X1550196Y1677519D03*
X1558070Y1681456D03*
X1550196Y1682244D03*
X1558070Y1686180D03*
X1569882Y1677519D03*
Y1682244D03*
X1585630Y1677519D03*
Y1682244D03*
X1577756Y1681456D03*
Y1686180D03*
X1593504Y1681456D03*
Y1686180D03*
X1601378Y1677519D03*
Y1682244D03*
X1617126Y1677519D03*
Y1682244D03*
X1609252Y1681456D03*
Y1686180D03*
X1625000Y1681456D03*
Y1686180D03*
G54D50*
X676509Y145866D03*
G54D35*
X230905Y1691692D03*
Y1696417D03*
Y1705866D03*
Y1710590D03*
Y1720039D03*
Y1724763D03*
Y1734212D03*
X238779Y1643661D03*
X246653Y1649173D03*
Y1653897D03*
X238779Y1667283D03*
Y1672007D03*
X246653Y1691692D03*
Y1696417D03*
X238779Y1695629D03*
Y1700354D03*
X246653Y1705866D03*
Y1710590D03*
X238779Y1709803D03*
Y1714527D03*
X246653Y1720039D03*
Y1724763D03*
X238779Y1723976D03*
Y1728700D03*
X246653Y1734212D03*
X254527Y1643661D03*
Y1653110D03*
Y1657834D03*
Y1695629D03*
Y1700354D03*
Y1709803D03*
Y1714527D03*
Y1723976D03*
Y1728700D03*
X270275Y1643661D03*
X262401Y1649173D03*
Y1653897D03*
Y1663346D03*
Y1668070D03*
Y1691692D03*
X270275Y1695629D03*
X262401Y1696417D03*
X270275Y1700354D03*
X262401Y1705866D03*
X270275Y1709803D03*
X262401Y1710590D03*
X270275Y1714527D03*
X262401Y1720039D03*
X270275Y1723976D03*
X262401Y1724763D03*
X270275Y1728700D03*
X262401Y1734212D03*
X286023Y1643661D03*
X278149Y1691692D03*
X286023Y1695629D03*
X278149Y1696417D03*
X286023Y1700354D03*
X278149Y1705866D03*
X286023Y1709803D03*
X278149Y1710590D03*
X286023Y1714527D03*
X278149Y1720039D03*
X286023Y1723976D03*
X278149Y1724763D03*
X286023Y1728700D03*
X278149Y1734212D03*
X305709Y1672007D03*
X297835Y1691692D03*
X305709Y1695629D03*
X297835Y1696417D03*
X305709Y1700354D03*
X297835Y1705866D03*
X305709Y1709803D03*
X297835Y1710590D03*
X305709Y1714527D03*
X297835Y1720039D03*
X305709Y1723976D03*
X297835Y1724763D03*
X305709Y1728700D03*
X297835Y1734212D03*
X321457Y1672007D03*
X313583Y1691692D03*
X321457Y1695629D03*
X313583Y1696417D03*
X321457Y1700354D03*
X313583Y1705866D03*
X321457Y1709803D03*
X313583Y1710590D03*
X321457Y1714527D03*
X313583Y1720039D03*
X321457Y1723976D03*
X313583Y1724763D03*
X321457Y1728700D03*
X313583Y1734212D03*
X329331Y1691692D03*
Y1696417D03*
Y1705866D03*
Y1710590D03*
Y1720039D03*
Y1724763D03*
Y1734212D03*
X337205Y1672007D03*
X345079Y1691692D03*
Y1696417D03*
X337205Y1695629D03*
Y1700354D03*
X345079Y1705866D03*
Y1710590D03*
X337205Y1709803D03*
Y1714527D03*
X345079Y1720039D03*
Y1724763D03*
X337205Y1723976D03*
Y1728700D03*
X345079Y1734212D03*
X352953Y1672007D03*
Y1695629D03*
Y1700354D03*
Y1709803D03*
Y1714527D03*
Y1723976D03*
Y1728700D03*
X495078Y1691692D03*
Y1696417D03*
Y1705866D03*
Y1710590D03*
Y1720039D03*
Y1724763D03*
Y1734212D03*
X502952Y1672007D03*
X510826Y1691692D03*
Y1696417D03*
X502952Y1695629D03*
Y1700354D03*
X510826Y1705866D03*
Y1710590D03*
X502952Y1709803D03*
Y1714527D03*
X510826Y1720039D03*
Y1724763D03*
X502952Y1723976D03*
Y1728700D03*
X510826Y1734212D03*
X518700Y1672007D03*
Y1695629D03*
Y1700354D03*
X526574Y1691692D03*
Y1696417D03*
X518700Y1709803D03*
Y1714527D03*
X526574Y1705866D03*
Y1710590D03*
X518700Y1723976D03*
Y1728700D03*
X526574Y1720039D03*
Y1724763D03*
Y1734212D03*
X534448Y1672007D03*
X542322Y1691692D03*
Y1696417D03*
X534448Y1695629D03*
Y1700354D03*
X542322Y1705866D03*
Y1710590D03*
X534448Y1709803D03*
Y1714527D03*
X542322Y1720039D03*
Y1724763D03*
X534448Y1723976D03*
Y1728700D03*
X542322Y1734212D03*
X550196Y1672007D03*
Y1695629D03*
Y1700354D03*
Y1709803D03*
Y1714527D03*
Y1723976D03*
Y1728700D03*
X569882Y1672007D03*
X562008Y1691692D03*
X569882Y1695629D03*
X562008Y1696417D03*
X569882Y1700354D03*
X562008Y1705866D03*
X569882Y1709803D03*
X562008Y1710590D03*
X569882Y1714527D03*
X562008Y1720039D03*
X569882Y1723976D03*
X562008Y1724763D03*
X569882Y1728700D03*
X562008Y1734212D03*
X585630Y1672007D03*
X577756Y1691692D03*
X585630Y1695629D03*
X577756Y1696417D03*
X585630Y1700354D03*
X577756Y1705866D03*
X585630Y1709803D03*
X577756Y1710590D03*
X585630Y1714527D03*
X577756Y1720039D03*
X585630Y1723976D03*
X577756Y1724763D03*
X585630Y1728700D03*
X577756Y1734212D03*
X601378Y1672007D03*
X593504Y1691692D03*
X601378Y1695629D03*
X593504Y1696417D03*
X601378Y1700354D03*
X593504Y1705866D03*
X601378Y1709803D03*
X593504Y1710590D03*
X601378Y1714527D03*
X593504Y1720039D03*
X601378Y1723976D03*
X593504Y1724763D03*
X601378Y1728700D03*
X593504Y1734212D03*
X617126Y1672007D03*
X609252Y1691692D03*
X617126Y1695629D03*
X609252Y1696417D03*
X617126Y1700354D03*
X609252Y1705866D03*
X617126Y1709803D03*
X609252Y1710590D03*
X617126Y1714527D03*
X609252Y1720039D03*
X617126Y1723976D03*
X609252Y1724763D03*
X617126Y1728700D03*
X609252Y1734212D03*
X1238778Y1691692D03*
Y1696417D03*
Y1705866D03*
Y1710590D03*
Y1720039D03*
Y1724763D03*
Y1734212D03*
X1246652Y1672007D03*
X1254526Y1691692D03*
Y1696417D03*
X1246652Y1695629D03*
Y1700354D03*
X1254526Y1705866D03*
Y1710590D03*
X1246652Y1709803D03*
Y1714527D03*
X1254526Y1720039D03*
Y1724763D03*
X1246652Y1723976D03*
Y1728700D03*
X1254526Y1734212D03*
X1262400Y1672007D03*
Y1695629D03*
Y1700354D03*
X1270274Y1691692D03*
Y1696417D03*
X1262400Y1709803D03*
Y1714527D03*
X1270274Y1705866D03*
Y1710590D03*
X1262400Y1723976D03*
Y1728700D03*
X1270274Y1720039D03*
Y1724763D03*
Y1734212D03*
X1278148Y1672007D03*
X1286022Y1691692D03*
Y1696417D03*
X1278148Y1695629D03*
Y1700354D03*
X1286022Y1705866D03*
Y1710590D03*
X1278148Y1709803D03*
Y1714527D03*
X1286022Y1720039D03*
Y1724763D03*
X1278148Y1723976D03*
Y1728700D03*
X1286022Y1734212D03*
X1293896Y1672007D03*
Y1695629D03*
Y1700354D03*
Y1709803D03*
Y1714527D03*
Y1723976D03*
Y1728700D03*
X1313582Y1672007D03*
X1305708Y1691692D03*
X1313582Y1695629D03*
X1305708Y1696417D03*
X1313582Y1700354D03*
X1305708Y1705866D03*
X1313582Y1709803D03*
X1305708Y1710590D03*
X1313582Y1714527D03*
X1305708Y1720039D03*
X1313582Y1723976D03*
X1305708Y1724763D03*
X1313582Y1728700D03*
X1305708Y1734212D03*
X1329330Y1672007D03*
X1321456Y1691692D03*
X1329330Y1695629D03*
X1321456Y1696417D03*
X1329330Y1700354D03*
X1321456Y1705866D03*
X1329330Y1709803D03*
X1321456Y1710590D03*
X1329330Y1714527D03*
X1321456Y1720039D03*
X1329330Y1723976D03*
X1321456Y1724763D03*
X1329330Y1728700D03*
X1321456Y1734212D03*
X1345078Y1672007D03*
X1337204Y1691692D03*
X1345078Y1695629D03*
X1337204Y1696417D03*
X1345078Y1700354D03*
X1337204Y1705866D03*
X1345078Y1709803D03*
X1337204Y1710590D03*
X1345078Y1714527D03*
X1337204Y1720039D03*
X1345078Y1723976D03*
X1337204Y1724763D03*
X1345078Y1728700D03*
X1337204Y1734212D03*
X1360826Y1672007D03*
X1352952Y1691692D03*
X1360826Y1695629D03*
X1352952Y1696417D03*
X1360826Y1700354D03*
X1352952Y1705866D03*
X1360826Y1709803D03*
X1352952Y1710590D03*
X1360826Y1714527D03*
X1352952Y1720039D03*
X1360826Y1723976D03*
X1352952Y1724763D03*
X1360826Y1728700D03*
X1352952Y1734212D03*
X1510826Y1672007D03*
X1502952Y1691692D03*
X1510826Y1695629D03*
X1502952Y1696417D03*
X1510826Y1700354D03*
X1502952Y1705866D03*
X1510826Y1709803D03*
X1502952Y1710590D03*
X1510826Y1714527D03*
X1502952Y1720039D03*
X1510826Y1723976D03*
X1502952Y1724763D03*
X1510826Y1728700D03*
X1502952Y1734212D03*
X1526574Y1672007D03*
X1518700Y1691692D03*
X1526574Y1695629D03*
X1518700Y1696417D03*
X1526574Y1700354D03*
X1518700Y1705866D03*
X1526574Y1709803D03*
X1518700Y1710590D03*
X1526574Y1714527D03*
X1518700Y1720039D03*
X1526574Y1723976D03*
X1518700Y1724763D03*
X1526574Y1728700D03*
X1518700Y1734212D03*
X1542322Y1672007D03*
X1534448Y1691692D03*
X1542322Y1695629D03*
X1534448Y1696417D03*
X1542322Y1700354D03*
X1534448Y1705866D03*
X1542322Y1709803D03*
X1534448Y1710590D03*
X1542322Y1714527D03*
X1534448Y1720039D03*
X1542322Y1723976D03*
X1534448Y1724763D03*
X1542322Y1728700D03*
X1534448Y1734212D03*
X1558070Y1672007D03*
X1550196Y1691692D03*
X1558070Y1695629D03*
X1550196Y1696417D03*
X1558070Y1700354D03*
X1550196Y1705866D03*
X1558070Y1709803D03*
X1550196Y1710590D03*
X1558070Y1714527D03*
X1550196Y1720039D03*
X1558070Y1723976D03*
X1550196Y1724763D03*
X1558070Y1728700D03*
X1550196Y1734212D03*
X1569882Y1691692D03*
Y1696417D03*
Y1705866D03*
Y1710590D03*
Y1720039D03*
Y1724763D03*
Y1734212D03*
X1577756Y1672007D03*
X1585630Y1691692D03*
Y1696417D03*
X1577756Y1695629D03*
Y1700354D03*
X1585630Y1705866D03*
Y1710590D03*
X1577756Y1709803D03*
Y1714527D03*
X1585630Y1720039D03*
Y1724763D03*
X1577756Y1723976D03*
Y1728700D03*
X1585630Y1734212D03*
X1593504Y1672007D03*
Y1695629D03*
Y1700354D03*
X1601378Y1691692D03*
Y1696417D03*
X1593504Y1709803D03*
Y1714527D03*
X1601378Y1705866D03*
Y1710590D03*
X1593504Y1723976D03*
Y1728700D03*
X1601378Y1720039D03*
Y1724763D03*
Y1734212D03*
X1609252Y1672007D03*
X1617126Y1691692D03*
Y1696417D03*
X1609252Y1695629D03*
Y1700354D03*
X1617126Y1705866D03*
Y1710590D03*
X1609252Y1709803D03*
Y1714527D03*
X1617126Y1720039D03*
Y1724763D03*
X1609252Y1723976D03*
Y1728700D03*
X1617126Y1734212D03*
X1625000Y1672007D03*
Y1695629D03*
Y1700354D03*
Y1709803D03*
Y1714527D03*
Y1723976D03*
Y1728700D03*
G54D74*
X1859986Y1403418D03*
X1859706Y1709011D03*
X1871790Y476573D03*
X1861790D03*
X1870648Y783729D03*
X1860648D03*
X1862295Y850767D03*
X1872295D03*
X1871790Y1158071D03*
X1861790D03*
X1869986Y1403418D03*
X1869706Y1709011D03*
X1881862Y107291D03*
X1882340Y410829D03*
X1882711Y476864D03*
X1882240Y783474D03*
X1883273Y850816D03*
X1882579Y1158348D03*
X1881223Y1404467D03*
X1881177Y1709323D03*
X1891862Y107291D03*
X1892340Y410829D03*
X1892711Y476864D03*
X1892240Y783474D03*
X1893273Y850816D03*
X1892579Y1158348D03*
X1891223Y1404467D03*
X1891177Y1709323D03*
X2082012Y108312D03*
X2072012D03*
X2071128Y410829D03*
X2081128D03*
G54D13*
X27559Y87795D03*
X40708Y631889D03*
Y1368908D03*
X51180Y1714961D03*
X373622Y87795D03*
X395671Y1714960D03*
X661024Y631890D03*
X707677Y1714960D03*
X800787Y87795D03*
X931693Y757874D03*
X931692Y1072835D03*
X931693Y1387795D03*
X1045866Y87795D03*
X1155709Y1714961D03*
X1271260Y631890D03*
X1461806Y1714961D03*
X1499606Y87795D03*
X1806298Y1714961D03*
X1829921Y87795D03*
X1816772Y631889D03*
Y1368897D03*
G54D37*
X277098Y185236D03*
X395208D03*
G54D65*
X1183858Y217205D03*
X1173858D03*
X1193858D03*
G54D47*
X443467Y594259D03*
X1425533Y601230D03*
G54D16*
X27048Y1533228D03*
X79590Y1369350D03*
X137284Y1533228D03*
X215418Y658055D03*
X276440Y1357539D03*
X420125Y656008D03*
X443764Y1339823D03*
X523173Y578174D03*
X681440Y1385138D03*
X791678D03*
X873622Y1145275D03*
X983858D03*
X1052960Y1369350D03*
X1249812Y1357539D03*
X1370284Y582303D03*
X1417134Y1339823D03*
X1533552Y682342D03*
X1629732Y1383523D03*
X1664890Y642972D03*
X1714330Y1570984D03*
X1739968Y1383527D03*
X1761575Y159134D03*
X1824566Y1570988D03*
X1838150Y201929D03*
G54D52*
X757184Y1702772D03*
X1072863Y1409176D03*
X1080970Y1640958D03*
G54D66*
X1225530Y60384D03*
G54D73*
X1835198Y1601502D03*
G54D77*
X1864986Y1390234D03*
X1886862Y94107D03*
X1887711Y463680D03*
X1888273Y837632D03*
G54D75*
X1866790Y463389D03*
X1867295Y837583D03*
X1886223Y1391283D03*
X2077012Y95128D03*
G54D39*
X303154Y879624D03*
Y886002D03*
X305004Y882813D03*
X303154Y892380D03*
Y898758D03*
X310555Y873246D03*
X317957Y879624D03*
X310555D03*
X319807Y876435D03*
X314256Y873246D03*
X310555Y886002D03*
X314256D03*
X316107Y882813D03*
Y889191D03*
X308705D03*
X319807Y882813D03*
X314256Y892380D03*
X308705Y895569D03*
Y882813D03*
X314256Y898758D03*
X316107Y901947D03*
X308705D03*
Y908325D03*
X314256Y911513D03*
X316107Y908325D03*
X314256Y917891D03*
X308705Y914702D03*
Y921080D03*
X316107D03*
Y940214D03*
X308705Y927458D03*
X316107D03*
X308705Y933836D03*
X314256Y930647D03*
Y937025D03*
X308705Y940214D03*
X314256Y949781D03*
X316107Y946592D03*
X308705D03*
Y952970D03*
X314256Y956159D03*
X316107Y959348D03*
X308705D03*
Y965726D03*
X316107D03*
X314256Y968915D03*
X317957Y981671D03*
X308705Y978482D03*
X316107D03*
X314256Y975293D03*
X308705Y972104D03*
X316107Y984860D03*
X308705D03*
X312406D03*
X319807D03*
X308705Y991238D03*
X310555Y988049D03*
X314256D03*
X316107Y997616D03*
X308705D03*
X314256Y994427D03*
X316107Y1003994D03*
X314256Y1007183D03*
X316107Y1010372D03*
X308705D03*
Y1003994D03*
X327209Y876435D03*
X332760Y879624D03*
X325358D03*
X334598Y872066D03*
X334610Y882813D03*
X321658Y886002D03*
X325358D03*
X330910Y882813D03*
X329059Y886002D03*
X334610Y889191D03*
X327209D03*
X334610Y895569D03*
X321658Y892380D03*
X327209Y895569D03*
X329059Y892380D03*
X334610Y901947D03*
X321658Y898758D03*
X327209Y901947D03*
X329059Y898758D03*
X321658Y905135D03*
Y911513D03*
X329059Y905135D03*
Y911513D03*
X327209Y908325D03*
X334610Y908324D03*
Y914702D03*
X321658Y917891D03*
X327209Y914702D03*
X329059Y917891D03*
X334610Y921080D03*
X321658Y924269D03*
X329059D03*
X327209Y921080D03*
X334610Y927458D03*
Y933836D03*
X321658Y930647D03*
X327209Y927458D03*
Y933836D03*
X329059Y930647D03*
X334610Y940214D03*
X321658Y937025D03*
X327209Y940214D03*
X329059Y937025D03*
Y956159D03*
X334610Y946592D03*
X321658Y943403D03*
Y949781D03*
X329059Y943403D03*
Y949781D03*
X327209Y946592D03*
X334610Y952970D03*
X321658Y956159D03*
X327209Y952970D03*
X334610Y959348D03*
Y965726D03*
X329059Y962537D03*
X327209Y965726D03*
X321658Y962537D03*
X327209Y959348D03*
X321658Y968915D03*
X329059D03*
X334610Y972104D03*
Y978482D03*
X321658Y975293D03*
Y981671D03*
X329059Y975293D03*
X327209Y972104D03*
X332760Y981671D03*
X329059D03*
X327209Y978482D03*
X334610Y984860D03*
X327209D03*
X330910D03*
X334610Y991238D03*
Y997616D03*
X321658Y988049D03*
Y994427D03*
X327209Y991238D03*
X329059Y988049D03*
Y994427D03*
X327209Y997616D03*
X321658Y1000805D03*
X329059D03*
X334610Y1003994D03*
Y1010372D03*
X321658Y1007183D03*
X327209Y1010372D03*
X329059Y1007183D03*
X327209Y1003994D03*
X343862Y879624D03*
X340162Y879568D03*
X345713Y882813D03*
X336461Y886002D03*
X340162D03*
X347563D03*
X342012Y882813D03*
X347563Y892380D03*
X342012Y889191D03*
X340162Y892380D03*
X347563Y898758D03*
Y905135D03*
Y911513D03*
X342012Y901947D03*
X340162Y898758D03*
Y911513D03*
X342012Y908325D03*
X347563Y917891D03*
Y924269D03*
X340162Y917891D03*
X342012Y921080D03*
X347563Y930647D03*
Y937025D03*
X342012Y927458D03*
X340162Y930647D03*
X342012Y940214D03*
X340162Y937025D03*
X347563Y943403D03*
Y949781D03*
Y956159D03*
X340162Y949781D03*
X342012Y946592D03*
X340162Y956159D03*
X347563Y962537D03*
Y968915D03*
X342012Y959348D03*
Y965726D03*
X340162Y968915D03*
X347563Y975293D03*
Y981671D03*
X345713Y984860D03*
X340162Y975293D03*
X343862Y981671D03*
X342012Y978482D03*
Y984860D03*
X347563Y988049D03*
Y994427D03*
Y1000805D03*
X340162Y988049D03*
X342012Y997616D03*
X340162Y994427D03*
X347563Y1007183D03*
X342012Y1010372D03*
X340162Y1007183D03*
X342012Y1003994D03*
X351265Y879568D03*
X360516Y876435D03*
X354965Y879624D03*
X356803Y872066D03*
X351264Y886002D03*
X362366D03*
X356815Y882813D03*
X360516D03*
X353114D03*
X354965Y886002D03*
Y892380D03*
X360516Y889191D03*
Y895569D03*
X353114Y889191D03*
Y895569D03*
X354965Y898758D03*
X360516Y901947D03*
X353114D03*
X354965Y911513D03*
Y905135D03*
X360516Y908325D03*
X353114Y908324D03*
X354965Y917891D03*
X360516Y914702D03*
X353114D03*
X354965Y924269D03*
X360516Y921080D03*
X353114D03*
X354965Y930647D03*
X360516Y927458D03*
Y933836D03*
X353114D03*
Y927458D03*
X354965Y937025D03*
X360516Y940214D03*
X353114D03*
X360516Y946592D03*
X353114D03*
X360516Y952970D03*
X353114D03*
X354965Y956159D03*
Y943403D03*
Y949781D03*
X360516Y959348D03*
Y965726D03*
X353114Y959348D03*
Y965726D03*
X354965Y962537D03*
Y968915D03*
Y975293D03*
Y981671D03*
X360516Y972104D03*
Y978482D03*
X358665Y981671D03*
X353114Y972104D03*
Y978482D03*
X360516Y984860D03*
X356815D03*
X353114D03*
X360516Y997616D03*
Y991238D03*
X353114D03*
Y997616D03*
X354965Y988049D03*
Y994427D03*
Y1000805D03*
Y1007183D03*
X360516Y1003994D03*
X353114D03*
X360516Y1010372D03*
X353114D03*
X369768Y879624D03*
X373469D03*
X375319Y876435D03*
X377169Y879624D03*
X366067Y886002D03*
Y892380D03*
X367917Y889191D03*
X373469Y892380D03*
X367917Y882813D03*
X373469Y886002D03*
X379020Y882813D03*
X377169Y886002D03*
X379020Y895569D03*
X366067Y898758D03*
Y911513D03*
X367917Y901947D03*
X373469Y898758D03*
X379020Y908325D03*
X373469Y911513D03*
Y905135D03*
X367917Y908324D03*
X366067Y917891D03*
X373469D03*
X367917Y921080D03*
X373469Y924269D03*
X379020Y921080D03*
X366067Y930647D03*
Y937025D03*
X367917Y927458D03*
X379020Y933836D03*
X373469Y930647D03*
X367917Y940214D03*
X373469Y937025D03*
X379020Y940214D03*
X366067Y949781D03*
Y956159D03*
X367917Y946592D03*
X373469Y943403D03*
Y949781D03*
Y956159D03*
X379020Y952970D03*
X366067Y968915D03*
X367917Y959348D03*
Y965726D03*
X373469Y962537D03*
Y968915D03*
X379020Y965726D03*
X366067Y975293D03*
X369768Y981671D03*
X367917Y978482D03*
X373469Y975293D03*
Y981671D03*
X367917Y984860D03*
X379020D03*
X371618D03*
X379020Y978482D03*
X366067Y994427D03*
Y988049D03*
X367917Y997616D03*
X379020Y991238D03*
X373469Y988049D03*
X379020Y997616D03*
X373469Y994427D03*
Y1000805D03*
X366067Y1007183D03*
X373469D03*
X367917Y1003994D03*
X379020D03*
X367917Y1010372D03*
X386421Y876435D03*
X388272Y879624D03*
X384571Y873246D03*
X382721Y882813D03*
Y889191D03*
X380870Y892380D03*
X384571Y886002D03*
X386421Y882813D03*
X393823D03*
X388272Y886002D03*
X390122Y882813D03*
X391973Y892380D03*
X390122Y895569D03*
X386421Y889191D03*
X393823D03*
X382721Y901947D03*
X380870Y898758D03*
Y911513D03*
Y905135D03*
X393823Y901947D03*
X391973Y898758D03*
X390122Y901947D03*
X386421D03*
X391973Y905135D03*
Y911513D03*
X390122Y908325D03*
X382721Y914702D03*
X380870Y917891D03*
Y924269D03*
X386421Y914702D03*
X391973Y917891D03*
X393823Y914702D03*
X390122D03*
Y921080D03*
X391973Y924269D03*
X382721Y927458D03*
Y933836D03*
X380870Y930647D03*
X386421Y927458D03*
Y933836D03*
X393823Y927458D03*
X390122D03*
X393823Y933836D03*
X391973Y930647D03*
X390122Y933836D03*
Y940214D03*
X382721Y946592D03*
X380870Y943403D03*
Y949781D03*
Y956159D03*
X386421Y946592D03*
X391973Y943403D03*
Y949781D03*
X393823Y946592D03*
X390122D03*
X391973Y956159D03*
X390122Y952970D03*
X382721Y959348D03*
X380870Y962537D03*
Y968915D03*
X393823Y959348D03*
X390122D03*
Y965726D03*
X386421Y959348D03*
X391973Y962537D03*
Y968915D03*
X386421Y984860D03*
X382721Y972104D03*
X380870Y975293D03*
X393823Y972104D03*
X390122D03*
Y978482D03*
X384571Y981671D03*
X391973D03*
Y975293D03*
X386421Y972104D03*
X393823Y984860D03*
X391973Y988049D03*
X384571Y994427D03*
Y988049D03*
X391973Y994427D03*
X393823Y991238D03*
X386421D03*
Y997616D03*
X391973Y1000805D03*
X384571D03*
X393823Y997616D03*
X386421Y1003994D03*
X382721Y1010372D03*
X390122D03*
X391973Y1007183D03*
X393823Y1003994D03*
X395673Y1007183D03*
X384571D03*
X410477Y873246D03*
X397524Y876435D03*
X399374Y873246D03*
Y879624D03*
X397524Y882813D03*
Y889191D03*
X401225Y882813D03*
X408626D03*
X404925D03*
X401225Y895569D03*
X408626Y889191D03*
X404925D03*
X403075Y892380D03*
X397524Y901947D03*
X401225D03*
X408626D03*
X404925D03*
X403075Y898758D03*
Y905135D03*
Y911513D03*
X401225Y908324D03*
X397524Y914702D03*
X401225D03*
X408626D03*
X403075Y917891D03*
X404925Y914702D03*
X401225Y921080D03*
X403075Y924269D03*
X401225Y933836D03*
X408626Y927458D03*
X404925D03*
X403075Y930647D03*
X401225Y940214D03*
X397524Y927458D03*
Y933836D03*
X401225Y927458D03*
X397524Y946592D03*
X401225D03*
X403075Y943403D03*
X408626Y946592D03*
X403075Y949781D03*
X404925Y946592D03*
X401225Y952970D03*
X403075Y956159D03*
X397524Y959348D03*
X401225Y965726D03*
Y959348D03*
X408626D03*
X404925D03*
X403075Y962537D03*
Y968915D03*
X397524Y972104D03*
X401225D03*
X408626D03*
X404925D03*
X399374Y981671D03*
X406776D03*
X401225Y978482D03*
X403075Y975293D03*
X401225Y984860D03*
X408626D03*
Y991238D03*
X399374Y988049D03*
Y994427D03*
X406776Y988049D03*
X401225Y991238D03*
Y997616D03*
X399374Y1000805D03*
X397524Y1010372D03*
X399374Y1007183D03*
X401225Y1003994D03*
X421579Y873246D03*
X412327Y882813D03*
Y895569D03*
X414177Y892380D03*
X419729Y882813D03*
X416028D03*
X423429Y895569D03*
X425280Y892380D03*
X416028Y889191D03*
X419729D03*
X412327Y901947D03*
X414177Y898758D03*
Y905135D03*
Y911513D03*
X412327Y908325D03*
X423429Y901947D03*
X425280Y898758D03*
X419729Y901947D03*
X416028D03*
X425280Y905135D03*
Y911513D03*
X423429Y908324D03*
X414177Y917891D03*
X412327Y914702D03*
X414177Y924269D03*
X412327Y921080D03*
X423429Y914702D03*
X419729D03*
X416028D03*
X425280Y917891D03*
Y924269D03*
X423429Y921080D03*
X412327Y927458D03*
Y933836D03*
X414177Y930647D03*
X412327Y940214D03*
X414177Y937025D03*
X423429Y927458D03*
X419729D03*
X423429Y933836D03*
X425280Y930647D03*
X419729Y933836D03*
X416028Y927458D03*
Y933836D03*
X425280Y937025D03*
X423429Y940214D03*
X414177Y949781D03*
X412327Y946592D03*
X414177Y943403D03*
X412327Y952970D03*
X414177Y956159D03*
X416028Y946592D03*
X425280Y943403D03*
Y949781D03*
X423429Y946592D03*
X419729D03*
X423429Y952970D03*
X425280Y956159D03*
X412327Y965726D03*
Y959348D03*
X414177Y962537D03*
Y968915D03*
X423429Y965726D03*
X416028Y959348D03*
X423429D03*
X419729D03*
X425280Y962537D03*
Y968915D03*
X416028Y972104D03*
X423429D03*
X419729D03*
X416028Y984860D03*
X423429D03*
X412327Y978482D03*
X414177Y981671D03*
Y975293D03*
X412327Y972104D03*
X423429Y978482D03*
X421579Y981671D03*
X425280Y975293D03*
X414177Y988049D03*
X421579D03*
X423429Y991238D03*
X416028D03*
X434532Y876435D03*
X432681Y879624D03*
X430831Y882813D03*
X427130D03*
X430831Y889191D03*
X427130D03*
X434532Y895569D03*
Y889191D03*
X428981Y905135D03*
X434532Y901947D03*
X432681Y905135D03*
X434532Y908325D03*
X428981Y917891D03*
X432681D03*
X434532Y914702D03*
Y921080D03*
X428981Y930647D03*
Y937025D03*
X432681Y930647D03*
X434532Y927458D03*
Y933836D03*
X432681Y937025D03*
X434532Y940214D03*
X428981Y949781D03*
X432681D03*
X434532Y946592D03*
Y952970D03*
X428981Y962537D03*
X432681D03*
X434532Y959348D03*
Y965726D03*
X428981Y981671D03*
Y975293D03*
X430831Y984860D03*
X434532Y972104D03*
X432681Y975293D03*
X434532Y978482D03*
X430831Y991238D03*
X428981Y988049D03*
X445609Y876435D03*
X447460Y879624D03*
X445609Y882813D03*
Y889191D03*
Y895569D03*
X453011Y882813D03*
X449310Y889191D03*
X453011D03*
X454861Y892380D03*
X445609Y901947D03*
Y908325D03*
X454861Y898758D03*
X451160Y905135D03*
X454861D03*
Y911513D03*
X447460Y905135D03*
X445609Y914702D03*
Y921080D03*
X447460Y917891D03*
X451160D03*
X454861D03*
Y924269D03*
Y930647D03*
X447460Y937025D03*
X451160D03*
X454861D03*
X445609Y927458D03*
Y933836D03*
Y940214D03*
X447460Y930647D03*
X451160D03*
X445609Y946592D03*
Y952970D03*
X447460Y949781D03*
X454861Y943403D03*
X451160Y949781D03*
X454861D03*
Y956159D03*
X445609Y959348D03*
Y965726D03*
X454861Y962537D03*
X451160D03*
X447460D03*
X454861Y968915D03*
X445609Y972104D03*
Y978482D03*
Y984860D03*
X447460Y981671D03*
X454861D03*
X451160Y975293D03*
X447460D03*
X454861D03*
X453011Y984860D03*
X445609Y991238D03*
X453011D03*
X454861Y988049D03*
X447460D03*
X460412Y876435D03*
X469664Y879624D03*
X460412Y889191D03*
X456712Y895569D03*
X467814Y882813D03*
X465964Y892380D03*
X467814Y895569D03*
X464113Y889191D03*
X456712Y908324D03*
X465964Y911513D03*
X456712Y901947D03*
X460412D03*
X465964Y898758D03*
X467814Y901947D03*
X464113D03*
X467814Y908325D03*
X465964Y905135D03*
X460412Y914702D03*
X456712D03*
Y921080D03*
X467814Y914702D03*
X464113D03*
X465964Y917891D03*
X467814Y921080D03*
X465964Y924269D03*
X460412Y927458D03*
X456712D03*
Y933836D03*
X460412D03*
X456712Y940214D03*
X467814Y927458D03*
Y933836D03*
X464113Y927458D03*
Y933836D03*
X467814Y940214D03*
X465964Y937025D03*
X460412Y946592D03*
X456712D03*
Y952970D03*
X467814Y946592D03*
X464113D03*
X465964Y943403D03*
Y949781D03*
X467814Y952970D03*
X465964Y956159D03*
X456712Y965726D03*
X460412Y959348D03*
X456712D03*
X467814Y965726D03*
Y959348D03*
X465964Y962537D03*
X464113Y959348D03*
X465964Y968915D03*
X456712Y972104D03*
Y978482D03*
X462263Y981671D03*
X460412Y972104D03*
Y984860D03*
X469664Y981671D03*
X467814Y978482D03*
Y972104D03*
X465964Y975293D03*
X464113Y972104D03*
X467814Y984860D03*
X460412Y991238D03*
X462263Y988049D03*
X469664D03*
X467814Y991238D03*
X471515Y876435D03*
X480767Y873246D03*
Y879624D03*
X482617Y876435D03*
X478916Y882813D03*
X475215D03*
X471515D03*
X478916Y895569D03*
X477066Y892380D03*
X475215Y889191D03*
X471515D03*
X482617Y882813D03*
Y889191D03*
X478916Y901947D03*
X471515D03*
X475215D03*
X477066Y898758D03*
X478916Y908325D03*
X477066Y905135D03*
Y911513D03*
X482617Y901947D03*
X478916Y914702D03*
X477066Y917891D03*
X475215Y914702D03*
X471515D03*
X478916Y921080D03*
X477066Y924269D03*
X482617Y914702D03*
X478916Y927458D03*
Y933836D03*
X475215Y927458D03*
X471515D03*
X477066Y930647D03*
X478916Y940214D03*
X482617Y927458D03*
Y933836D03*
X478916Y946592D03*
X477066Y943403D03*
X475215Y946592D03*
X471515D03*
X477066Y949781D03*
X478916Y952970D03*
X477066Y956159D03*
X482617Y946592D03*
X478916Y965726D03*
Y959348D03*
X475215D03*
X471515D03*
X477066Y962537D03*
Y968915D03*
X482617Y959348D03*
X478916Y978482D03*
Y972104D03*
X477066Y981671D03*
Y975293D03*
X475215Y972104D03*
X471515D03*
X475215Y984860D03*
X484467Y981671D03*
X482617Y972104D03*
Y984860D03*
X477066Y994427D03*
X475215Y991238D03*
X477066Y988049D03*
Y1000805D03*
X484467Y994427D03*
Y988049D03*
X482617Y991238D03*
Y997616D03*
X484467Y1000805D03*
X477066Y1007183D03*
X484467D03*
X482617Y1010372D03*
Y1003994D03*
X493719Y876435D03*
X491869Y879624D03*
X493719Y882813D03*
X490019D03*
X486318D03*
X493719Y889191D03*
X486318D03*
X490019Y895569D03*
X488168Y892380D03*
X497420Y889191D03*
X499271Y892380D03*
X493719Y901947D03*
X486318D03*
X490019D03*
X488168Y898758D03*
Y905135D03*
Y911513D03*
X497420Y901947D03*
X499271Y898758D03*
Y905135D03*
Y911513D03*
X490019Y908324D03*
X493719Y914702D03*
X488168Y917891D03*
X490019Y914702D03*
X486318D03*
X490019Y921080D03*
X488168Y924269D03*
X499271Y917891D03*
X497420Y914702D03*
X499271Y924269D03*
X493719Y927458D03*
X486318D03*
X490019D03*
X493719Y933836D03*
X490019D03*
X486318D03*
X488168Y930647D03*
X490019Y940214D03*
X497420Y927458D03*
Y933836D03*
X499271Y930647D03*
X488168Y943403D03*
X493719Y946592D03*
X490019D03*
X486318D03*
X488168Y949781D03*
X490019Y952970D03*
X488168Y956159D03*
X497420Y946592D03*
X499271Y943403D03*
Y949781D03*
Y956159D03*
X490019Y965726D03*
X493719Y959348D03*
X490019D03*
X486318D03*
X488168Y962537D03*
Y968915D03*
X499271Y962537D03*
X497420Y959348D03*
X499271Y968915D03*
X491869Y981671D03*
X490019Y978482D03*
X493719Y972104D03*
X488168Y975293D03*
X490019Y972104D03*
X486318D03*
X490019Y984860D03*
X497420Y972104D03*
X499271Y975293D03*
Y981671D03*
X497420Y984860D03*
X491869Y994427D03*
Y988049D03*
X490019Y997616D03*
Y991238D03*
X491869Y1000805D03*
X497420Y991238D03*
Y997616D03*
X499271Y988049D03*
Y994427D03*
Y1000805D03*
X491869Y1007183D03*
X490019Y1010372D03*
Y1003994D03*
X497420Y1010372D03*
Y1003994D03*
X499271Y1007183D03*
X502971Y879624D03*
X501133Y872118D03*
X508523Y882813D03*
X506672Y886002D03*
X502971D03*
X504822Y882813D03*
X506672Y892380D03*
X501121Y895569D03*
X512223Y882813D03*
X514074Y886002D03*
X512223Y889191D03*
X514074Y892380D03*
X506672Y898758D03*
Y905135D03*
Y911513D03*
X501121Y908325D03*
X512223Y901947D03*
X514074Y898758D03*
Y911513D03*
X512223Y908325D03*
X506672Y917891D03*
X501121Y921080D03*
X506672Y924269D03*
X514074Y917891D03*
X512223Y921080D03*
X506672Y930647D03*
X501121Y933836D03*
X506672Y937025D03*
X501121Y940214D03*
X512223Y927458D03*
X514074Y930647D03*
X512223Y940214D03*
X514074Y937025D03*
X506672Y943403D03*
Y949781D03*
X501121Y952970D03*
X506672Y956159D03*
X514074Y949781D03*
X512223Y946592D03*
X514074Y956159D03*
X506672Y962537D03*
X501121Y965726D03*
X506672Y968915D03*
X512223Y959348D03*
Y965726D03*
X514074Y968915D03*
X510373Y981671D03*
X506672Y975293D03*
Y981671D03*
X501121Y978482D03*
X508523Y984860D03*
X514074Y975293D03*
X512223Y978482D03*
Y984860D03*
X506672Y988049D03*
Y994427D03*
Y1000805D03*
X514074Y988049D03*
Y994427D03*
X512223Y997616D03*
X506672Y1007183D03*
X514074D03*
X512223Y1003994D03*
X525176Y879624D03*
X515924Y876435D03*
X525176Y873246D03*
Y886002D03*
X523326Y882813D03*
X517775Y886002D03*
X519625Y882813D03*
X527027Y895569D03*
Y889191D03*
X525176Y892380D03*
X519625Y889191D03*
Y895569D03*
X528877Y886002D03*
X527027Y901947D03*
X525176Y898758D03*
X519625Y901947D03*
X525176Y905135D03*
Y911513D03*
X519625Y908325D03*
X527027Y908324D03*
X525176Y917891D03*
X519625Y914702D03*
X527027D03*
Y921080D03*
X525176Y924269D03*
X519625Y921080D03*
X525176Y937025D03*
X527027Y927458D03*
Y933836D03*
X525176Y930647D03*
X519625Y927458D03*
Y933836D03*
X527027Y940214D03*
X519625D03*
X527027Y946592D03*
X519625D03*
X525176Y943403D03*
Y949781D03*
X527027Y952970D03*
X525176Y956159D03*
X519625Y952970D03*
X527027Y959348D03*
Y965726D03*
X525176Y962537D03*
X519625Y959348D03*
Y965726D03*
X525176Y968915D03*
X521475Y981671D03*
X519625Y978482D03*
X527027Y984860D03*
X523326D03*
X519625D03*
X527027Y972104D03*
Y978482D03*
X525176Y975293D03*
Y981671D03*
X519625Y972104D03*
X527027Y991238D03*
Y997616D03*
X525176Y988049D03*
Y994427D03*
X519625Y991238D03*
Y997616D03*
X525176Y1000805D03*
X527027Y1010372D03*
Y1003994D03*
X525176Y1007183D03*
X519625Y1010372D03*
Y1003994D03*
X534428Y876435D03*
X539979Y879624D03*
X532578D03*
X541830Y876435D03*
X543680Y879624D03*
X538129Y889191D03*
X539979Y892380D03*
X532578D03*
X543680Y886002D03*
X538129Y882813D03*
X532578Y886002D03*
X534428Y882813D03*
X538129Y901947D03*
X539979Y898758D03*
X532578D03*
X539979Y911513D03*
X538129Y908325D03*
X532578Y905135D03*
Y911513D03*
X539979Y917891D03*
X532578D03*
X538129Y921080D03*
X532578Y924269D03*
X538129Y927458D03*
X539979Y930647D03*
X532578D03*
X539979Y937025D03*
X538129Y940214D03*
X532578Y937025D03*
X539979Y949781D03*
X538129Y946592D03*
X532578Y943403D03*
Y949781D03*
X539979Y956159D03*
X532578D03*
X538129Y959348D03*
Y965726D03*
X532578Y962537D03*
X539979Y968915D03*
X532578D03*
X539979Y975293D03*
X532578D03*
X538129Y978482D03*
X536279Y981671D03*
X532578D03*
X538129Y984860D03*
X534428D03*
X532578Y994427D03*
X539979Y988049D03*
X532578D03*
X539979Y994427D03*
X538129Y997616D03*
X532578Y1000805D03*
X539978Y1007184D03*
X538129Y1003994D03*
X532578Y1007183D03*
X545531Y876435D03*
X552932D03*
X556633D03*
X551082Y879624D03*
X545543Y872085D03*
X554783Y886002D03*
X549231Y882813D03*
X558483Y892380D03*
X545531Y889191D03*
Y895569D03*
X552932Y889191D03*
X551082Y892380D03*
X552932Y895569D03*
X558483Y886002D03*
X545531Y882813D03*
X551082Y886002D03*
X558483Y898758D03*
X545531Y901947D03*
X552932D03*
X551082Y898758D03*
X558483Y905135D03*
Y911513D03*
X551082Y905135D03*
Y911513D03*
X552932Y908325D03*
X545531Y908324D03*
X558483Y917891D03*
X551082D03*
X552932Y914702D03*
X545531D03*
X558483Y924269D03*
X551082D03*
X552932Y921080D03*
X545531D03*
X558483Y930647D03*
X545531Y927458D03*
Y933836D03*
X552932Y927458D03*
Y933836D03*
X551082Y930647D03*
X558483Y937025D03*
X545531Y940214D03*
X551082Y937025D03*
X552932Y940214D03*
X558483Y943403D03*
Y949781D03*
X545531Y946592D03*
X551082Y943403D03*
Y949781D03*
X552932Y946592D03*
X558483Y956159D03*
X545531Y952970D03*
X552932D03*
X551082Y956159D03*
X558483Y962537D03*
X545531Y959348D03*
Y965726D03*
X552932Y959348D03*
X551082Y962537D03*
X552932Y965726D03*
X558483Y968915D03*
X551082D03*
X558483Y975293D03*
Y981671D03*
X545531Y972104D03*
Y978482D03*
X547381Y981671D03*
X551082Y975293D03*
X552932Y972104D03*
X551082Y981671D03*
X552932Y978482D03*
Y984860D03*
X549231D03*
X545531D03*
X558483Y988049D03*
Y994427D03*
X552932Y991238D03*
X551082Y994427D03*
X552932Y997616D03*
X545531Y991238D03*
Y997616D03*
X551082Y988049D03*
X558483Y1000805D03*
X551082D03*
X558483Y1007183D03*
X545531Y1010372D03*
Y1003994D03*
X552932Y1010372D03*
X551082Y1007183D03*
X552932Y1003994D03*
X562184Y879624D03*
X569586Y873246D03*
X560334Y882813D03*
X564034D03*
X569586Y886002D03*
X571436Y882813D03*
Y889191D03*
X564034D03*
X565885Y892380D03*
X571436Y895569D03*
X564034Y901947D03*
X571436D03*
X565885Y898758D03*
X564034Y908325D03*
X571436D03*
X565885Y911513D03*
Y917891D03*
X571436Y914702D03*
X564034Y921080D03*
X571436D03*
X564034Y927458D03*
X571436D03*
X565885Y930647D03*
X571436Y933836D03*
X565885Y937025D03*
X564034Y940214D03*
X571436D03*
X565885Y949781D03*
X564034Y946592D03*
X571436D03*
Y952970D03*
X565885Y956159D03*
X564034Y959348D03*
X571436D03*
X564034Y965726D03*
X571436D03*
X565885Y968915D03*
X562184Y981671D03*
X565885Y975293D03*
X571436Y972104D03*
X564034Y978482D03*
X571436D03*
X567735Y984860D03*
X560334D03*
X564034D03*
X571436D03*
X569586Y988049D03*
X571436Y991238D03*
X565885Y994427D03*
X564034Y997616D03*
X571436D03*
X565885Y988049D03*
X571436Y1010372D03*
X565885Y1007183D03*
X564034Y1003994D03*
X571436D03*
X576987Y879624D03*
X575137Y882813D03*
X576987Y886002D03*
Y892380D03*
Y898758D03*
X1286697Y873245D03*
Y879623D03*
X1279296D03*
X1284847Y895568D03*
Y882812D03*
X1286697Y886001D03*
X1281146Y882812D03*
X1279296Y886001D03*
X1284847Y889190D03*
X1279296Y892379D03*
X1284847Y901946D03*
X1279296Y898757D03*
X1284847Y908324D03*
Y914701D03*
Y921079D03*
Y927457D03*
Y933835D03*
Y940213D03*
Y946591D03*
Y952969D03*
Y959347D03*
Y965725D03*
Y972103D03*
Y978481D03*
Y984859D03*
X1288548D03*
X1284847Y991237D03*
X1286697Y988048D03*
X1284847Y997615D03*
Y1010371D03*
Y1003993D03*
X1290398Y873245D03*
X1301500Y879623D03*
X1303351Y876434D03*
X1294099Y879623D03*
X1295949Y876434D03*
X1303351Y895568D03*
X1290398Y886001D03*
Y892379D03*
X1292249Y882812D03*
X1297800Y886001D03*
X1301500D03*
X1295949Y882812D03*
X1292249Y889190D03*
X1303351D03*
X1297800Y892379D03*
X1290398Y898757D03*
Y911512D03*
X1292249Y901946D03*
X1297800Y898757D03*
X1303351Y901946D03*
X1292249Y908324D03*
X1297800Y905134D03*
Y911512D03*
X1303351Y908324D03*
X1290398Y917890D03*
X1297800D03*
X1303351Y914701D03*
Y921079D03*
X1297800Y924268D03*
X1292249Y921079D03*
X1297800Y930646D03*
X1303351Y927457D03*
Y933835D03*
X1292249Y927457D03*
X1303351Y940213D03*
X1297800Y937024D03*
X1292249Y940213D03*
X1290398Y930646D03*
Y937024D03*
Y949780D03*
Y956158D03*
X1297800Y949780D03*
X1303351Y946591D03*
X1292249D03*
X1297800Y943402D03*
X1303351Y952969D03*
X1297800Y956158D03*
X1290398Y968914D03*
X1297800Y962536D03*
X1303351Y959347D03*
Y965725D03*
X1292249Y959347D03*
Y965725D03*
X1297800Y968914D03*
X1290398Y975292D03*
X1297800Y981670D03*
Y975292D03*
X1303351Y972103D03*
Y978481D03*
X1294099Y981670D03*
X1292249Y978481D03*
X1303351Y984859D03*
X1295949D03*
X1292249D03*
X1290398Y988048D03*
Y994426D03*
X1297800D03*
Y988048D03*
X1303351Y991237D03*
Y997615D03*
X1292249D03*
X1297800Y1000804D03*
X1290398Y1007182D03*
X1292249Y1010371D03*
X1297800Y1007182D03*
X1303351Y1010371D03*
Y1003993D03*
X1292249D03*
X1314453Y876434D03*
X1308902Y873245D03*
Y879623D03*
X1310752Y895568D03*
X1307052Y882812D03*
X1305201Y886001D03*
Y892379D03*
X1310752Y882812D03*
X1312603Y886001D03*
X1316304D03*
X1318154Y882812D03*
X1310752Y889190D03*
X1318154D03*
X1316304Y892379D03*
X1305201Y898757D03*
Y905134D03*
Y911512D03*
X1310752Y901946D03*
X1318154D03*
X1316304Y898757D03*
Y911512D03*
X1318154Y908324D03*
X1310752Y908323D03*
X1305201Y917890D03*
Y924268D03*
X1310752Y914701D03*
X1316304Y917890D03*
X1318154Y921079D03*
X1310752D03*
X1305201Y930646D03*
Y937024D03*
X1310752Y927457D03*
Y933835D03*
X1318154Y927457D03*
X1316304Y930646D03*
Y937024D03*
X1310752Y940213D03*
X1318154D03*
X1305201Y943402D03*
Y949780D03*
Y956158D03*
X1310752Y946591D03*
X1316304Y949780D03*
X1318154Y946591D03*
X1310752Y952969D03*
X1316304Y956158D03*
X1318154Y959347D03*
Y965725D03*
X1316304Y968914D03*
X1305201Y962536D03*
Y968914D03*
X1310752Y959347D03*
Y965725D03*
X1305201Y975292D03*
Y981670D03*
X1307052Y984859D03*
X1310752Y972103D03*
Y978481D03*
X1316304Y975292D03*
X1318154Y978481D03*
X1308902Y981670D03*
X1310752Y984859D03*
X1318154D03*
X1305201Y988048D03*
Y994426D03*
Y1000804D03*
X1310752Y991237D03*
Y997615D03*
X1316304Y988048D03*
X1318154Y997615D03*
X1316304Y994426D03*
X1305201Y1007182D03*
X1310752Y1003993D03*
Y1010371D03*
X1318154D03*
X1316304Y1007182D03*
X1318154Y1003993D03*
X1320004Y879623D03*
X1331107Y873245D03*
X1325556Y876434D03*
X1331107Y879623D03*
X1321855Y882812D03*
X1323705Y886001D03*
X1329256Y882812D03*
X1332957D03*
X1331107Y886001D03*
X1327406D03*
X1323705Y892379D03*
X1329256Y889190D03*
X1331107Y892379D03*
X1329256Y895568D03*
X1323705Y898757D03*
X1331107D03*
X1329256Y901946D03*
X1331107Y911512D03*
X1323705D03*
Y905134D03*
X1331107D03*
X1329256Y908323D03*
Y914701D03*
X1323705Y917890D03*
X1331107D03*
X1323705Y924268D03*
X1329256Y921079D03*
X1331107Y924268D03*
Y930646D03*
X1329256Y933835D03*
X1323705Y930646D03*
X1329256Y927457D03*
X1331107Y937024D03*
X1329256Y940213D03*
X1323705Y937024D03*
X1331107Y943402D03*
X1329256Y946591D03*
X1331107Y949780D03*
X1323705Y943402D03*
Y949780D03*
X1329256Y952969D03*
X1331107Y956158D03*
X1323705D03*
X1329256Y959347D03*
X1331107Y962536D03*
X1329256Y965725D03*
X1323705Y962536D03*
X1331107Y968914D03*
X1323705D03*
X1320004Y981670D03*
X1321855Y984859D03*
X1323705Y975292D03*
Y981670D03*
X1329256Y972103D03*
X1331107Y975292D03*
X1329256Y978481D03*
X1331107Y981670D03*
X1334807D03*
X1329256Y984859D03*
X1332957D03*
X1323705Y1000804D03*
Y988048D03*
Y994426D03*
X1329256Y997615D03*
X1331107Y988048D03*
X1329256Y991237D03*
X1331107Y994426D03*
Y1000804D03*
X1323705Y1007182D03*
X1329256Y1003993D03*
X1331107Y1007182D03*
X1329256Y1010371D03*
X1336658Y876434D03*
X1345910Y879623D03*
X1349611D03*
X1338508Y886001D03*
X1336658Y882812D03*
Y889190D03*
Y895568D03*
X1342209Y886001D03*
X1349611D03*
X1344059Y882812D03*
Y889190D03*
X1342209Y892379D03*
X1349611D03*
X1336658Y901946D03*
Y908324D03*
X1342209Y898757D03*
X1349611D03*
X1344059Y901946D03*
X1349611Y905134D03*
X1342209Y911512D03*
X1349611D03*
X1344059Y908323D03*
X1336658Y914701D03*
Y921079D03*
X1342209Y917890D03*
X1349611D03*
X1344059Y921079D03*
X1349611Y924268D03*
X1336658Y933835D03*
Y927457D03*
Y940213D03*
X1344059Y927457D03*
X1342209Y930646D03*
X1349611D03*
X1344059Y940213D03*
X1342209Y937024D03*
X1349611D03*
Y943402D03*
X1344059Y946591D03*
X1349611Y949780D03*
X1342209D03*
X1349611Y956158D03*
X1342209D03*
X1336658Y946591D03*
Y952969D03*
Y965725D03*
Y959347D03*
X1344059D03*
X1349611Y962536D03*
X1344059Y965725D03*
X1349611Y968914D03*
X1342209D03*
X1336658Y972103D03*
Y978481D03*
Y984859D03*
X1349611Y975292D03*
X1342209D03*
X1344059Y978481D03*
X1349611Y981670D03*
X1345910D03*
X1344059Y984859D03*
X1347760D03*
X1336658Y997615D03*
Y991237D03*
X1349611Y988048D03*
Y994426D03*
X1342209D03*
X1344059Y997615D03*
X1342209Y988048D03*
X1349611Y1000804D03*
X1336658Y1010371D03*
X1344059D03*
X1336658Y1003993D03*
X1344059D03*
X1342209Y1007182D03*
X1349611D03*
X1351461Y876434D03*
X1353311Y879623D03*
X1364414D03*
X1360713Y873245D03*
X1362563Y876434D03*
X1353311Y886001D03*
X1362563Y882812D03*
X1358863D03*
X1364414Y886001D03*
X1360713D03*
X1355162Y882812D03*
X1357012Y892379D03*
X1355162Y895568D03*
X1362563Y889190D03*
X1358863D03*
X1357012Y898757D03*
X1362563Y901946D03*
X1358863D03*
X1357012Y905134D03*
Y911512D03*
X1355162Y908324D03*
X1358863Y914701D03*
X1362563D03*
X1357012Y917890D03*
X1355162Y921079D03*
X1357012Y924268D03*
X1362563Y933835D03*
X1358863D03*
X1355162D03*
X1362563Y927457D03*
X1358863D03*
X1357012Y930646D03*
X1355162Y940213D03*
X1357012Y943402D03*
X1358863Y946591D03*
X1362563D03*
X1357012Y949780D03*
Y956158D03*
X1355162Y952969D03*
X1358863Y959347D03*
X1362563D03*
X1357012Y962536D03*
X1355162Y965725D03*
X1357012Y968914D03*
X1358863Y972103D03*
X1362563D03*
X1357012Y975292D03*
X1360713Y981670D03*
X1355162Y978481D03*
X1362563Y984859D03*
X1355162D03*
Y991237D03*
Y997615D03*
X1362563Y991237D03*
Y997615D03*
X1360713Y994426D03*
Y988048D03*
Y1000804D03*
X1358863Y1010371D03*
X1360713Y1007182D03*
X1362563Y1003993D03*
X1355162D03*
X1373666Y876434D03*
X1375516Y873245D03*
Y879623D03*
X1369965Y882812D03*
X1366264D03*
X1369965Y889190D03*
X1368115Y892379D03*
X1366264Y895568D03*
X1373666Y882812D03*
X1377367D03*
X1379217Y892379D03*
X1377367Y895568D03*
X1373666Y889190D03*
X1368115Y898757D03*
X1369965Y901946D03*
X1366264D03*
X1368115Y905134D03*
Y911512D03*
X1366264Y908324D03*
X1379217Y898757D03*
X1377367Y901946D03*
X1373666D03*
X1379217Y905134D03*
X1377367Y908324D03*
X1379217Y911512D03*
X1369965Y914701D03*
X1368115Y917890D03*
X1366264Y914701D03*
X1368115Y924268D03*
X1366264Y921079D03*
X1377367Y914701D03*
X1373666D03*
X1379217Y917890D03*
X1377367Y921079D03*
X1379217Y924268D03*
X1366264Y933835D03*
X1369965Y927457D03*
X1368115Y930646D03*
X1369965Y933835D03*
X1366264Y927457D03*
Y940213D03*
X1377367Y927457D03*
X1373666D03*
X1379217Y930646D03*
X1377367Y933835D03*
X1373666D03*
X1377367Y940213D03*
X1368115Y943402D03*
X1369965Y946591D03*
X1368115Y949780D03*
X1366264Y946591D03*
X1368115Y956158D03*
X1366264Y952969D03*
X1379217Y943402D03*
X1373666Y946591D03*
X1377367D03*
X1379217Y949780D03*
X1377367Y952969D03*
X1379217Y956158D03*
X1366264Y959347D03*
X1369965D03*
X1368115Y962536D03*
X1366264Y965725D03*
X1368115Y968914D03*
X1373666Y959347D03*
X1377367Y965725D03*
Y959347D03*
X1379217Y962536D03*
Y968914D03*
X1369965Y972103D03*
X1368115Y975292D03*
Y981670D03*
X1366264Y972103D03*
Y978481D03*
X1369965Y984859D03*
X1373666Y972103D03*
X1377367D03*
X1379217Y975292D03*
X1375516Y981670D03*
X1377367Y978481D03*
Y984859D03*
X1369965Y991237D03*
Y997615D03*
X1368115Y994426D03*
Y988048D03*
Y1000804D03*
X1375516Y994426D03*
X1377367Y991237D03*
Y997615D03*
X1375516Y988048D03*
Y1000804D03*
X1369965Y1003993D03*
X1368115Y1007182D03*
X1366264Y1010371D03*
X1373666D03*
X1375516Y1007182D03*
X1371815D03*
X1377367Y1003993D03*
X1386619Y879623D03*
X1382918Y873245D03*
X1384768Y876434D03*
X1394020Y873245D03*
X1384768Y882812D03*
X1381067D03*
Y889190D03*
X1384768D03*
X1392170Y882812D03*
X1388469D03*
Y895568D03*
X1392170Y889190D03*
X1390319Y892379D03*
X1381067Y901946D03*
X1384768D03*
X1388469D03*
X1390319Y898757D03*
X1392170Y901946D03*
X1388469Y908324D03*
X1390319Y911512D03*
Y905134D03*
X1381067Y914701D03*
X1384768D03*
X1390319Y917890D03*
X1388469Y914701D03*
X1392170D03*
X1388469Y921079D03*
X1390319Y924268D03*
X1381067Y927457D03*
X1384768D03*
X1388469D03*
Y933835D03*
X1392170Y927457D03*
X1390319Y930646D03*
X1392170Y933835D03*
X1388469Y940213D03*
X1390319Y937024D03*
X1381067Y946591D03*
X1384768D03*
X1388469D03*
X1390319Y943402D03*
X1392170Y946591D03*
X1390319Y949780D03*
X1388469Y952969D03*
X1390319Y956158D03*
X1381067Y959347D03*
X1384768D03*
X1388469Y965725D03*
Y959347D03*
X1392170D03*
X1390319Y962536D03*
Y968914D03*
X1388469Y978481D03*
X1381067Y972103D03*
X1384768D03*
X1382918Y981670D03*
X1384768Y984859D03*
X1388469Y972103D03*
X1392170D03*
X1390319Y981670D03*
Y975292D03*
X1392170Y984859D03*
X1384768Y991237D03*
X1382918Y988048D03*
X1392170Y991237D03*
X1390319Y988048D03*
X1397721Y873245D03*
Y879623D03*
X1395871Y876434D03*
X1408823Y879623D03*
X1399571Y882812D03*
X1395871D03*
X1401422Y892379D03*
X1399571Y895568D03*
X1395871Y889190D03*
X1403272Y882812D03*
X1406973D03*
X1403272Y889190D03*
X1406973D03*
X1399571Y901946D03*
X1395871D03*
X1401422Y905134D03*
Y911512D03*
X1405123Y905134D03*
X1408823D03*
X1401422Y898757D03*
X1399571Y908323D03*
Y914701D03*
X1401422Y917890D03*
X1395871Y914701D03*
X1399571Y921079D03*
X1401422Y924268D03*
X1405123Y917890D03*
X1408823D03*
X1395871Y927457D03*
Y933835D03*
X1399571Y927457D03*
X1401422Y930646D03*
X1399571Y933835D03*
Y940213D03*
X1401422Y937024D03*
X1405123Y930646D03*
X1408823D03*
X1405123Y937024D03*
X1408823D03*
X1401422Y943402D03*
X1399571Y946591D03*
X1401422Y949780D03*
X1399571Y952969D03*
X1401422Y956158D03*
X1408823Y949780D03*
X1405123D03*
X1395871Y946591D03*
X1399571Y965725D03*
X1395871Y959347D03*
X1399571D03*
X1401422Y962536D03*
Y968914D03*
X1408823Y962536D03*
X1405123D03*
X1397721Y981670D03*
X1399571Y978481D03*
X1395871Y972103D03*
X1399571D03*
X1401422Y975292D03*
X1399571Y984859D03*
X1405123Y981670D03*
X1408823Y975292D03*
X1405123D03*
X1406973Y984859D03*
X1399571Y991237D03*
X1397721Y988048D03*
X1406973Y991237D03*
X1405123Y988048D03*
X1410674Y876434D03*
X1423602Y879623D03*
X1421751Y876434D03*
X1410674Y882812D03*
Y889190D03*
Y895568D03*
X1421751Y882812D03*
Y895568D03*
Y889190D03*
X1410674Y901946D03*
Y908324D03*
X1421751Y901946D03*
X1423602Y905134D03*
X1421751Y908324D03*
X1410674Y914701D03*
Y921079D03*
X1423602Y917890D03*
X1421751Y914701D03*
Y921079D03*
Y940213D03*
X1410674Y927457D03*
Y933835D03*
Y940213D03*
X1423602Y930646D03*
X1421751Y927457D03*
Y933835D03*
X1423602Y937024D03*
X1410674Y946591D03*
Y952969D03*
X1423602Y949780D03*
X1421751Y946591D03*
Y952969D03*
X1410674Y959347D03*
Y965725D03*
X1423602Y962536D03*
X1421751Y959347D03*
Y965725D03*
X1410674Y972103D03*
Y978481D03*
X1423602Y981670D03*
Y975292D03*
X1421751Y972103D03*
Y978481D03*
Y984859D03*
X1423602Y988048D03*
X1421751Y991237D03*
X1436554Y876434D03*
X1429153Y882812D03*
X1425452Y889190D03*
X1429153D03*
X1431003Y892379D03*
X1432854Y895568D03*
X1436554Y889190D03*
X1432854Y901946D03*
X1431003Y898757D03*
Y911512D03*
Y905134D03*
X1427302D03*
X1436554Y901946D03*
X1432854Y908323D03*
Y914701D03*
X1431003Y917890D03*
X1427302D03*
X1432854Y921079D03*
X1431003Y924268D03*
X1436554Y914701D03*
X1432854Y927457D03*
X1431003Y930646D03*
X1427302D03*
X1432854Y933835D03*
Y940213D03*
X1431003Y937024D03*
X1427302D03*
X1436554Y927457D03*
Y933835D03*
X1431003Y943402D03*
Y949780D03*
X1427302D03*
X1432854Y946591D03*
Y952969D03*
X1431003Y956158D03*
X1436554Y946591D03*
X1432854Y959347D03*
X1427302Y962536D03*
X1431003D03*
X1432854Y965725D03*
X1431003Y968914D03*
X1436554Y959347D03*
X1432854Y978481D03*
X1431003Y981670D03*
X1432854Y972103D03*
X1431003Y975292D03*
X1427302D03*
X1429153Y984859D03*
X1438405Y981670D03*
X1436554Y972103D03*
Y984859D03*
X1431003Y988048D03*
X1429153Y991237D03*
X1436554D03*
X1438405Y988048D03*
X1447657Y876434D03*
X1445806Y879623D03*
X1443956Y882812D03*
X1447657D03*
X1440255Y889190D03*
X1447657D03*
X1442106Y892379D03*
X1443956Y895568D03*
X1451357Y882812D03*
X1451358Y889190D03*
X1453208Y892379D03*
X1442106Y898757D03*
X1440255Y901946D03*
X1447657D03*
X1443956D03*
X1442106Y905134D03*
X1443956Y908324D03*
X1442106Y911512D03*
X1451358Y901946D03*
X1453208Y898757D03*
Y905134D03*
Y911512D03*
X1440255Y914701D03*
X1443956D03*
X1447657D03*
X1442106Y917890D03*
X1443956Y921079D03*
X1442106Y924268D03*
X1451357Y914701D03*
X1453208Y917890D03*
Y924268D03*
X1440255Y927457D03*
X1443956D03*
X1447657D03*
X1440255Y933835D03*
X1443956D03*
X1442106Y937024D03*
X1443956Y940213D03*
X1453208Y930646D03*
X1451357Y927457D03*
X1447657Y946591D03*
X1442106Y943402D03*
X1440255Y946591D03*
X1442106Y949780D03*
X1443956Y946591D03*
Y952969D03*
X1442106Y956158D03*
X1451357Y946591D03*
X1453208Y943402D03*
Y949780D03*
Y956158D03*
X1440255Y959347D03*
X1443956D03*
X1447657D03*
X1443956Y965725D03*
X1442106Y962536D03*
Y968914D03*
X1451357Y959347D03*
X1453208Y962536D03*
Y968914D03*
X1445806Y981670D03*
X1443956Y978481D03*
Y972103D03*
X1447657D03*
X1442106Y975292D03*
X1440255Y972103D03*
X1443956Y984859D03*
X1453208Y981670D03*
X1451357Y972103D03*
X1453208Y975292D03*
X1451357Y984859D03*
X1445806Y988048D03*
X1443956Y991237D03*
X1453208Y988048D03*
Y994426D03*
X1451357Y991237D03*
X1453208Y1000804D03*
Y1007182D03*
X1456909Y873245D03*
Y879623D03*
X1458759Y876434D03*
X1468011Y879623D03*
X1455058Y882812D03*
X1462460D03*
X1466161D03*
X1458759D03*
Y889190D03*
X1455058Y895568D03*
X1464310Y892379D03*
X1466161Y895568D03*
X1462460Y889190D03*
X1464310Y898757D03*
X1455058Y901946D03*
X1458759D03*
X1466161D03*
X1462460D03*
X1464310Y905134D03*
X1455058Y908324D03*
X1464310Y911512D03*
X1466161Y908323D03*
X1458759Y914701D03*
X1464310Y917890D03*
Y924268D03*
X1455058Y921079D03*
X1466161D03*
X1455058Y914701D03*
X1462460D03*
X1466161D03*
X1455058Y927457D03*
X1458759D03*
X1466161D03*
X1462460D03*
X1455058Y933835D03*
X1464310Y930646D03*
X1462460Y933835D03*
X1466161D03*
X1458759D03*
X1455058Y940213D03*
X1466161D03*
X1462460Y946591D03*
X1466161D03*
X1458759D03*
X1466161Y952969D03*
X1464310Y956158D03*
X1455058Y952969D03*
X1464310Y943402D03*
X1455058Y946591D03*
X1464310Y949780D03*
X1455058Y965725D03*
X1466161D03*
X1455058Y959347D03*
X1462460D03*
X1466161D03*
X1458759D03*
X1464310Y962536D03*
Y968914D03*
X1460609Y981670D03*
X1455058Y978481D03*
X1466161D03*
X1455058Y972103D03*
X1462460D03*
X1466161D03*
X1458759D03*
X1464310Y975292D03*
X1458759Y984859D03*
X1466161D03*
X1468011Y981670D03*
X1458759Y997615D03*
X1466161D03*
X1460609Y988048D03*
Y994426D03*
X1458759Y991237D03*
X1466161D03*
X1460609Y1000804D03*
X1468011Y988048D03*
Y994426D03*
Y1000804D03*
X1458759Y1003993D03*
X1466161D03*
Y1010371D03*
X1458759D03*
X1460609Y1007182D03*
X1468011D03*
X1479113Y873245D03*
X1469861Y876434D03*
X1479113Y879623D03*
X1482814Y886001D03*
X1480964Y882812D03*
X1469861D03*
X1479113Y886001D03*
X1482814Y892379D03*
X1469861Y889190D03*
X1473562D03*
X1475413Y892379D03*
X1477263Y895568D03*
X1482814Y898757D03*
X1469861Y901946D03*
X1475413Y898757D03*
X1473562Y901946D03*
X1482814Y905134D03*
Y911512D03*
X1477263Y908324D03*
X1475413Y911512D03*
Y905134D03*
X1482814Y917890D03*
X1469861Y914701D03*
X1473562D03*
X1475413Y917890D03*
Y924268D03*
X1482814D03*
X1477263Y921079D03*
X1469861Y933835D03*
X1473562D03*
X1482814Y930646D03*
X1475413D03*
X1477263Y933835D03*
X1473562Y927457D03*
X1469861D03*
X1482814Y937024D03*
X1477263Y940213D03*
X1482814Y943402D03*
Y949780D03*
X1475413Y943402D03*
X1469861Y946591D03*
X1473562D03*
X1475413Y949780D03*
X1482814Y956158D03*
X1477263Y952969D03*
X1475413Y956158D03*
X1482814Y962536D03*
X1469861Y959347D03*
X1473562D03*
X1475413Y962536D03*
X1477263Y965725D03*
X1482814Y968914D03*
X1475413D03*
X1482814Y975292D03*
Y981670D03*
X1469861Y972103D03*
X1473562D03*
X1475413Y975292D03*
X1477263Y978481D03*
X1475413Y981670D03*
X1473562Y984859D03*
X1475413Y1000804D03*
X1482814Y988048D03*
Y994426D03*
X1473562Y991237D03*
Y997615D03*
X1475413Y988048D03*
Y994426D03*
X1482814Y1000804D03*
Y1007182D03*
X1473562Y1003993D03*
Y1010371D03*
X1475413Y1007182D03*
X1492066Y876434D03*
X1490216Y886001D03*
X1484665Y882812D03*
X1488365D03*
X1495767D03*
X1493917Y886001D03*
X1488365Y889190D03*
X1495767D03*
X1490216Y892379D03*
X1495767Y895568D03*
X1490216Y898757D03*
X1488365Y901946D03*
X1495767D03*
X1488365Y908324D03*
X1490216Y911512D03*
X1495767Y908324D03*
Y914701D03*
X1490216Y917890D03*
X1488365Y921079D03*
X1495767D03*
X1490216Y930646D03*
X1495767Y933835D03*
X1488365Y927457D03*
X1495767D03*
X1488365Y940213D03*
X1495767D03*
X1490216Y937024D03*
X1488365Y946591D03*
X1490216Y949780D03*
X1495767Y946591D03*
Y952969D03*
X1490216Y956158D03*
X1488365Y965725D03*
X1495767Y959347D03*
Y965725D03*
X1488365Y959347D03*
X1490216Y968914D03*
X1495767Y972103D03*
X1490216Y975292D03*
X1486515Y981670D03*
X1488365Y978481D03*
X1495767D03*
X1497617Y981670D03*
X1484665Y984859D03*
X1488365D03*
X1495767D03*
X1490216Y988048D03*
X1488365Y997615D03*
X1490216Y994426D03*
X1495767Y991237D03*
Y997615D03*
X1488365Y1003993D03*
X1490216Y1007182D03*
X1495767Y1003993D03*
Y1010371D03*
X1501318Y873245D03*
Y879623D03*
X1510570Y876434D03*
X1508720Y879623D03*
X1501318Y886001D03*
X1510570Y882812D03*
X1508720Y886001D03*
X1503169Y889190D03*
Y895568D03*
X1501318Y892379D03*
X1508720D03*
X1499468Y882812D03*
X1505019Y886001D03*
X1501318Y898757D03*
X1508720D03*
X1503169Y901946D03*
X1501318Y905134D03*
X1508720D03*
X1501318Y911512D03*
X1508720D03*
X1503169Y908323D03*
Y914701D03*
X1501318Y917890D03*
X1508720D03*
X1503169Y921079D03*
X1501318Y924268D03*
X1508720D03*
X1503169Y927457D03*
X1501318Y930646D03*
X1503169Y933835D03*
X1508720Y930646D03*
Y937024D03*
X1503169Y940213D03*
X1501318Y937024D03*
Y943402D03*
X1508720D03*
X1503169Y946591D03*
X1501318Y949780D03*
X1508720D03*
X1503169Y952969D03*
X1501318Y956158D03*
X1508720D03*
X1503169Y959347D03*
Y965725D03*
X1501318Y962536D03*
X1508720D03*
X1501318Y968914D03*
X1508720D03*
X1510570Y984859D03*
X1512421Y981670D03*
X1503169Y972103D03*
X1501318Y975292D03*
X1503169Y978481D03*
X1501318Y981670D03*
X1508720Y975292D03*
Y981670D03*
X1499468Y984859D03*
X1503169D03*
Y991237D03*
X1501318Y988048D03*
X1503169Y997615D03*
X1501318Y994426D03*
X1508720Y988048D03*
Y994426D03*
X1501318Y1000804D03*
X1508720D03*
X1501318Y1007182D03*
X1503169Y1010371D03*
X1508720Y1007182D03*
X1503169Y1003993D03*
X1521673Y876434D03*
X1517972D03*
X1519822Y879623D03*
X1527224D03*
X1516121D03*
X1523523Y873245D03*
X1514271Y882812D03*
Y889190D03*
X1521673Y882812D03*
X1519822Y886001D03*
X1525373Y882812D03*
X1527224Y886001D03*
X1521673Y889190D03*
Y895568D03*
X1527224Y892379D03*
X1516121D03*
X1514271Y901946D03*
Y908324D03*
X1521673Y901946D03*
X1527224Y898757D03*
X1516121D03*
X1527224Y911512D03*
Y905134D03*
X1516121Y911512D03*
X1521673Y908323D03*
X1514271Y921079D03*
X1521673Y914701D03*
X1527224Y917890D03*
X1516121D03*
X1521673Y921079D03*
X1527224Y924268D03*
X1514271Y927457D03*
Y940213D03*
X1516121Y930646D03*
X1521673Y927457D03*
Y933835D03*
X1527224Y930646D03*
X1516121Y937024D03*
X1527224D03*
X1521673Y940213D03*
X1514271Y946591D03*
X1516121Y949780D03*
X1521673Y946591D03*
X1527224Y943402D03*
Y949780D03*
X1521673Y952969D03*
X1527224Y956158D03*
X1516121D03*
X1514271Y959347D03*
Y965725D03*
X1521673Y959347D03*
Y965725D03*
X1527224Y962536D03*
Y968914D03*
X1516121D03*
X1514271Y978481D03*
Y984859D03*
X1521673Y972103D03*
X1523523Y981670D03*
X1521673Y978481D03*
X1527224Y975292D03*
Y981670D03*
X1516121Y975292D03*
X1521673Y984859D03*
X1525373D03*
X1514271Y997615D03*
X1521673Y991237D03*
Y997615D03*
X1527224Y988048D03*
Y994426D03*
X1516121Y988048D03*
Y994426D03*
X1527224Y1000804D03*
X1514271Y1003993D03*
X1516121Y1007182D03*
X1521673Y1003993D03*
Y1010371D03*
X1527224Y1007182D03*
X1529074Y876434D03*
X1538326Y879623D03*
X1530925Y886001D03*
X1529074Y889190D03*
Y895568D03*
X1540176Y882812D03*
X1536476D03*
X1534625Y886001D03*
X1540176Y889190D03*
X1542027Y892379D03*
X1534625D03*
X1529074Y901946D03*
Y908324D03*
X1542027Y898757D03*
X1540176Y901946D03*
X1534625Y898757D03*
X1540176Y908324D03*
X1542027Y911512D03*
X1534625Y905134D03*
Y911512D03*
X1529074Y914701D03*
Y921079D03*
X1542027Y917890D03*
X1534625D03*
X1540176Y921079D03*
X1534625Y924268D03*
X1529074Y927457D03*
Y933835D03*
Y940213D03*
X1540176Y927457D03*
X1542027Y930646D03*
X1534625D03*
X1542027Y937024D03*
X1540176Y940213D03*
X1534625Y937024D03*
X1529074Y946591D03*
Y952969D03*
X1540176Y946591D03*
X1542027Y949780D03*
X1534625Y943402D03*
Y949780D03*
Y956158D03*
X1542027D03*
X1529074Y959347D03*
Y965725D03*
X1540176Y959347D03*
Y965725D03*
X1534625Y962536D03*
X1542027Y968914D03*
X1534625D03*
X1538326Y981670D03*
X1542027Y975292D03*
X1540176Y978481D03*
X1534625Y975292D03*
Y981670D03*
X1536476Y984859D03*
X1540176D03*
X1529074Y972103D03*
Y978481D03*
Y984859D03*
Y991237D03*
Y997615D03*
X1542027Y988048D03*
X1540176Y997615D03*
X1542027Y994426D03*
X1534625Y988048D03*
Y994426D03*
Y1000804D03*
X1542027Y1007182D03*
X1534625D03*
X1529074Y1003993D03*
Y1010371D03*
X1540176Y1003993D03*
X1545728Y873245D03*
X1553129Y879623D03*
X1545728Y886001D03*
X1547578Y882812D03*
X1553129Y886001D03*
X1551279Y882812D03*
X1547578Y889190D03*
Y895568D03*
X1553129Y892379D03*
X1547578Y901946D03*
X1553129Y898757D03*
X1547578Y908324D03*
Y914701D03*
Y921079D03*
Y927457D03*
Y933835D03*
Y940213D03*
Y946591D03*
Y952969D03*
Y959347D03*
Y965725D03*
X1543877Y984859D03*
X1547578Y972103D03*
Y978481D03*
Y984859D03*
X1545728Y988048D03*
X1547578Y991237D03*
Y997615D03*
Y1003993D03*
Y1010371D03*
G54D60*
X928740Y321654D03*
G54D36*
X250326Y185236D03*
X368437D03*
G54D61*
X916546Y309460D03*
X911495Y321654D03*
X916546Y333848D03*
X928740Y304409D03*
Y338899D03*
X940934Y309460D03*
X945985Y321654D03*
X940934Y333848D03*
G54D72*
X1766929Y1714960D03*
G54D11*
X19685Y-29134D03*
Y1803261D03*
X2081889Y-29134D03*
Y1803261D03*
G54D27*
X117933Y605376D03*
X763602Y605413D03*
X1094076Y605378D03*
X1739745Y605411D03*
G54D18*
X44000Y154200D03*
X31818Y1424257D03*
X441043Y1672205D03*
Y1718465D03*
X1416437Y1672205D03*
Y1718465D03*
X1800449Y126194D03*
X1804650Y1667292D03*
G54D53*
X791280Y1704890D03*
X1066280D03*
G54D33*
X230905Y1644448D03*
Y1658621D03*
Y1672795D03*
Y1686968D03*
Y1701141D03*
Y1715314D03*
Y1729488D03*
X246653Y1644448D03*
X238779Y1648385D03*
X246653Y1658621D03*
X238779Y1662558D03*
X246653Y1672795D03*
X238779Y1676732D03*
X246653Y1686968D03*
X238779Y1690905D03*
X246653Y1701141D03*
X238779Y1705078D03*
X246653Y1715314D03*
X238779Y1719251D03*
X246653Y1729488D03*
X238779Y1733425D03*
X254527Y1648385D03*
Y1662558D03*
Y1676732D03*
Y1690905D03*
Y1705078D03*
Y1719251D03*
Y1733425D03*
X262401Y1644448D03*
X270275Y1648385D03*
X262401Y1658621D03*
X270275Y1662558D03*
X262401Y1672795D03*
X270275Y1676732D03*
X262401Y1686968D03*
X270275Y1690905D03*
X262401Y1701141D03*
X270275Y1705078D03*
X262401Y1715314D03*
X270275Y1719251D03*
X262401Y1729488D03*
X270275Y1733425D03*
X278149Y1644448D03*
X286023Y1648385D03*
X278149Y1658621D03*
X286023Y1662558D03*
X278149Y1672795D03*
X286023Y1676732D03*
X278149Y1686968D03*
X286023Y1690905D03*
X278149Y1701141D03*
X286023Y1705078D03*
X278149Y1715314D03*
X286023Y1719251D03*
X278149Y1729488D03*
X286023Y1733425D03*
X297835Y1672795D03*
X305709Y1676732D03*
X297835Y1686968D03*
X305709Y1690905D03*
X297835Y1701141D03*
X305709Y1705078D03*
X297835Y1715314D03*
X305709Y1719251D03*
X297835Y1729488D03*
X305709Y1733425D03*
X313583Y1672795D03*
X321457Y1676732D03*
X313583Y1686968D03*
X321457Y1690905D03*
X313583Y1701141D03*
X321457Y1705078D03*
X313583Y1715314D03*
X321457Y1719251D03*
X313583Y1729488D03*
X321457Y1733425D03*
X329331Y1672795D03*
Y1686968D03*
Y1701141D03*
Y1715314D03*
Y1729488D03*
X345079Y1672795D03*
X337205Y1676732D03*
X345079Y1686968D03*
X337205Y1690905D03*
X345079Y1701141D03*
X337205Y1705078D03*
X345079Y1715314D03*
X337205Y1719251D03*
X345079Y1729488D03*
X337205Y1733425D03*
X352953Y1676732D03*
Y1690905D03*
Y1705078D03*
Y1719251D03*
Y1733425D03*
X495078Y1672795D03*
Y1686968D03*
Y1701141D03*
Y1715314D03*
Y1729488D03*
X510826Y1672795D03*
X502952Y1676732D03*
X510826Y1686968D03*
X502952Y1690905D03*
X510826Y1701141D03*
X502952Y1705078D03*
X510826Y1715314D03*
X502952Y1719251D03*
X510826Y1729488D03*
X502952Y1733425D03*
X526574Y1672795D03*
X518700Y1676732D03*
X526574Y1686968D03*
X518700Y1690905D03*
X526574Y1701141D03*
X518700Y1705078D03*
X526574Y1715314D03*
X518700Y1719251D03*
X526574Y1729488D03*
X518700Y1733425D03*
X542322Y1672795D03*
X534448Y1676732D03*
X542322Y1686968D03*
X534448Y1690905D03*
X542322Y1701141D03*
X534448Y1705078D03*
X542322Y1715314D03*
X534448Y1719251D03*
X542322Y1729488D03*
X534448Y1733425D03*
X550196Y1676732D03*
Y1690905D03*
Y1705078D03*
Y1719251D03*
Y1733425D03*
X562008Y1672795D03*
X569882Y1676732D03*
X562008Y1686968D03*
X569882Y1690905D03*
X562008Y1701141D03*
X569882Y1705078D03*
X562008Y1715314D03*
X569882Y1719251D03*
X562008Y1729488D03*
X569882Y1733425D03*
X577756Y1672795D03*
X585630Y1676732D03*
X577756Y1686968D03*
X585630Y1690905D03*
X577756Y1701141D03*
X585630Y1705078D03*
X577756Y1715314D03*
X585630Y1719251D03*
X577756Y1729488D03*
X585630Y1733425D03*
X593504Y1672795D03*
X601378Y1676732D03*
X593504Y1686968D03*
X601378Y1690905D03*
X593504Y1701141D03*
X601378Y1705078D03*
X593504Y1715314D03*
X601378Y1719251D03*
X593504Y1729488D03*
X601378Y1733425D03*
X609252Y1672795D03*
X617126Y1676732D03*
X609252Y1686968D03*
X617126Y1690905D03*
X609252Y1701141D03*
X617126Y1705078D03*
X609252Y1715314D03*
X617126Y1719251D03*
X609252Y1729488D03*
X617126Y1733425D03*
X1238778Y1672795D03*
Y1686968D03*
Y1701141D03*
Y1715314D03*
Y1729488D03*
X1254526Y1672795D03*
X1246652Y1676732D03*
X1254526Y1686968D03*
X1246652Y1690905D03*
X1254526Y1701141D03*
X1246652Y1705078D03*
X1254526Y1715314D03*
X1246652Y1719251D03*
X1254526Y1729488D03*
X1246652Y1733425D03*
X1270274Y1672795D03*
X1262400Y1676732D03*
X1270274Y1686968D03*
X1262400Y1690905D03*
X1270274Y1701141D03*
X1262400Y1705078D03*
X1270274Y1715314D03*
X1262400Y1719251D03*
X1270274Y1729488D03*
X1262400Y1733425D03*
X1286022Y1672795D03*
X1278148Y1676732D03*
X1286022Y1686968D03*
X1278148Y1690905D03*
X1286022Y1701141D03*
X1278148Y1705078D03*
X1286022Y1715314D03*
X1278148Y1719251D03*
X1286022Y1729488D03*
X1278148Y1733425D03*
X1305708Y1672795D03*
Y1686968D03*
X1293896Y1676732D03*
X1305708Y1701141D03*
X1293896Y1690905D03*
X1305708Y1715314D03*
X1293896Y1705078D03*
X1305708Y1729488D03*
X1293896Y1719251D03*
Y1733425D03*
X1313582Y1676732D03*
Y1690905D03*
Y1705078D03*
Y1719251D03*
Y1733425D03*
X1321456Y1672795D03*
X1329330Y1676732D03*
X1321456Y1686968D03*
X1329330Y1690905D03*
X1321456Y1701141D03*
X1329330Y1705078D03*
X1321456Y1715314D03*
X1329330Y1719251D03*
X1321456Y1729488D03*
X1329330Y1733425D03*
X1337204Y1672795D03*
X1345078Y1676732D03*
X1337204Y1686968D03*
X1345078Y1690905D03*
X1337204Y1701141D03*
X1345078Y1705078D03*
X1337204Y1715314D03*
X1345078Y1719251D03*
X1337204Y1729488D03*
X1345078Y1733425D03*
X1352952Y1672795D03*
X1360826Y1676732D03*
X1352952Y1686968D03*
X1360826Y1690905D03*
X1352952Y1701141D03*
X1360826Y1705078D03*
X1352952Y1715314D03*
X1360826Y1719251D03*
X1352952Y1729488D03*
X1360826Y1733425D03*
X1502952Y1672795D03*
X1510826Y1676732D03*
X1502952Y1686968D03*
X1510826Y1690905D03*
X1502952Y1701141D03*
X1510826Y1705078D03*
X1502952Y1715314D03*
X1510826Y1719251D03*
X1502952Y1729488D03*
X1510826Y1733425D03*
X1518700Y1672795D03*
X1526574Y1676732D03*
X1518700Y1686968D03*
X1526574Y1690905D03*
X1518700Y1701141D03*
X1526574Y1705078D03*
X1518700Y1715314D03*
X1526574Y1719251D03*
X1518700Y1729488D03*
X1526574Y1733425D03*
X1534448Y1672795D03*
X1542322Y1676732D03*
X1534448Y1686968D03*
X1542322Y1690905D03*
X1534448Y1701141D03*
X1542322Y1705078D03*
X1534448Y1715314D03*
X1542322Y1719251D03*
X1534448Y1729488D03*
X1542322Y1733425D03*
X1550196Y1672795D03*
X1558070Y1676732D03*
X1550196Y1686968D03*
X1558070Y1690905D03*
X1550196Y1701141D03*
X1558070Y1705078D03*
X1550196Y1715314D03*
X1558070Y1719251D03*
X1550196Y1729488D03*
X1558070Y1733425D03*
X1569882Y1672795D03*
Y1686968D03*
Y1701141D03*
Y1715314D03*
Y1729488D03*
X1585630Y1672795D03*
X1577756Y1676732D03*
X1585630Y1686968D03*
X1577756Y1690905D03*
X1585630Y1701141D03*
X1577756Y1705078D03*
X1585630Y1715314D03*
X1577756Y1719251D03*
X1585630Y1729488D03*
X1577756Y1733425D03*
X1601378Y1672795D03*
X1593504Y1676732D03*
X1601378Y1686968D03*
X1593504Y1690905D03*
X1601378Y1701141D03*
X1593504Y1705078D03*
X1601378Y1715314D03*
X1593504Y1719251D03*
X1601378Y1729488D03*
X1593504Y1733425D03*
X1617126Y1672795D03*
X1609252Y1676732D03*
X1617126Y1686968D03*
X1609252Y1690905D03*
X1617126Y1701141D03*
X1609252Y1705078D03*
X1617126Y1715314D03*
X1609252Y1719251D03*
X1617126Y1729488D03*
X1609252Y1733425D03*
X1625000Y1676732D03*
Y1690905D03*
Y1705078D03*
Y1719251D03*
Y1733425D03*
G54D46*
X441043Y1698268D03*
X1416437D03*
G54D55*
X805690Y204724D03*
X1057659D03*
G54D15*
X17292Y290137D03*
X35689Y301357D03*
X33822Y1462075D03*
Y1459075D03*
Y1456075D03*
X36822D03*
Y1459075D03*
Y1462075D03*
X33822Y1465075D03*
X36822D03*
X37671Y1515214D03*
X34704Y1515235D03*
X47892Y290137D03*
X49400Y384392D03*
X49250Y396332D03*
X47618Y412613D03*
X47619Y421655D03*
X42822Y1462075D03*
Y1459075D03*
Y1456075D03*
Y1465075D03*
X47138Y1513072D03*
X47089Y1510268D03*
X50642Y1557451D03*
X45633Y1592481D03*
X50133D03*
X38426Y1654079D03*
X41427Y1668587D03*
X38426Y1659059D03*
X44583Y1672433D03*
Y1677613D03*
X66289Y301357D03*
X61340Y384362D03*
X61250Y396142D03*
X56542Y589521D03*
X66822Y1462075D03*
Y1459075D03*
Y1456075D03*
X57822Y1462075D03*
Y1459075D03*
Y1456075D03*
X66822Y1465075D03*
X57822D03*
X63990Y1562177D03*
Y1567627D03*
Y1564727D03*
X63915Y1558805D03*
Y1556254D03*
X63990Y1570427D03*
X61225Y1570283D03*
X58564Y1570209D03*
X65767Y1609405D03*
X59767D03*
X53767D03*
X65767Y1615405D03*
X65943Y1621405D03*
X59767D03*
X53767Y1615405D03*
Y1621405D03*
X59427Y1644410D03*
X53648Y1653088D03*
X77790Y520108D03*
X77733Y526764D03*
X77790Y537808D03*
X77733Y544464D03*
X81822Y1462075D03*
Y1456075D03*
Y1465075D03*
X68427Y1644410D03*
X73427D03*
X80000Y1702450D03*
X79500Y1720450D03*
X88722Y1462075D03*
X85722D03*
X88722Y1456075D03*
X85722D03*
X88722Y1465075D03*
X85722D03*
X85621Y1551969D03*
X82974Y1552051D03*
X83340Y1654353D03*
X89466Y1663138D03*
Y1667127D03*
X83340Y1659333D03*
X85395Y1670331D03*
Y1675311D03*
X102096Y1555442D03*
X100439Y1667361D03*
X106573Y1660235D03*
X100915Y1679564D03*
X105069Y1685763D03*
X102243Y1682263D03*
Y1689263D03*
X120016Y300654D03*
Y320631D03*
X114973Y1660235D03*
X113469Y1685763D03*
X133120Y1454751D03*
X137120D03*
X141028Y1454705D03*
X140775Y1638035D03*
X146982Y526997D03*
X145028Y1454705D03*
X152449Y1623572D03*
Y1628528D03*
X151611Y1663933D03*
X159427Y1687843D03*
X151510Y1676811D03*
X163113Y1477590D03*
Y1499490D03*
X164730Y1521561D03*
X161239Y1636147D03*
Y1631191D03*
X162995Y1661377D03*
X160011Y1663933D03*
X163003Y1666462D03*
X159910Y1676811D03*
X162848Y1679357D03*
X162840Y1674272D03*
X187250Y129674D03*
X189410Y388180D03*
X200754Y595174D03*
Y603274D03*
X192951Y1560498D03*
X196081Y1639349D03*
X195504Y1645359D03*
X203754Y595174D03*
Y603274D03*
X207968Y1653130D03*
X203800Y1646832D03*
X272242Y523076D03*
X276085Y1509654D03*
X270720Y1531073D03*
X273220D03*
X275720D03*
X281147Y521803D03*
X280621Y1478082D03*
X291175Y1477590D03*
X283221Y1484772D03*
Y1479992D03*
X278021Y1484772D03*
Y1479992D03*
X283221Y1493392D03*
X280621Y1491482D03*
X278021Y1493392D03*
X291175Y1499490D03*
X283221Y1498172D03*
X278021D03*
X291619Y1536606D03*
X291593Y1529402D03*
Y1531902D03*
X284800Y1526750D03*
X277572Y1536763D03*
X280072D03*
X291619Y1539106D03*
X292792Y1521561D03*
X297323Y1651172D03*
X318660Y24989D03*
X307255Y1641150D03*
X339914Y165170D03*
X384668Y471926D03*
X410701Y99148D03*
X396977Y216685D03*
X399625Y479119D03*
X408683Y1478082D03*
Y1491482D03*
X406083Y1479992D03*
Y1484772D03*
Y1493392D03*
Y1498172D03*
X404147Y1509654D03*
X398782Y1531073D03*
X401282D03*
X403782D03*
X411800Y220200D03*
X413425Y479042D03*
X411283Y1479992D03*
Y1484772D03*
Y1493392D03*
Y1498172D03*
X412862Y1526750D03*
X436090Y120007D03*
X429997Y166400D03*
X441997D03*
X439299Y220046D03*
X427225Y478965D03*
X440159Y966741D03*
Y981741D03*
Y974241D03*
X427286Y1477590D03*
Y1499490D03*
X428746Y1521727D03*
X427730Y1536606D03*
X427704Y1531902D03*
Y1529402D03*
X427730Y1539106D03*
X428500Y1650000D03*
X465997Y166400D03*
X457997D03*
X466041Y1664913D03*
X483467Y209755D03*
X514418Y145171D03*
Y149171D03*
Y153171D03*
X513360Y169190D03*
X511771Y199576D03*
X506261Y865338D03*
X522418Y153171D03*
X516572Y865327D03*
X530418Y145171D03*
Y149171D03*
Y153171D03*
X531280Y210922D03*
X544794Y1478082D03*
Y1491482D03*
X542194Y1479992D03*
Y1484772D03*
Y1493392D03*
X537694Y1504872D03*
X542194Y1498172D03*
X543759Y1536882D03*
X540193Y1531073D03*
X537693D03*
X535193D03*
X541259Y1536882D03*
X555348Y1477590D03*
X547394Y1479992D03*
Y1484772D03*
Y1493392D03*
X555348Y1499490D03*
X547394Y1498172D03*
X556965Y1521561D03*
X556642Y1529389D03*
X554715Y1531564D03*
X550540Y1526910D03*
X556197Y1536687D03*
Y1539187D03*
X561248Y106985D03*
Y100399D03*
X562208Y387227D03*
Y376427D03*
Y401158D03*
X568433Y415846D03*
X581985Y379577D03*
Y390377D03*
Y404308D03*
X588723Y423949D03*
X593975Y164440D03*
X598208Y387227D03*
Y376427D03*
X599164Y432209D03*
X604718Y257562D03*
X617985Y379577D03*
Y398578D03*
Y390377D03*
X610935Y409996D03*
X615075Y443000D03*
X633882Y587488D03*
X646285Y297171D03*
X640317Y391085D03*
X634566Y407848D03*
X639482Y587488D03*
X645446Y587300D03*
X653821Y90326D03*
X653013Y443200D03*
X664170Y445711D03*
X651046Y587300D03*
X672856Y1478082D03*
Y1491482D03*
X675112Y1479602D03*
X675456Y1484772D03*
Y1493392D03*
X670256Y1479992D03*
Y1484772D03*
Y1493392D03*
X665756Y1504872D03*
X675456Y1498172D03*
X670256D03*
X680710Y1520284D03*
X683674Y1522287D03*
X695796Y418358D03*
X708395Y430957D03*
X702095Y421508D03*
X698946Y437256D03*
X702095Y449854D03*
X708395Y474971D03*
X698946Y468672D03*
X695796Y487570D03*
X706172Y1552082D03*
X698003Y1684692D03*
X711544Y421508D03*
X720993Y443555D03*
Y446705D03*
X717843D03*
Y440405D03*
X720993Y449854D03*
Y462373D03*
Y459223D03*
Y456074D03*
X717843Y459223D03*
Y465523D03*
X711544Y484420D03*
X722141Y1405912D03*
X721916Y1414339D03*
Y1416939D03*
X722141Y1408412D03*
X721916Y1428989D03*
Y1431589D03*
X733512Y427807D03*
X727292Y421508D03*
X736661Y443555D03*
X733512Y446705D03*
Y443555D03*
X727292Y446705D03*
Y443555D03*
X724143D03*
Y462373D03*
X727292D03*
X733512Y459223D03*
X727292D03*
X733512Y462373D03*
X736661D03*
X727292Y474971D03*
X736661Y484420D03*
X724143D03*
X752409Y421508D03*
X739811Y443555D03*
Y446705D03*
X742961Y440405D03*
X739811Y449854D03*
Y456074D03*
Y459223D03*
Y462373D03*
X742961Y465523D03*
X752409Y484420D03*
X746082Y1506931D03*
X751030Y1668583D03*
X765008Y418358D03*
X758709Y437256D03*
X755559Y456074D03*
X758709Y468672D03*
X765008Y487570D03*
X758179Y1482049D03*
X758163Y1526223D03*
X758179Y1534963D03*
X779014Y1343262D03*
Y1340062D03*
X782014D03*
Y1337062D03*
Y1343262D03*
X780000Y1353500D03*
X779014Y1346462D03*
Y1349862D03*
X782014Y1346462D03*
Y1349862D03*
X780000Y1357500D03*
Y1363500D03*
Y1360500D03*
X780111Y1405366D03*
X782758Y1405249D03*
X795421Y1331257D03*
X785014Y1350862D03*
X804099Y1333835D03*
X801171Y1343278D03*
X810986Y1361684D03*
X819115Y115223D03*
X824499Y145198D03*
X820405Y311830D03*
X831115Y115223D03*
X829115Y150273D03*
X838670Y1518558D03*
X841310Y1518608D03*
X838630Y1521538D03*
X841270Y1521588D03*
X854578Y99651D03*
X856397Y339751D03*
X847007Y1521458D03*
X844367Y1521408D03*
Y1518784D03*
X847007Y1518834D03*
X855853Y1521308D03*
X853213Y1521258D03*
X850146Y1521261D03*
Y1518637D03*
X853213Y1518634D03*
X855853Y1518684D03*
X860152Y328399D03*
X865132D03*
X861377Y339751D03*
X872986Y753451D03*
X858581Y1518568D03*
X858567Y1521416D03*
X876133Y73580D03*
Y95580D03*
Y117580D03*
X919272Y989932D03*
X921289Y1663187D03*
X942779Y277731D03*
X936693Y1462328D03*
X939507Y1462497D03*
X945195Y1459453D03*
X942056Y1459650D03*
X939416Y1459600D03*
Y1456976D03*
X942056Y1457026D03*
X945195Y1456829D03*
X951099Y632206D03*
X956693Y1459805D03*
X953630Y1456760D03*
X958383Y1462447D03*
X950902Y1459500D03*
X948262Y1459450D03*
X953616Y1459608D03*
X948262Y1456826D03*
X950902Y1456876D03*
X955350Y1532760D03*
X961350D03*
X958350D03*
X953520Y1567570D03*
X950520D03*
X959520D03*
X956520D03*
X953520Y1582570D03*
X950520D03*
Y1579570D03*
X953520D03*
Y1576570D03*
X950520D03*
X953520Y1573570D03*
X950520D03*
Y1570570D03*
X953520D03*
X959520Y1582570D03*
X956520D03*
Y1579570D03*
X959520D03*
Y1576570D03*
X956520D03*
X959520Y1573570D03*
X956520D03*
Y1570570D03*
X959520D03*
X953520Y1588570D03*
X950520D03*
Y1585570D03*
X953520D03*
X959520Y1588570D03*
X956520D03*
Y1585570D03*
X959520D03*
X977150Y1052684D03*
X966000Y1300000D03*
X968500D03*
X971000D03*
X967350Y1532760D03*
X964350D03*
X991280D03*
X988280D03*
X988160Y1567710D03*
X991160D03*
X985160D03*
X988160Y1582710D03*
X991160D03*
X985160D03*
Y1579710D03*
X991160D03*
X988160D03*
X991160Y1570710D03*
X988160D03*
Y1573710D03*
X991160D03*
X988160Y1576710D03*
X991160D03*
X985160Y1570710D03*
Y1573710D03*
Y1576710D03*
X988160Y1588710D03*
X991160D03*
X985160D03*
Y1585710D03*
X991160D03*
X988160D03*
X994280Y1532760D03*
X997280D03*
X1000280D03*
X1014206Y510304D03*
X1013306Y526146D03*
X1019440Y1532930D03*
X1016750Y1567710D03*
X1019750D03*
X1016750Y1576710D03*
Y1573710D03*
Y1570710D03*
X1019750Y1576710D03*
Y1573710D03*
Y1570710D03*
Y1579710D03*
X1016750D03*
Y1582710D03*
X1019750D03*
Y1585710D03*
X1016750D03*
Y1588710D03*
X1019750D03*
X1025440Y1532930D03*
X1022440D03*
X1031440D03*
X1028440D03*
X1022750Y1567710D03*
Y1576710D03*
Y1573710D03*
Y1570710D03*
Y1579710D03*
Y1582710D03*
Y1585710D03*
Y1588710D03*
X1045254Y521074D03*
X1037212Y510940D03*
X1051110Y1532850D03*
X1048219Y1567883D03*
X1051219D03*
X1048219Y1576883D03*
Y1573883D03*
Y1570883D03*
X1051219Y1576883D03*
Y1573883D03*
Y1570883D03*
Y1579883D03*
X1048219D03*
Y1582883D03*
X1051219D03*
Y1585883D03*
X1048219D03*
Y1588883D03*
X1051219D03*
X1055934Y385488D03*
X1057110Y1532850D03*
X1054110D03*
X1063110D03*
X1060110D03*
X1054219Y1567883D03*
Y1576883D03*
Y1573883D03*
Y1570883D03*
Y1579883D03*
Y1582883D03*
Y1585883D03*
Y1588883D03*
X1068143Y383688D03*
X1073204Y383417D03*
X1083819Y353094D03*
X1090300Y1532660D03*
X1087300D03*
X1096300D03*
X1093300D03*
X1119067Y1551457D03*
X1133765Y1572102D03*
X1170986Y1510590D03*
Y1532490D03*
X1183354Y77685D03*
X1176972Y86788D03*
X1200824Y1593498D03*
X1192612Y1680410D03*
X1207954Y1680419D03*
X1209879Y1700359D03*
X1230094Y314216D03*
X1226094Y305216D03*
X1216875Y1705826D03*
X1216738Y1720861D03*
X1277732Y236594D03*
Y246594D03*
Y241594D03*
Y251594D03*
X1288494Y1511082D03*
X1285894Y1512992D03*
Y1517772D03*
X1288494Y1524482D03*
X1285894Y1531172D03*
Y1526392D03*
X1283958Y1542654D03*
X1278593Y1564073D03*
X1281093D03*
X1283593D03*
X1287945Y1569763D03*
X1285445D03*
X1302365Y1418702D03*
X1292522Y1421596D03*
X1303943Y1430729D03*
X1299048Y1510590D03*
X1291094Y1512992D03*
Y1517772D03*
X1299048Y1532490D03*
X1291094Y1531172D03*
Y1526392D03*
X1299466Y1562402D03*
Y1564902D03*
X1292673Y1559750D03*
X1299492Y1572106D03*
Y1569606D03*
X1307766Y563013D03*
X1308700Y590300D03*
X1317266Y592522D03*
X1308700Y587800D03*
X1313109Y1195398D03*
Y1200898D03*
X1325366Y592522D03*
X1339488Y1202295D03*
X1340483Y1209006D03*
X1336861Y1222119D03*
X1350809Y1202323D03*
X1368137Y1222298D03*
Y1227798D03*
X1383800Y1685398D03*
X1406655Y1564073D03*
X1409155D03*
X1399940Y1637127D03*
X1414619Y244450D03*
X1416301Y966740D03*
Y981740D03*
Y974240D03*
X1416556Y1511082D03*
X1419156Y1512992D03*
Y1517772D03*
X1413956Y1512992D03*
Y1517772D03*
X1416556Y1524482D03*
X1419156Y1531172D03*
Y1526392D03*
X1413956Y1531172D03*
Y1526392D03*
X1412020Y1542654D03*
X1420735Y1559750D03*
X1411655Y1564073D03*
X1435160Y1510590D03*
Y1532490D03*
X1435578Y1564902D03*
Y1562402D03*
X1436940Y1554277D03*
X1435604Y1572106D03*
Y1569606D03*
X1445985Y116953D03*
X1441390Y163944D03*
X1442993Y176204D03*
X1462405Y61563D03*
X1461242Y128242D03*
X1463017Y136368D03*
X1465832Y535330D03*
X1542767Y1564073D03*
X1552668Y1511082D03*
X1555268Y1512992D03*
Y1517772D03*
X1550068Y1512992D03*
Y1517772D03*
X1552668Y1524482D03*
X1555268Y1531172D03*
Y1526392D03*
X1550068Y1531172D03*
Y1526392D03*
X1548132Y1542654D03*
X1556847Y1559750D03*
X1545267Y1564073D03*
X1547767D03*
X1552118Y1569763D03*
X1549618D03*
X1563222Y1510590D03*
Y1532490D03*
X1564581Y1562316D03*
X1562613Y1564816D03*
X1564128Y1572225D03*
X1562621Y1569761D03*
X1602270Y229530D03*
X1629597Y221842D03*
X1619909Y306746D03*
X1643283Y1425541D03*
X1648337Y1451313D03*
X1654419Y233062D03*
X1655383Y1425541D03*
X1656997Y1708609D03*
Y1723759D03*
X1665100Y156762D03*
Y166762D03*
X1673223Y220857D03*
X1673630Y1533092D03*
Y1537872D03*
X1684925Y118762D03*
Y149762D03*
Y161762D03*
Y153762D03*
X1684942Y234000D03*
X1683587Y1433425D03*
X1680430Y1511198D03*
X1682760Y1512169D03*
X1683330Y1517772D03*
X1678130Y1512992D03*
Y1517772D03*
X1680730Y1524482D03*
X1683330Y1531172D03*
Y1526392D03*
X1678130Y1531172D03*
Y1526392D03*
X1688584Y1553284D03*
X1691548Y1555287D03*
X1686857Y1683918D03*
X1684733Y1698952D03*
X1695102Y1698947D03*
X1691357Y1688418D03*
X1691997Y1708609D03*
X1733083Y654034D03*
X1737606Y1539807D03*
X1736579Y1587480D03*
X1723929Y1654456D03*
X1723963Y1658965D03*
Y1663465D03*
Y1667965D03*
X1731117Y1705115D03*
Y1720265D03*
X1741329Y1482405D03*
Y1485405D03*
Y1491405D03*
Y1488405D03*
X1740058Y1537419D03*
X1744866Y1539589D03*
X1742165Y1539620D03*
X1740979Y1577905D03*
X1743681Y1626750D03*
X1750681D03*
X1747181D03*
X1743481Y1616550D03*
X1750481D03*
X1746981D03*
X1747963Y1641965D03*
X1764029Y1485405D03*
Y1482405D03*
Y1491405D03*
Y1488405D03*
X1756329Y1485405D03*
Y1482405D03*
Y1491405D03*
Y1488405D03*
X1769054Y1585705D03*
X1753079Y1596650D03*
Y1606550D03*
Y1603050D03*
Y1600150D03*
X1761839Y1634223D03*
X1757763Y1643365D03*
X1761494Y1661947D03*
X1779029Y1482405D03*
Y1485405D03*
Y1491405D03*
Y1488405D03*
X1772904Y1585005D03*
X1773863Y1661465D03*
X1774940Y1669037D03*
X1773738Y1672965D03*
X1773963Y1680965D03*
X1793070Y25001D03*
X1788029Y1485405D03*
Y1482405D03*
Y1491405D03*
Y1488405D03*
X1789379Y1588478D03*
X1805525Y146716D03*
X1812029Y1485405D03*
Y1482405D03*
X1803029D03*
Y1485405D03*
X1812029Y1491405D03*
Y1488405D03*
X1803029Y1491405D03*
Y1488405D03*
X1801789Y1536742D03*
X1807408Y1539223D03*
X1810408D03*
X1812078Y1596725D03*
X1812003Y1607375D03*
Y1603875D03*
X1812078Y1600225D03*
X1809179Y1616550D03*
X1809254Y1613775D03*
X1812570Y159275D03*
X1827029Y1488405D03*
Y1491405D03*
Y1485405D03*
Y1482405D03*
X1815344Y1539373D03*
X1818344D03*
X1823112Y1538659D03*
X1812679Y1616550D03*
X1816179D03*
X1812754Y1613775D03*
X1816254D03*
X1837641Y159275D03*
X1840700Y326201D03*
Y348201D03*
Y370201D03*
Y392201D03*
Y414201D03*
Y436201D03*
Y458201D03*
Y480201D03*
Y502201D03*
Y524201D03*
Y546201D03*
Y568201D03*
Y590201D03*
Y656201D03*
Y678201D03*
Y700201D03*
Y722201D03*
Y744201D03*
Y766201D03*
Y788201D03*
Y810201D03*
Y832201D03*
Y854201D03*
Y876201D03*
Y898201D03*
Y920201D03*
Y942201D03*
Y964201D03*
Y986201D03*
Y1008201D03*
Y1030201D03*
Y1052201D03*
Y1074201D03*
Y1096201D03*
Y1118201D03*
Y1140201D03*
Y1162201D03*
Y1184201D03*
Y1206201D03*
Y1228201D03*
Y1250201D03*
Y1272201D03*
Y1294201D03*
Y1316201D03*
Y1338201D03*
Y1404201D03*
Y1448201D03*
Y1470201D03*
Y1492201D03*
Y1514201D03*
Y1536201D03*
Y1558201D03*
Y1580201D03*
X1828889Y1622578D03*
Y1644578D03*
Y1666578D03*
Y1688578D03*
X1854479Y66461D03*
Y110461D03*
Y132461D03*
Y154461D03*
X1847866Y159124D03*
X1854479Y176461D03*
Y198461D03*
Y220461D03*
Y242461D03*
Y264461D03*
Y286461D03*
G54D59*
X922441Y154311D03*
Y243799D03*
G54D12*
X21569Y49379D03*
X21345Y387760D03*
X21309Y395712D03*
X36500Y323500D03*
X33686Y383944D03*
X27309Y383926D03*
X29962Y401000D03*
X36524Y398013D03*
X26771Y398811D03*
X30680Y438142D03*
X35852Y664480D03*
Y686410D03*
Y683910D03*
X43569Y49379D03*
X45423Y197224D03*
Y212224D03*
Y202224D03*
Y207224D03*
X40000Y323500D03*
X55190Y360862D03*
X42809D03*
X46834D03*
X39410Y384582D03*
X39226Y395346D03*
X53825Y421746D03*
X49848Y524210D03*
X49889Y531149D03*
X50880Y1421963D03*
X52405Y1514835D03*
X49405D03*
X52405Y1511986D03*
X49405D03*
X52330Y1509137D03*
X49330D03*
X52796Y1526469D03*
X52905Y1523335D03*
X47760Y1529506D03*
X65347Y66847D03*
X60367D03*
X65347Y71839D03*
X60367D03*
X58457Y69340D03*
X67575Y287500D03*
X56620Y303500D03*
X64150Y434972D03*
X53800Y435451D03*
X54762Y444993D03*
X56800Y524220D03*
X56719Y531120D03*
X64923Y795316D03*
Y832127D03*
Y868938D03*
Y905750D03*
Y942561D03*
Y1089805D03*
Y1126616D03*
Y1163427D03*
Y1200238D03*
Y1237049D03*
X58349Y1412731D03*
X55755Y1511885D03*
X55905Y1514835D03*
X57281Y1523287D03*
X66081D03*
X59881D03*
X63481D03*
X55789Y1509224D03*
X57281Y1526394D03*
X66081D03*
X65281Y1529501D03*
X59881Y1526394D03*
X63481D03*
X62681Y1529501D03*
X64235Y1533150D03*
X61755D03*
X59275D03*
X67196Y1552869D03*
X64235Y1538750D03*
X61755D03*
X59275D03*
X63802Y1579997D03*
X58602D03*
X61302D03*
X75928Y3001D03*
X81159Y17045D03*
X72087Y25977D03*
X74087Y23981D03*
X79043D03*
X81043Y25977D03*
X79192Y19541D03*
X81159Y22037D03*
X73025Y37106D03*
X80111D03*
X73025Y48720D03*
X80111D03*
X69453Y75343D03*
X82367Y71839D03*
X80457Y69340D03*
X82367Y66847D03*
X76347Y72850D03*
X71367D03*
X76347Y77842D03*
X71367D03*
X71779Y157194D03*
Y161194D03*
X71772Y421746D03*
X68365Y443677D03*
X80915Y756766D03*
X73873D03*
Y760266D03*
X69323Y776911D03*
X80915Y763766D03*
X80015Y786950D03*
X69323Y783604D03*
X81065Y791970D03*
X80015Y796989D03*
X69323Y807029D03*
Y813722D03*
Y820415D03*
X80015Y823761D03*
Y833800D03*
X81065Y828781D03*
X69323Y843840D03*
Y850533D03*
X80015Y860572D03*
X81065Y865592D03*
X69323Y857226D03*
X80015Y870611D03*
X69323Y880651D03*
Y887344D03*
Y894037D03*
X80015Y907423D03*
Y897383D03*
X81065Y902403D03*
X69323Y924155D03*
Y917462D03*
X81065Y939214D03*
X80015Y934194D03*
X69323Y930848D03*
X80015Y944234D03*
X69323Y954273D03*
Y960966D03*
Y967659D03*
Y974352D03*
Y981045D03*
Y987737D03*
Y994430D03*
Y1004470D03*
Y1034588D03*
Y1041281D03*
Y1047974D03*
Y1054667D03*
Y1071399D03*
Y1061360D03*
X80015Y1081438D03*
X81065Y1086458D03*
X69323Y1078092D03*
X80015Y1091478D03*
X69323Y1101517D03*
X80015Y1118249D03*
X69323Y1114903D03*
Y1108210D03*
X80015Y1128289D03*
X81065Y1123269D03*
X69323Y1145021D03*
Y1138328D03*
X80015Y1165100D03*
X81065Y1160080D03*
X80015Y1155060D03*
X69323Y1151714D03*
Y1175139D03*
Y1181832D03*
X80015Y1191871D03*
X69323Y1188525D03*
X81065Y1196891D03*
X80015Y1201911D03*
X69323Y1211950D03*
Y1218643D03*
X80015Y1238722D03*
Y1228682D03*
X81065Y1233702D03*
X69323Y1225336D03*
Y1248761D03*
Y1255454D03*
X76378Y1406622D03*
X74325Y1523303D03*
X68870Y1523147D03*
X71359Y1523186D03*
X81868Y1511285D03*
X81405Y1516835D03*
X81905Y1513835D03*
X81405Y1519835D03*
Y1522835D03*
X78808Y1522839D03*
X81905Y1508698D03*
X74440Y1526385D03*
X74462Y1529665D03*
X82696Y1529095D03*
X76806Y1593265D03*
X80400Y1602225D03*
X86139Y17045D03*
X95333D03*
X88148Y19541D03*
X95216Y25977D03*
X86260D03*
X93216Y23981D03*
X88260D03*
X86139Y22037D03*
X95333D03*
X93365Y19541D03*
X94284Y37106D03*
X87198D03*
Y48720D03*
X94284D03*
X87347Y71839D03*
Y66847D03*
X91457Y75340D03*
X93367Y72847D03*
Y77839D03*
X89150Y154494D03*
X93717Y159053D03*
X87654Y376026D03*
X87520Y386502D03*
X85465Y773564D03*
Y780257D03*
Y803682D03*
X94624Y795316D03*
X85465Y810375D03*
Y817068D03*
X94624Y832127D03*
X85465Y840493D03*
Y847186D03*
Y853879D03*
Y877304D03*
X94624Y868938D03*
X85465Y890690D03*
Y883997D03*
X94624Y905750D03*
X85465Y920808D03*
Y914115D03*
Y927501D03*
Y950926D03*
X94624Y942561D03*
X85465Y957619D03*
Y971005D03*
Y964312D03*
Y984391D03*
Y977698D03*
Y991084D03*
Y997777D03*
Y1004470D03*
Y1044627D03*
Y1031241D03*
Y1037934D03*
Y1051320D03*
Y1058013D03*
Y1068052D03*
Y1074745D03*
X94624Y1089805D03*
X85465Y1098171D03*
Y1104863D03*
Y1111556D03*
X94624Y1126616D03*
X85465Y1134982D03*
Y1148367D03*
Y1141675D03*
X94624Y1163427D03*
X85465Y1178486D03*
Y1171793D03*
Y1185178D03*
Y1208604D03*
X94624Y1200238D03*
X85465Y1215297D03*
Y1221989D03*
X94624Y1237049D03*
X85465Y1252108D03*
Y1245415D03*
X90501Y1338952D03*
X92791Y1341302D03*
X96191Y1337721D03*
X92941Y1346172D03*
X91000Y1350300D03*
X88500D03*
X84000Y1408000D03*
Y1412500D03*
Y1417000D03*
X97530Y1410247D03*
X93000Y1430500D03*
X84000Y1421500D03*
Y1426000D03*
X93000Y1435500D03*
Y1440000D03*
X84500D03*
X95624Y1523287D03*
X85368Y1511285D03*
X85405Y1513835D03*
X88868Y1511285D03*
X88905Y1513835D03*
X93024Y1523287D03*
X85405Y1508698D03*
X88905D03*
X97498Y1533150D03*
X95624Y1526394D03*
X95018Y1533150D03*
X88696Y1526769D03*
X93024Y1526394D03*
X88696Y1523769D03*
X97498Y1538750D03*
X95018D03*
X93029Y1705225D03*
X97683Y1722477D03*
X97928Y3001D03*
X100313Y17045D03*
X109506D03*
X109389Y25977D03*
X100433D03*
X107389Y23981D03*
X102433D03*
X100313Y22037D03*
X102321Y19541D03*
X109506Y22037D03*
X107538Y19541D03*
X108458Y37106D03*
X101371D03*
Y48720D03*
X108458D03*
X98347Y72847D03*
X104367Y71839D03*
X109347D03*
X102457Y69340D03*
X104367Y66847D03*
X109347D03*
X98347Y77839D03*
X104829Y151191D03*
X107931Y158767D03*
X99754Y155807D03*
X110616Y756766D03*
X103574D03*
Y760266D03*
X99024Y776911D03*
X110616Y763766D03*
X103574Y767266D03*
X99024Y783604D03*
X109716Y786950D03*
X110766Y791970D03*
X99024Y807029D03*
X109716Y796989D03*
X99024Y813722D03*
Y820415D03*
X109716Y823761D03*
Y833800D03*
X110766Y828781D03*
X99024Y843840D03*
Y850533D03*
Y857226D03*
X109716Y860572D03*
X110766Y865592D03*
X99024Y880651D03*
X109716Y870611D03*
X99024Y887344D03*
Y894037D03*
X109716Y897383D03*
X110766Y902403D03*
X109716Y907423D03*
X99024Y924155D03*
Y917462D03*
Y930848D03*
X110766Y939214D03*
X109716Y934194D03*
X99024Y954273D03*
X109716Y944234D03*
X99024Y960966D03*
Y967659D03*
Y974352D03*
Y981045D03*
Y987737D03*
Y994430D03*
Y1004470D03*
Y1034588D03*
Y1041281D03*
Y1047974D03*
Y1054667D03*
Y1071399D03*
Y1061360D03*
Y1078092D03*
X109716Y1081438D03*
X110766Y1086458D03*
X99024Y1101517D03*
X109716Y1091478D03*
X99024Y1114903D03*
Y1108210D03*
X109716Y1118249D03*
Y1128289D03*
X110766Y1123269D03*
X99024Y1145021D03*
Y1138328D03*
Y1151714D03*
X109716Y1165100D03*
X110766Y1160080D03*
X109716Y1155060D03*
X99024Y1175139D03*
Y1181832D03*
Y1188525D03*
X109716Y1191871D03*
X110766Y1196891D03*
X109716Y1201911D03*
X99024Y1211950D03*
Y1218643D03*
Y1225336D03*
X109716Y1228682D03*
Y1238722D03*
X110766Y1233702D03*
X99024Y1248761D03*
Y1255454D03*
X99211Y1337771D03*
X112677Y1357409D03*
X110077D03*
X107477D03*
X104877D03*
X111581Y1372872D03*
X106721Y1367272D03*
Y1372872D03*
X109151D03*
X112677Y1363473D03*
X110077D03*
X112677Y1360516D03*
X110077D03*
X107477D03*
X104877D03*
X100347Y1361417D03*
X109151Y1367272D03*
X111581D03*
X111630Y1385287D03*
X101995Y1388247D03*
X98492Y1523287D03*
X100922D03*
X109635Y1523158D03*
X106713Y1523098D03*
X103513D03*
X99978Y1533150D03*
X98492Y1526394D03*
X98424Y1529501D03*
X100922Y1526394D03*
X101024Y1529501D03*
X108861Y1528840D03*
Y1526410D03*
X101396Y1552769D03*
X99978Y1538750D03*
X106448Y1696436D03*
X119928Y3001D03*
X114486Y17045D03*
X123683D03*
X123563Y25977D03*
X114607D03*
X116607Y23981D03*
X121563D03*
X114486Y22037D03*
X116494Y19541D03*
X121712D03*
X123683Y22037D03*
X122631Y37106D03*
X115544D03*
Y48720D03*
X122631D03*
X113457Y75340D03*
X115367Y72847D03*
X120347D03*
X126367Y71842D03*
X124457Y69343D03*
X126367Y66850D03*
X115367Y77839D03*
X120347D03*
X115166Y773564D03*
Y780257D03*
X124324Y795316D03*
X115166Y803682D03*
Y810375D03*
Y817068D03*
X124324Y832127D03*
X115166Y840493D03*
Y847186D03*
Y853879D03*
Y877304D03*
X124324Y868938D03*
X115166Y890690D03*
Y883997D03*
X124324Y905750D03*
X115166Y920808D03*
Y914115D03*
Y927501D03*
Y950926D03*
X124324Y942561D03*
X115166Y957619D03*
Y971005D03*
Y964312D03*
Y984391D03*
Y977698D03*
Y991084D03*
Y997777D03*
Y1004470D03*
Y1031241D03*
Y1037934D03*
Y1044627D03*
Y1051320D03*
Y1058013D03*
Y1068052D03*
Y1074745D03*
X124324Y1089805D03*
X115166Y1098171D03*
Y1104863D03*
Y1111556D03*
X124324Y1126616D03*
X115166Y1134982D03*
Y1148367D03*
Y1141675D03*
X124324Y1163427D03*
X115166Y1178486D03*
Y1171793D03*
Y1185178D03*
Y1208604D03*
X124324Y1200238D03*
X115166Y1215297D03*
Y1221989D03*
X124324Y1237049D03*
X115166Y1252108D03*
Y1245415D03*
X124071Y1337843D03*
X126671D03*
X115277Y1357409D03*
X126491Y1354871D03*
X125241Y1357371D03*
X126491Y1352271D03*
X123891Y1354871D03*
Y1352271D03*
X120221Y1357425D03*
X126491Y1349671D03*
X123891D03*
X117777Y1357409D03*
X121207Y1360686D03*
X114405Y1509335D03*
Y1516335D03*
Y1512835D03*
Y1519835D03*
Y1522835D03*
X116905D03*
Y1519835D03*
Y1512835D03*
Y1516335D03*
Y1509335D03*
Y1526335D03*
X120052Y1712450D03*
X141928Y3001D03*
X128663Y17045D03*
X130668Y19541D03*
X128663Y22037D03*
X129718Y37106D03*
Y48720D03*
X135457Y75340D03*
X137367Y72847D03*
X142347D03*
X131347Y71842D03*
Y66850D03*
X137367Y77839D03*
X142347D03*
X128367Y202241D03*
Y207241D03*
Y197241D03*
Y212241D03*
X139440Y439000D03*
X138090Y441900D03*
X140800Y441920D03*
X134812Y530955D03*
X131861Y664958D03*
X139869Y686582D03*
X140316Y756766D03*
X133124D03*
Y760266D03*
X128724Y776911D03*
X140316Y763766D03*
X133124Y767266D03*
X139416Y786950D03*
X128724Y783604D03*
X140466Y791970D03*
X128724Y807029D03*
X139416Y796989D03*
X128724Y813722D03*
Y820415D03*
X139416Y823761D03*
Y833800D03*
X140466Y828781D03*
X128724Y843840D03*
Y850533D03*
Y857226D03*
X139416Y860572D03*
X140466Y865592D03*
X128724Y880651D03*
X139416Y870611D03*
X128724Y887344D03*
Y894037D03*
X139416Y897383D03*
X140466Y902403D03*
X139416Y907423D03*
X128724Y924155D03*
Y917462D03*
X140466Y939214D03*
X139416Y934194D03*
X128724Y930848D03*
Y954273D03*
X139416Y944234D03*
X128724Y960966D03*
Y967659D03*
Y974352D03*
Y981045D03*
Y987737D03*
Y994430D03*
Y1004470D03*
Y1034588D03*
Y1041281D03*
Y1047974D03*
Y1054667D03*
Y1071399D03*
Y1061360D03*
X139416Y1081438D03*
X140466Y1086458D03*
X128724Y1078092D03*
Y1101517D03*
X139416Y1091478D03*
X128724Y1114903D03*
X139416Y1118249D03*
X128724Y1108210D03*
X139416Y1128289D03*
X140466Y1123269D03*
X128724Y1145021D03*
Y1138328D03*
X139416Y1165100D03*
X140466Y1160080D03*
X139416Y1155060D03*
X128724Y1151714D03*
Y1175139D03*
Y1181832D03*
X139416Y1191871D03*
X128724Y1188525D03*
X140466Y1196891D03*
X139416Y1201911D03*
X128724Y1211950D03*
Y1218643D03*
Y1225336D03*
X139416Y1228682D03*
X140466Y1233702D03*
X139416Y1238722D03*
X128724Y1248761D03*
Y1255454D03*
X137551Y1337771D03*
X131791Y1337811D03*
X140077Y1357409D03*
X137477D03*
X139321Y1367272D03*
Y1372872D03*
X141751D03*
X140077Y1360516D03*
X137477D03*
X132947Y1361417D03*
X141751Y1367272D03*
X130492Y1384789D03*
X132150Y1386740D03*
X132643Y1711846D03*
X150473Y25977D03*
X157429Y23981D03*
X152473D03*
X151410Y37106D03*
Y48720D03*
X153347Y71842D03*
X148367D03*
X153347Y66850D03*
X148367D03*
X146453Y69343D03*
X150318Y233536D03*
X142660Y438930D03*
X143720Y441960D03*
X145960Y438800D03*
X146930Y441870D03*
X149210Y438640D03*
X149830Y441920D03*
X149672Y665500D03*
X152705Y683218D03*
X144866Y773564D03*
Y780257D03*
X154025Y795316D03*
X144866Y803682D03*
Y810375D03*
Y817068D03*
X154025Y832127D03*
X144866Y840493D03*
Y847186D03*
Y853879D03*
Y877304D03*
X154025Y868938D03*
X144866Y890690D03*
Y883997D03*
X154025Y905750D03*
X144866Y920808D03*
Y914115D03*
Y927501D03*
X154025Y942561D03*
X144866Y950926D03*
Y957619D03*
Y971005D03*
Y964312D03*
Y984391D03*
Y977698D03*
Y991084D03*
Y997777D03*
Y1004470D03*
Y1031241D03*
Y1037934D03*
Y1044627D03*
Y1051320D03*
Y1058013D03*
Y1068052D03*
Y1074745D03*
X154025Y1089805D03*
X144866Y1098171D03*
Y1104863D03*
Y1111556D03*
X154025Y1126616D03*
X144866Y1134982D03*
Y1148367D03*
Y1141675D03*
X154025Y1163427D03*
X144866Y1178486D03*
Y1171793D03*
Y1185178D03*
Y1208604D03*
X154025Y1200238D03*
X144866Y1215297D03*
Y1221989D03*
X154025Y1237049D03*
X144866Y1252108D03*
Y1245415D03*
X156491Y1354871D03*
Y1352271D03*
X152821Y1357425D03*
X156491Y1349671D03*
X145277Y1357409D03*
X147877D03*
X142677D03*
X150377D03*
X144181Y1367272D03*
X153767Y1360456D03*
Y1363413D03*
X144181Y1372872D03*
X142677Y1360516D03*
X145277Y1363473D03*
X142677D03*
X145277Y1360516D03*
X144230Y1385287D03*
X150900Y1433500D03*
Y1429500D03*
X143478Y1440000D03*
X151082Y1436653D03*
X146978Y1440000D03*
X147277Y1712791D03*
X152815Y1705500D03*
X155740Y1729726D03*
X163928Y3001D03*
X164525Y17045D03*
X159545D03*
X159429Y25977D03*
X164646D03*
X171602Y23981D03*
X166646D03*
X157578Y19541D03*
X166534D03*
X171751D03*
X164525Y22037D03*
X159545D03*
X158497Y37106D03*
X165584D03*
X158497Y48720D03*
X165584D03*
X158661Y75340D03*
X160571Y72847D03*
X165551D03*
X171571Y71839D03*
X169661Y69340D03*
X171571Y66847D03*
X160571Y77839D03*
X165551D03*
X172120Y416600D03*
X168950Y412950D03*
X168910Y415930D03*
X170500Y441420D03*
X167580Y441380D03*
X164870Y441360D03*
X169440Y438390D03*
X166220Y438460D03*
X162975Y760266D03*
Y756766D03*
X170017D03*
X158425Y776911D03*
X170017Y763766D03*
X162975Y767266D03*
X158425Y783604D03*
X169117Y786950D03*
X170167Y791970D03*
X158425Y807029D03*
X169117Y796989D03*
X158425Y813722D03*
Y820415D03*
X169117Y823761D03*
Y833800D03*
X170167Y828781D03*
X158425Y843840D03*
Y850533D03*
Y857226D03*
X169117Y860572D03*
X170167Y865592D03*
X158425Y880651D03*
X169117Y870611D03*
X158425Y887344D03*
Y894037D03*
X169117Y897383D03*
X170167Y902403D03*
X169117Y907423D03*
X158425Y924155D03*
Y917462D03*
Y930848D03*
X170167Y939214D03*
X169117Y934194D03*
X158425Y954273D03*
X169117Y944234D03*
X158425Y960966D03*
Y967659D03*
Y974352D03*
Y981045D03*
Y987737D03*
Y994430D03*
Y1004470D03*
Y1034588D03*
Y1041281D03*
Y1047974D03*
Y1054667D03*
Y1071399D03*
Y1061360D03*
Y1078092D03*
X169117Y1081438D03*
X170167Y1086458D03*
X158425Y1101517D03*
X169117Y1091478D03*
X158425Y1114903D03*
Y1108210D03*
X169117Y1118249D03*
Y1128289D03*
X170167Y1123269D03*
X158425Y1145021D03*
Y1138328D03*
X169117Y1165100D03*
X170167Y1160080D03*
X169117Y1155060D03*
X158425Y1151714D03*
Y1175139D03*
Y1181832D03*
Y1188525D03*
X169117Y1191871D03*
X170167Y1196891D03*
X169117Y1201911D03*
X158425Y1211950D03*
Y1218643D03*
Y1225336D03*
X169117Y1238722D03*
Y1228682D03*
X170167Y1233702D03*
X158425Y1248761D03*
Y1255454D03*
X171481Y1337853D03*
X164481Y1337813D03*
X161881D03*
X170177Y1357409D03*
X159091Y1354871D03*
X157841Y1357371D03*
X159091Y1352271D03*
Y1349671D03*
X172021Y1367272D03*
Y1372872D03*
X170177Y1360516D03*
X165647Y1361417D03*
X163192Y1384789D03*
X164850Y1386740D03*
X168661Y1459995D03*
X166751Y1462595D03*
X168661Y1465195D03*
X164650Y1529350D03*
Y1540250D03*
X171925Y1708428D03*
X167500Y1712864D03*
X171925Y1727581D03*
X157860Y1718500D03*
X185928Y3001D03*
X173719Y17045D03*
X178699D03*
X173602Y25977D03*
X173719Y22037D03*
X178699D03*
X180707Y19541D03*
X172670Y37106D03*
X179757D03*
X172670Y48720D03*
X179757D03*
X176551Y71839D03*
Y66847D03*
X180657Y75343D03*
X182571Y72850D03*
Y77842D03*
X182548Y147260D03*
X176610Y441380D03*
X175990Y438100D03*
X173710Y441330D03*
X172740Y438260D03*
X173299Y664958D03*
X172802Y682036D03*
X174567Y773564D03*
Y780257D03*
Y803682D03*
X183726Y795316D03*
X174567Y810375D03*
Y817068D03*
X183726Y832127D03*
X174567Y840493D03*
Y847186D03*
Y853879D03*
Y877304D03*
X183726Y868938D03*
X174567Y890690D03*
Y883997D03*
X183726Y905750D03*
X174567Y920808D03*
Y914115D03*
Y927501D03*
Y950926D03*
X183726Y942561D03*
X174567Y957619D03*
Y971005D03*
Y964312D03*
Y984391D03*
Y977698D03*
Y991084D03*
Y997777D03*
Y1004470D03*
Y1031241D03*
Y1037934D03*
Y1044627D03*
Y1051320D03*
Y1058013D03*
Y1068052D03*
Y1074745D03*
X183726Y1089805D03*
X174567Y1098171D03*
Y1104863D03*
Y1111556D03*
Y1134982D03*
X183726Y1126616D03*
X174567Y1148367D03*
Y1141675D03*
X183726Y1163427D03*
X174567Y1178486D03*
Y1171793D03*
Y1185178D03*
Y1208604D03*
X183726Y1200238D03*
X174567Y1215297D03*
Y1221989D03*
X183726Y1237049D03*
X174567Y1252108D03*
Y1245415D03*
X185701Y1337853D03*
X183101D03*
X174081D03*
X172777Y1357409D03*
X183077D03*
X185521Y1357425D03*
X175377Y1357409D03*
X177977D03*
X180577D03*
X176881Y1367272D03*
X174451D03*
X186467Y1360456D03*
Y1363413D03*
X172777Y1360516D03*
X176881Y1372872D03*
X174451D03*
X177977Y1363473D03*
X175377D03*
Y1360516D03*
X177977D03*
X176930Y1385287D03*
X173441Y1459995D03*
X173451Y1452895D03*
X180141Y1450295D03*
X175361D03*
X180141Y1455495D03*
X175361D03*
X173441Y1465195D03*
X186851Y1472295D03*
X177322Y1498320D03*
X173980Y1528731D03*
X185254Y1686870D03*
X179444Y1708810D03*
X184340Y1718000D03*
X194607Y25977D03*
X196607Y23981D03*
X201563D03*
X201712Y19541D03*
X195544Y37106D03*
Y48720D03*
X193571Y71839D03*
X198551D03*
X191661Y69340D03*
X193571Y66847D03*
X198551D03*
X187656Y72850D03*
Y77842D03*
X195979Y109462D03*
X203061Y131158D03*
X195690Y415390D03*
X195730Y412410D03*
X200405Y622385D03*
Y632385D03*
X192676Y760266D03*
Y756766D03*
X199718D03*
X192676Y767266D03*
X199718Y763766D03*
X188126Y776911D03*
X199868Y791970D03*
X198818Y786950D03*
X188126Y783604D03*
X198818Y796989D03*
X188126Y807029D03*
Y813722D03*
Y820415D03*
X199868Y828781D03*
X198818Y823761D03*
Y833800D03*
X188126Y843840D03*
Y850533D03*
X199868Y865592D03*
X198818Y860572D03*
X188126Y857226D03*
X198818Y870611D03*
X188126Y880651D03*
Y887344D03*
Y894037D03*
X199868Y902403D03*
X198818Y897383D03*
Y907423D03*
X188126Y917462D03*
Y924155D03*
X199868Y939214D03*
X198818Y934194D03*
X188126Y930848D03*
X198818Y944234D03*
X188126Y954273D03*
Y960966D03*
Y967659D03*
Y974352D03*
Y981045D03*
Y987737D03*
Y994430D03*
Y1004470D03*
Y1034588D03*
Y1041281D03*
Y1047974D03*
Y1054667D03*
Y1061360D03*
Y1071399D03*
X199868Y1086458D03*
X198818Y1081438D03*
X188126Y1078092D03*
X198818Y1091478D03*
X188126Y1101517D03*
X198818Y1118249D03*
X188126Y1108210D03*
Y1114903D03*
X199868Y1123269D03*
X198818Y1128289D03*
X188126Y1138328D03*
Y1145021D03*
X199868Y1160080D03*
X198818Y1155060D03*
Y1165100D03*
X188126Y1151714D03*
Y1175139D03*
X198818Y1191871D03*
X188126Y1181832D03*
Y1188525D03*
X199868Y1196891D03*
X198818Y1201911D03*
X188126Y1211950D03*
Y1218643D03*
X199868Y1233702D03*
X198818Y1228682D03*
Y1238722D03*
X188126Y1225336D03*
Y1248761D03*
Y1255454D03*
X195771Y1337903D03*
X193171D03*
X190541Y1357371D03*
X189191Y1354871D03*
Y1352271D03*
X191791Y1354871D03*
Y1352271D03*
X189191Y1349671D03*
X191791D03*
X198547Y1361417D03*
X196092Y1384789D03*
X197750Y1386740D03*
X193551Y1462595D03*
X200241Y1459995D03*
X195461D03*
X202161Y1450295D03*
X200251Y1452895D03*
X202161Y1455495D03*
X193541Y1469695D03*
X188761D03*
X193541Y1474895D03*
X188761D03*
X200241Y1465195D03*
X195461D03*
X197703Y1550897D03*
X192978Y1550797D03*
X188254D03*
X187388Y1594876D03*
X192344D03*
X199448D03*
X187388Y1589884D03*
X199448D03*
X192344D03*
X193418Y1604876D03*
Y1599884D03*
X198374D03*
Y1604876D03*
Y1611796D03*
X193418D03*
X198374Y1616788D03*
X193418D03*
X192344Y1626788D03*
X199448D03*
X192344Y1621796D03*
X199448D03*
X187388D03*
Y1626788D03*
X200848Y1655656D03*
X190242Y1656635D03*
X201120Y1668603D03*
X199040Y1666925D03*
X196366Y1664821D03*
X190271Y1671753D03*
X195153Y1679774D03*
X190391Y1701988D03*
X195300Y1694898D03*
X194000Y1712362D03*
X201531Y1715000D03*
X192745Y1707106D03*
X199547Y1704605D03*
X195150Y1723000D03*
X207928Y3001D03*
X208659Y17045D03*
X203679D03*
X208780Y25977D03*
X203563D03*
X210780Y23981D03*
X215736D03*
X210668Y19541D03*
X215885D03*
X208659Y22037D03*
X203679D03*
X202631Y37106D03*
X216804D03*
X209718D03*
X202631Y48720D03*
X209718D03*
X216804D03*
X202795Y75340D03*
X204705Y72847D03*
X209685D03*
X213791Y69343D03*
X215705Y66850D03*
Y71842D03*
X204705Y77839D03*
X209685D03*
X214107Y113022D03*
X205489Y142790D03*
X206760Y148760D03*
X206805Y622385D03*
X203605D03*
X206805Y632385D03*
X203605D03*
X204268Y773564D03*
Y780257D03*
X213427Y795316D03*
X204268Y803682D03*
Y810375D03*
Y817068D03*
X213427Y832127D03*
X204268Y840493D03*
Y847186D03*
Y853879D03*
X213427Y868938D03*
X204268Y877304D03*
Y883997D03*
Y890690D03*
X213427Y905750D03*
X204268Y914115D03*
Y920808D03*
Y927501D03*
X213427Y942561D03*
X204268Y950926D03*
Y957619D03*
Y964312D03*
Y971005D03*
Y977698D03*
Y984391D03*
Y991084D03*
Y997777D03*
Y1004470D03*
Y1031241D03*
Y1037934D03*
Y1044627D03*
Y1051320D03*
Y1058013D03*
Y1068052D03*
Y1074745D03*
X213427Y1089805D03*
X204268Y1098171D03*
Y1104863D03*
Y1111556D03*
X213427Y1126616D03*
X204268Y1134982D03*
Y1141675D03*
Y1148367D03*
X213427Y1163427D03*
X204268Y1171793D03*
Y1178486D03*
Y1185178D03*
X213427Y1200238D03*
X204268Y1208604D03*
Y1215297D03*
Y1221989D03*
X213427Y1237049D03*
X204268Y1245415D03*
Y1252108D03*
X215977Y1357409D03*
X210877D03*
X208277D03*
X213477D03*
X205677D03*
X203077D03*
X207351Y1367272D03*
X209781Y1372872D03*
X204921Y1367272D03*
Y1372872D03*
X207351D03*
X210877Y1363473D03*
X208277D03*
Y1360516D03*
X210877D03*
X205677D03*
X203077D03*
X209781Y1367272D03*
X209830Y1385287D03*
X213648Y1416262D03*
X206941Y1450295D03*
Y1455495D03*
X213651Y1472295D03*
X215561Y1469695D03*
Y1474895D03*
X216601Y1550697D03*
X202427D03*
X211876Y1550897D03*
X207152D03*
X211508Y1594876D03*
X204404D03*
X216464D03*
X211508Y1589884D03*
X204404D03*
X216464D03*
X210434Y1604876D03*
X205478D03*
X210434Y1599884D03*
X205478D03*
Y1611796D03*
X210434D03*
Y1616788D03*
X205478D03*
X211508Y1626788D03*
X216464D03*
X211508Y1621796D03*
X216464D03*
X204404Y1626788D03*
Y1621796D03*
X203807Y1681173D03*
Y1696366D03*
X211103Y1708988D03*
X229928Y3001D03*
X217853Y17045D03*
X222833D03*
X217736Y25977D03*
X217853Y22037D03*
X222833D03*
X224841Y19541D03*
X223891Y37106D03*
X230977D03*
X223891Y48720D03*
X230977D03*
X224795Y75340D03*
X226705Y72847D03*
X231685D03*
X220685Y66850D03*
Y71842D03*
X231685Y77839D03*
X226705D03*
X233653Y162074D03*
X222000Y160000D03*
X220687Y522453D03*
X226687D03*
X233493Y676906D03*
X227493D03*
X224493D03*
X230493D03*
X221493D03*
X222377Y760266D03*
Y756766D03*
X229419D03*
X222377Y767266D03*
X229419Y763119D03*
X217827Y776911D03*
X229569Y791970D03*
X228519Y786950D03*
X217827Y783604D03*
X228519Y796989D03*
X217827Y807029D03*
Y813722D03*
Y820415D03*
X229569Y828781D03*
X228519Y823761D03*
Y833800D03*
X217827Y843840D03*
Y850533D03*
X229569Y865592D03*
X228519Y860572D03*
X217827Y857226D03*
X228519Y870611D03*
X217827Y880651D03*
Y887344D03*
Y894037D03*
X229569Y902403D03*
X228519Y897383D03*
Y907423D03*
X217827Y917462D03*
Y924155D03*
X229569Y939214D03*
X228519Y934194D03*
X217827Y930848D03*
X228519Y944234D03*
X217827Y954273D03*
Y960966D03*
Y967659D03*
Y974352D03*
Y981045D03*
Y987737D03*
Y994430D03*
Y1004470D03*
Y1034588D03*
Y1041281D03*
Y1047974D03*
Y1054667D03*
Y1061360D03*
Y1071399D03*
X229569Y1086458D03*
X228519Y1081438D03*
X217827Y1078092D03*
Y1101517D03*
X228519Y1091478D03*
Y1118249D03*
X217827Y1108210D03*
Y1114903D03*
X229569Y1123269D03*
X228519Y1128289D03*
X217827Y1138328D03*
Y1145021D03*
X229569Y1160080D03*
X228519Y1155060D03*
Y1165100D03*
X217827Y1151714D03*
Y1175139D03*
X228519Y1191871D03*
X217827Y1181832D03*
Y1188525D03*
X229569Y1196891D03*
X228519Y1201911D03*
X217827Y1211950D03*
Y1218643D03*
X229569Y1233702D03*
X228519Y1228682D03*
Y1238722D03*
X217827Y1225336D03*
Y1248761D03*
Y1255454D03*
X224481Y1326418D03*
X221881D03*
X224481Y1323918D03*
X221881Y1321418D03*
X224481D03*
X221881Y1323918D03*
X230171Y1323904D03*
Y1321404D03*
X227871Y1338124D03*
X223941Y1338068D03*
X221341D03*
X230661Y1338124D03*
X224691Y1354871D03*
Y1352271D03*
X223441Y1357371D03*
X222091Y1354871D03*
Y1352271D03*
X218421Y1357425D03*
X224691Y1349671D03*
X222091D03*
X219367Y1360456D03*
Y1363413D03*
X231347Y1361417D03*
X228892Y1384789D03*
X230550Y1386740D03*
X228693Y1408885D03*
X224881Y1410685D03*
X220803Y1412115D03*
X217097Y1413863D03*
X227051Y1452895D03*
X220351Y1462595D03*
X228961Y1450295D03*
Y1455495D03*
X227041Y1459995D03*
X222261D03*
X220341Y1469695D03*
Y1474895D03*
X227041Y1465195D03*
X222261D03*
X226050Y1550897D03*
X221325Y1550797D03*
X230774Y1550897D03*
X228524Y1594876D03*
X223568D03*
Y1589884D03*
X228524D03*
X222494Y1604876D03*
X217538D03*
X222494Y1599884D03*
X217538D03*
X229598Y1604876D03*
Y1599884D03*
Y1611796D03*
X217538D03*
X222494D03*
X229598Y1616788D03*
X217538D03*
X222494D03*
X223568Y1626788D03*
X228524D03*
X223568Y1621796D03*
X228524D03*
X243486Y23005D03*
X244296Y59765D03*
X242251Y162515D03*
X246250Y204360D03*
X233438Y593556D03*
X236638D03*
X233456Y601598D03*
X236656D03*
X236674Y609640D03*
X233474D03*
X233969Y773564D03*
Y780257D03*
Y803682D03*
Y810375D03*
Y817068D03*
Y840493D03*
Y847186D03*
Y853879D03*
Y877304D03*
Y883997D03*
Y890690D03*
Y914115D03*
Y920808D03*
Y927501D03*
Y950926D03*
Y957619D03*
Y964312D03*
Y971005D03*
Y977698D03*
Y984391D03*
Y991084D03*
Y997777D03*
Y1004470D03*
Y1031241D03*
Y1037934D03*
Y1044627D03*
Y1051320D03*
Y1058013D03*
Y1068052D03*
Y1074745D03*
Y1098171D03*
Y1104863D03*
Y1111556D03*
Y1134982D03*
Y1141675D03*
Y1148367D03*
Y1171793D03*
Y1178486D03*
Y1185178D03*
Y1208604D03*
Y1215297D03*
Y1221989D03*
Y1245415D03*
Y1252108D03*
X232961Y1323904D03*
Y1321404D03*
X239561Y1338124D03*
X243677Y1357409D03*
X241077D03*
X238477D03*
X235877D03*
X246277D03*
X242581Y1367272D03*
X240151D03*
X243677Y1363473D03*
X241077D03*
Y1360516D03*
X243677D03*
X242581Y1372872D03*
X240151D03*
X237721D03*
Y1367272D03*
X238477Y1360516D03*
X235877D03*
X242630Y1385287D03*
X233194Y1407349D03*
X233741Y1450295D03*
Y1455495D03*
X240451Y1472295D03*
X242361Y1469695D03*
Y1474895D03*
X235499Y1550897D03*
X240223D03*
X244947Y1550697D03*
X240584Y1594876D03*
X235628D03*
Y1589884D03*
X240584D03*
X246614Y1604876D03*
Y1599884D03*
X234554Y1604876D03*
Y1599884D03*
X241658Y1604876D03*
Y1599884D03*
X246614Y1611796D03*
X241658D03*
X234554D03*
X246614Y1616788D03*
X241658D03*
X234554D03*
X235628Y1626788D03*
X240584D03*
X235628Y1621796D03*
X240584D03*
X251928Y3001D03*
X247716Y75865D03*
Y71865D03*
X251793Y100846D03*
X261383Y133786D03*
X258253D03*
X249735Y152694D03*
X254095Y209235D03*
X254671Y642138D03*
X258470Y775410D03*
X260671Y1338124D03*
X258071D03*
X247725Y1338141D03*
X257491Y1352271D03*
X256241Y1357371D03*
X257491Y1354871D03*
X254891Y1352271D03*
Y1354871D03*
X251221Y1357425D03*
X248777Y1357409D03*
X257491Y1349671D03*
X254891D03*
X252167Y1363413D03*
Y1360456D03*
X253851Y1452895D03*
X247151Y1462595D03*
X260541Y1450295D03*
X255761D03*
X260541Y1455495D03*
X255761D03*
X253841Y1459995D03*
X249061D03*
X253841Y1465195D03*
X249061D03*
X247141Y1469695D03*
Y1474895D03*
X259120Y1550797D03*
X254396Y1550897D03*
X249671D03*
X259748Y1594876D03*
X247688D03*
X252644D03*
X247688Y1589884D03*
X259748D03*
X252644D03*
X253718Y1604876D03*
X258674D03*
X253718Y1599884D03*
X258674D03*
Y1611796D03*
X253718D03*
X258674Y1616788D03*
X253718D03*
X252644Y1626788D03*
X259748D03*
X252644Y1621796D03*
X259748D03*
X247688Y1626788D03*
Y1621796D03*
X273928Y3001D03*
X272596Y27185D03*
X263276Y34625D03*
X271596Y40165D03*
X270364Y118415D03*
X272361Y120243D03*
X264574Y159206D03*
Y155206D03*
X267500Y220441D03*
X265100Y595078D03*
X270905Y608485D03*
X273905D03*
Y611485D03*
X272603Y692910D03*
Y695510D03*
X271491Y1291740D03*
X274091D03*
X272077Y1314370D03*
X269477D03*
X274677D03*
X272077Y1311263D03*
X269477D03*
X274677D03*
X271321Y1326726D03*
Y1321126D03*
X276181Y1326726D03*
X273751D03*
X274677Y1317327D03*
X264947Y1315271D03*
X276181Y1321126D03*
X273751D03*
X276230Y1339141D03*
X264085Y1339175D03*
X267251Y1452895D03*
X273941Y1450295D03*
X269161D03*
X273941Y1455495D03*
X269161D03*
X276637Y1523953D03*
X270139Y1548563D03*
X271808Y1594876D03*
X264704D03*
X271808Y1589884D03*
X264704D03*
X265778Y1604876D03*
X270734D03*
X265778Y1599790D03*
X270734D03*
Y1611796D03*
X265778D03*
X270734Y1616788D03*
X265778D03*
X271808Y1626788D03*
Y1621796D03*
X264704Y1626788D03*
Y1621796D03*
X291000Y14820D03*
X285896Y23965D03*
X291156Y21395D03*
X286716Y40020D03*
X285499Y53191D03*
X278989Y48720D03*
X286076D03*
X283949Y152506D03*
X288516Y157065D03*
X285260Y234000D03*
X279500Y234075D03*
X290865Y609470D03*
X277105Y608485D03*
X280305D03*
X277105Y611485D03*
X280305D03*
X286665Y609470D03*
X283705Y608485D03*
X284705Y605485D03*
X283705Y611485D03*
X287832Y674150D03*
X283921Y1291740D03*
X281321D03*
X284821Y1311279D03*
X282377Y1311263D03*
X279877D03*
X277277Y1314370D03*
Y1311263D03*
X288491Y1306125D03*
Y1308725D03*
X291091Y1306125D03*
Y1308725D03*
X288491Y1303525D03*
X291091D03*
X289841Y1311225D03*
X285767Y1314310D03*
Y1317267D03*
X277277Y1317327D03*
X283946Y1530595D03*
X286446D03*
X288824Y1594876D03*
X276764D03*
X283868D03*
Y1589884D03*
X276764D03*
X288824D03*
X277838Y1604876D03*
X282794D03*
X277838Y1599884D03*
X282794D03*
X289898Y1604876D03*
Y1599884D03*
Y1611796D03*
X282794D03*
X277838D03*
X289898Y1616788D03*
X282794D03*
X277838D03*
X283868Y1626788D03*
X288824D03*
X283868Y1621796D03*
X288824D03*
X276764Y1626788D03*
Y1621796D03*
X295928Y3001D03*
X296272Y69128D03*
X293443Y78576D03*
X293448Y82486D03*
Y85986D03*
X303043Y79376D03*
X299943Y79276D03*
X299653Y92506D03*
X299628Y149203D03*
X299624Y158706D03*
X294553Y153819D03*
X293000Y216500D03*
X294165Y609570D03*
X297838Y609585D03*
X300965Y609570D03*
X304449D03*
X305121Y726348D03*
X298991D03*
X294541Y1291378D03*
X291941D03*
X302373Y1314342D03*
X304973D03*
X302373Y1311235D03*
X304973D03*
X304217Y1326698D03*
Y1321098D03*
X297843Y1315243D03*
X295388Y1338615D03*
X297046Y1340566D03*
X305199Y1398269D03*
Y1400769D03*
X295116Y1398132D03*
Y1400632D03*
X292516D03*
Y1398132D03*
X301513Y1452895D03*
X294813Y1462595D03*
X303423Y1450295D03*
Y1455495D03*
X301503Y1459995D03*
X296723D03*
X301503Y1465195D03*
X296723D03*
X299950Y1499500D03*
X301550Y1518040D03*
Y1514420D03*
Y1510800D03*
X302042Y1528731D03*
X300884Y1594876D03*
X295928D03*
Y1589884D03*
X300884D03*
X294854Y1604876D03*
Y1599884D03*
X301958Y1604876D03*
Y1599884D03*
Y1611796D03*
X294854D03*
X301958Y1616788D03*
X294854D03*
X295928Y1626788D03*
X300884D03*
X295928Y1621796D03*
X300884D03*
X317928Y3001D03*
X306716Y39985D03*
X320053Y85806D03*
Y88806D03*
X310425Y243925D03*
X317240Y252970D03*
X308925Y260075D03*
X307865Y609570D03*
X311349Y609632D03*
X313961Y607088D03*
Y604588D03*
X319657Y696415D03*
X319621Y1291740D03*
X321387Y1306097D03*
Y1308697D03*
Y1303497D03*
X317717Y1311251D03*
X315273Y1311235D03*
X312773D03*
X307573Y1314342D03*
Y1311235D03*
X310173Y1314342D03*
Y1311235D03*
X318663Y1314282D03*
X309077Y1321098D03*
X306647D03*
X318663Y1317239D03*
X309077Y1326698D03*
X306647D03*
X307573Y1317299D03*
X310173D03*
X309126Y1339113D03*
X307799Y1400769D03*
Y1398269D03*
X318199Y1400549D03*
X314199D03*
X310399D03*
X308203Y1450295D03*
Y1455495D03*
X314913Y1472295D03*
X316823Y1469695D03*
Y1474895D03*
X321040Y1550797D03*
X316316D03*
X320048Y1594876D03*
X307988D03*
X312944D03*
X307988Y1589884D03*
X320048D03*
X312944D03*
X306914Y1604876D03*
Y1599884D03*
X314018Y1604876D03*
X318974D03*
X314018Y1599884D03*
X318974D03*
Y1611796D03*
X314018D03*
X306914D03*
X318974Y1616788D03*
X314018D03*
X306914D03*
X320048Y1626788D03*
X312944D03*
X320048Y1621796D03*
X312944D03*
X307988Y1626788D03*
Y1621796D03*
X329535Y49379D03*
X331000Y270260D03*
X328966Y543012D03*
X334744Y566086D03*
X333500Y582500D03*
Y578500D03*
X333988Y590633D03*
X329471Y1291778D03*
X322221Y1291740D03*
X326761Y1291778D03*
X335277Y1314285D03*
Y1311178D03*
X323987Y1303497D03*
Y1306097D03*
Y1308697D03*
X322737Y1311197D03*
X330747Y1315186D03*
X328292Y1338558D03*
X329950Y1340509D03*
X333830Y1396299D03*
Y1398899D03*
Y1401499D03*
Y1393799D03*
X324309Y1396599D03*
Y1399199D03*
Y1401799D03*
Y1394099D03*
X321999Y1400549D03*
X321613Y1462595D03*
X323523Y1459995D03*
X328303D03*
X328313Y1452895D03*
X335003Y1450295D03*
X330223D03*
X335003Y1455495D03*
X330223D03*
X328313Y1472295D03*
X323523Y1465195D03*
X328303D03*
X321603Y1469695D03*
Y1474895D03*
X325765Y1550897D03*
X330489Y1550697D03*
X335214Y1550897D03*
X332108Y1594876D03*
X325004D03*
X332108Y1589884D03*
X325004D03*
X326078Y1604876D03*
X331034D03*
X326078Y1599884D03*
X331034D03*
Y1611796D03*
X326078D03*
X331034Y1616788D03*
X326078D03*
X332108Y1626788D03*
X325004D03*
X332108Y1621796D03*
X325004D03*
X343036Y122525D03*
X342075Y287925D03*
X351157Y562415D03*
X345500Y574415D03*
X351157D03*
X338664Y699660D03*
X337030Y697750D03*
X340477Y1314285D03*
X337877D03*
Y1311178D03*
X340477D03*
X350621Y1311194D03*
X348177Y1311178D03*
X343077Y1314285D03*
X345677Y1311178D03*
X343077D03*
X341981Y1321041D03*
X339551D03*
X341981Y1326641D03*
X337121Y1321041D03*
X339551Y1326641D03*
X337121D03*
X340477Y1317242D03*
X343077D03*
X342030Y1339056D03*
X347110Y1398312D03*
X351110D03*
X341760Y1401449D03*
X337760D03*
X349760D03*
X345760D03*
X348413Y1462595D03*
X350323Y1459995D03*
X341713Y1472295D03*
X350323Y1465195D03*
X348403Y1469695D03*
X343623D03*
X348403Y1474895D03*
X343623D03*
X339938Y1550897D03*
X349387Y1550797D03*
X344663Y1550697D03*
X349124Y1594876D03*
X337064D03*
X344168D03*
Y1589884D03*
X337064D03*
X349124D03*
X338138Y1604876D03*
X343094D03*
X338138Y1599884D03*
X343094D03*
X350198Y1604876D03*
Y1599884D03*
Y1611796D03*
X343094D03*
X338138D03*
X350198Y1616788D03*
X343094D03*
X338138D03*
X344168Y1626788D03*
X349124D03*
X344168Y1621796D03*
X349124D03*
X337064Y1626788D03*
Y1621796D03*
X351535Y49379D03*
X366874Y135157D03*
X366771Y127665D03*
X359734Y288768D03*
X360433Y294030D03*
X355832Y297855D03*
X353700Y547893D03*
X356850D03*
X365593Y621622D03*
X364788Y1193918D03*
X364457Y1188109D03*
X359541Y1291918D03*
X362311Y1291968D03*
X356551Y1291880D03*
X353951D03*
X356891Y1306040D03*
Y1308640D03*
Y1303440D03*
X354291Y1306040D03*
Y1308640D03*
Y1303440D03*
X355641Y1311140D03*
X351567Y1314225D03*
Y1317182D03*
X363547Y1315386D03*
X361092Y1338758D03*
X362750Y1340709D03*
X355110Y1398312D03*
X359110D03*
X363110D03*
X357760Y1401449D03*
X353760D03*
X355113Y1452895D03*
X361803Y1450295D03*
X357023D03*
X361803Y1455495D03*
X357023D03*
X355103Y1459995D03*
Y1465195D03*
X354112Y1550897D03*
X358836D03*
X363561D03*
X361184Y1594876D03*
X356228D03*
Y1589884D03*
X361184D03*
X355154Y1604876D03*
Y1599884D03*
X362258Y1604876D03*
Y1599790D03*
Y1611796D03*
X355154D03*
X362258Y1616788D03*
X355154D03*
X356228Y1626788D03*
X361184D03*
X356228Y1621796D03*
X361184D03*
X373535Y49379D03*
X375920Y146577D03*
X380012Y243615D03*
X379200Y298772D03*
X367902Y303760D03*
X380771Y524903D03*
X375943D03*
X371724Y699450D03*
X370090Y697482D03*
X372000Y816862D03*
Y826362D03*
Y828862D03*
Y837862D03*
Y840362D03*
Y849362D03*
X378083Y1184949D03*
X367782Y1199648D03*
X380977Y1311378D03*
X375877Y1314485D03*
X378477Y1311378D03*
X375877D03*
X370677Y1314485D03*
X368077D03*
X373277D03*
X368077Y1311378D03*
X370677D03*
X373277D03*
X375877Y1317442D03*
X372351Y1326841D03*
X369921D03*
Y1321241D03*
X374781Y1326841D03*
X373277Y1317442D03*
X374781Y1321241D03*
X372351D03*
X374830Y1339256D03*
X379610Y1391781D03*
X375056Y1393741D03*
X375213Y1462595D03*
X377123Y1459995D03*
X368513Y1472295D03*
X377123Y1465195D03*
X375203Y1469695D03*
X370423D03*
X375203Y1474895D03*
X370423D03*
X368285Y1550897D03*
X373009Y1550697D03*
X377733Y1550897D03*
X368288Y1594876D03*
X373244D03*
X368288Y1589884D03*
X373244D03*
X367214Y1604876D03*
Y1599790D03*
X374318Y1604876D03*
X379274D03*
X374318Y1599884D03*
X379274D03*
Y1611796D03*
X374318D03*
X367214D03*
X379274Y1616788D03*
X374318D03*
X367214D03*
X373244Y1626788D03*
Y1621796D03*
X368288Y1626788D03*
Y1621796D03*
X372313Y1641759D03*
X379895Y1670046D03*
X372350Y1683284D03*
X385024Y-17575D03*
X381771Y-17589D03*
X388049Y-18895D03*
X381756Y-20104D03*
X385009Y-20090D03*
X381725Y-14717D03*
X385008Y-9673D03*
X385023Y-7158D03*
X381755Y-9687D03*
X388048Y-8478D03*
X381770Y-7172D03*
X381740Y-12202D03*
X395535Y49379D03*
X391600Y121178D03*
X387712Y147441D03*
X384600Y221800D03*
X386563Y280370D03*
X387184Y470495D03*
X387440Y525154D03*
X395657Y546894D03*
X391657Y546816D03*
X387657Y546876D03*
X384500Y810862D03*
X384499Y819862D03*
X388361Y1293713D03*
X385701Y1291828D03*
X392176Y1309859D03*
X394951Y1311259D03*
X389691Y1306240D03*
Y1308840D03*
X387091Y1306240D03*
Y1308840D03*
X389691Y1303640D03*
X387091D03*
X383421Y1311394D03*
X388441Y1311340D03*
X384367Y1314425D03*
Y1317382D03*
X392950Y1315280D03*
X392910Y1317880D03*
X395267Y1358621D03*
X393321Y1385630D03*
X388718Y1387386D03*
X384270Y1389875D03*
X395313Y1452895D03*
X381913D03*
X383823Y1450295D03*
X388603D03*
X383823Y1455495D03*
X388603D03*
X381903Y1459995D03*
Y1465195D03*
X382458Y1550897D03*
X387182Y1550797D03*
X393322Y1573347D03*
X394915Y1590018D03*
X387805Y1607802D03*
Y1604802D03*
Y1610802D03*
X387325Y1627212D03*
X385502Y1667154D03*
X394824Y1667120D03*
X389824D03*
X403734Y110326D03*
Y118976D03*
X397426Y112815D03*
Y116215D03*
X402606Y129465D03*
Y126065D03*
X403141Y144300D03*
X396237Y315507D03*
X399657Y546915D03*
X401880Y696220D03*
X404771Y698670D03*
X396129Y1334717D03*
X408459Y1330709D03*
X405859D03*
X400659D03*
X403259D03*
X408459Y1333816D03*
X405859D03*
X403259D03*
X400659D03*
X408459Y1336773D03*
X405859D03*
X402503Y1340572D03*
X407363D03*
X404933D03*
X407412Y1358587D03*
X407363Y1346172D03*
X404933D03*
X402503D03*
X410002Y1375093D03*
X405978Y1377794D03*
X401953Y1380494D03*
X397187Y1383354D03*
X397223Y1450295D03*
X402003D03*
X397223Y1455495D03*
X402003D03*
X401583Y1504872D03*
X404699Y1523953D03*
X398201Y1548563D03*
X410672Y1561170D03*
X400905Y1596091D03*
X403417Y1606224D03*
X403848Y1615354D03*
X400623Y1629772D03*
X406075Y1641000D03*
X399824Y1667120D03*
X409000Y1667025D03*
X405000Y1683500D03*
X401666Y1677925D03*
X417535Y49379D03*
X413949Y69270D03*
X414486Y127579D03*
Y124179D03*
X423521Y1311969D03*
X421091Y1311219D03*
X419673Y1325571D03*
Y1322971D03*
Y1328171D03*
X422273Y1322971D03*
Y1325571D03*
Y1328171D03*
X416949Y1336713D03*
Y1333756D03*
X424333Y1331447D03*
X411059Y1330709D03*
X416003Y1330725D03*
X413559Y1330709D03*
X421023Y1330671D03*
X414132Y1372234D03*
X415862Y1503715D03*
X422557Y1530595D03*
X420057D03*
X421059Y1569168D03*
X416163Y1594450D03*
X422007Y1592330D03*
X413100Y1607600D03*
X418293Y1607495D03*
X423379Y1607675D03*
X413200Y1612700D03*
X423439Y1612407D03*
X411515Y1599649D03*
X413100Y1617900D03*
X418500Y1618000D03*
X423349Y1617857D03*
X416962Y1634123D03*
X415437Y1636382D03*
X417365Y1630495D03*
X420765D03*
X421347Y1636668D03*
X411500Y1653500D03*
X417441Y1643946D03*
X420000Y1668075D03*
X417000Y1683500D03*
X439535Y49379D03*
X430564Y56348D03*
X430500Y72900D03*
X436090Y128007D03*
X440090Y132007D03*
X433124Y222253D03*
Y225205D03*
X439500Y484000D03*
X439284Y1038766D03*
Y1042766D03*
X431830Y1311240D03*
X438561Y1321622D03*
X432561D03*
X435561D03*
X437624Y1452895D03*
X430924Y1462595D03*
X439534Y1450295D03*
Y1455495D03*
X437614Y1459995D03*
X432834D03*
X437614Y1465195D03*
X432834D03*
X436140Y1499320D03*
X437661Y1518040D03*
Y1514420D03*
Y1510800D03*
X438153Y1528731D03*
X430239Y1581726D03*
X426688Y1598003D03*
X439283Y1608704D03*
X432559Y1627500D03*
X439404Y1615146D03*
X428000Y1640500D03*
X450102Y87011D03*
X450414Y92384D03*
X443014D03*
X452090Y116007D03*
Y124007D03*
Y132007D03*
Y128007D03*
X445997Y170701D03*
X453783Y217646D03*
X441320Y304170D03*
Y310170D03*
X449760Y497240D03*
X448688Y1305947D03*
X449440Y1308386D03*
X450220Y1310834D03*
X451083Y1313347D03*
X441561Y1321622D03*
X444561D03*
X452089Y1316074D03*
X452936Y1318775D03*
X453823Y1321436D03*
X454603Y1324033D03*
X454909Y1326721D03*
X444314Y1450295D03*
Y1455495D03*
X451024Y1472295D03*
X452934Y1469695D03*
Y1474895D03*
X452427Y1550797D03*
X440846Y1576526D03*
X451561Y1589884D03*
Y1594876D03*
X444128Y1604200D03*
Y1600200D03*
X451561Y1621796D03*
Y1626788D03*
X448776Y1622266D03*
Y1617166D03*
Y1619766D03*
X452500Y1637559D03*
X447387Y1641441D03*
X454099Y1649575D03*
X461535Y49379D03*
X457502Y87011D03*
X464456Y93101D03*
X457056D03*
X464051Y224799D03*
X460624Y244103D03*
X465925Y489925D03*
X457724Y1462595D03*
X459634Y1459995D03*
X464414D03*
X466334Y1450295D03*
X464424Y1452895D03*
X466334Y1455495D03*
X459634Y1465195D03*
X464414D03*
X457714Y1469695D03*
Y1474895D03*
X461876Y1550897D03*
X457151Y1550797D03*
X466600Y1550697D03*
X468577Y1589884D03*
Y1594876D03*
X456517Y1589884D03*
X463621D03*
Y1594876D03*
X456517D03*
X457591Y1599884D03*
X462547D03*
Y1604876D03*
X457591D03*
X462547Y1611796D03*
X457591D03*
X469651D03*
Y1599884D03*
Y1604876D03*
X462547Y1616788D03*
X457591D03*
X469651D03*
X468577Y1621796D03*
Y1626788D03*
X463621Y1621796D03*
Y1626788D03*
X456517Y1621796D03*
Y1626788D03*
X457240Y1629500D03*
X462500Y1655500D03*
X468350Y1645351D03*
X461000Y1650000D03*
X470309Y1689000D03*
X470500Y1674075D03*
X462500Y1701000D03*
X468500Y1708500D03*
X467416Y1724808D03*
X469975D03*
X464734Y1730518D03*
X483535Y49379D03*
X478949Y60029D03*
Y55135D03*
Y64975D03*
X470895Y128020D03*
X478295D03*
X482255Y127322D03*
Y135722D03*
X479630Y141942D03*
X471371Y231764D03*
X477203Y1015474D03*
X484784D03*
X477203Y1019017D03*
X484784D03*
X477203Y1022560D03*
X484784D03*
X484524Y1462595D03*
X471114Y1450295D03*
Y1455495D03*
X477824Y1472295D03*
X484514Y1469695D03*
X479734D03*
X484514Y1474895D03*
X479734D03*
X480774Y1550697D03*
X476049Y1550897D03*
X471325D03*
X480637Y1589884D03*
Y1594876D03*
X475681D03*
Y1589884D03*
X481711Y1611796D03*
Y1599884D03*
Y1604876D03*
X474607Y1611796D03*
Y1599884D03*
Y1604876D03*
X481711Y1616788D03*
X474607D03*
X475681Y1621796D03*
X480637D03*
X475681Y1626788D03*
X480637D03*
X478500Y1655500D03*
X476000Y1680000D03*
X478500Y1701000D03*
Y1714500D03*
X487590Y105969D03*
X494810D03*
X492300Y121389D03*
X487880Y131442D03*
X496280D03*
X492300Y124389D03*
X488580Y141942D03*
X494200Y158800D03*
X488260Y418980D03*
X488405Y578572D03*
X492284Y1015474D03*
Y1019017D03*
Y1022560D03*
X491224Y1452895D03*
X497914Y1450295D03*
X493134D03*
X497914Y1455495D03*
X493134D03*
X486434Y1459995D03*
X491214D03*
X486434Y1465195D03*
X491214D03*
X485498Y1550797D03*
X490223Y1550897D03*
X494947D03*
X499672D03*
X499801Y1594876D03*
X492697Y1589884D03*
X487741Y1594876D03*
X492697D03*
X499801Y1589884D03*
X487741D03*
X498727Y1611796D03*
Y1599884D03*
Y1604876D03*
X486667Y1611796D03*
X493771D03*
Y1599884D03*
Y1604876D03*
X486667Y1599884D03*
Y1604876D03*
X498727Y1616788D03*
X499801Y1621796D03*
Y1626788D03*
X486667Y1616788D03*
X493771D03*
X492697Y1621796D03*
X487741D03*
X492697Y1626788D03*
X487741D03*
X510815Y69562D03*
X502815Y106984D03*
X512654Y94967D03*
X500836Y119092D03*
X511140Y109829D03*
X511170Y224930D03*
Y227882D03*
X501500Y433000D03*
X511324Y1462595D03*
X513234Y1459995D03*
X504624Y1472295D03*
X513234Y1465195D03*
X511314Y1469695D03*
X506534D03*
X511314Y1474895D03*
X506534D03*
X513844Y1550897D03*
X509120Y1550697D03*
X504396Y1550897D03*
X511861Y1594876D03*
X504757Y1589884D03*
Y1594876D03*
X511861Y1589884D03*
X505831Y1611796D03*
X510787D03*
X505831Y1599884D03*
Y1604876D03*
X510787Y1599884D03*
Y1604876D03*
X511861Y1621796D03*
Y1626788D03*
X505831Y1616788D03*
X510787D03*
X504757Y1621796D03*
Y1626788D03*
X518843Y23788D03*
X517907Y69507D03*
X524993D03*
X516020Y102870D03*
X519240Y94967D03*
X521420Y109829D03*
X516020Y111770D03*
X518418Y137171D03*
X522831Y443712D03*
X518024Y1452895D03*
X519934Y1450295D03*
X524714D03*
X519934Y1455495D03*
X524714D03*
X518014Y1459995D03*
Y1465195D03*
X523293Y1550797D03*
X518569Y1550897D03*
X528940Y1548260D03*
X528877Y1589884D03*
Y1594876D03*
X516817Y1589884D03*
Y1594876D03*
X523921D03*
Y1589884D03*
X529951Y1611796D03*
Y1599790D03*
Y1604876D03*
X517891Y1611796D03*
X522847D03*
Y1599884D03*
X517891D03*
X522847Y1604876D03*
X517891D03*
X529951Y1616788D03*
X528877Y1621796D03*
Y1626788D03*
X517891Y1616788D03*
X522847D03*
X523921Y1621796D03*
X516817D03*
X523921Y1626788D03*
X516817D03*
X540843Y23788D03*
X542723Y39562D03*
X532080Y69507D03*
X539166D03*
X535170Y108730D03*
Y117630D03*
X533097Y246780D03*
X532000Y426500D03*
X544844Y439701D03*
X543500Y463500D03*
X540106Y657325D03*
X531424Y1452895D03*
X533334Y1450295D03*
X538114D03*
X533334Y1455495D03*
X538114D03*
X544814Y1459995D03*
X540810Y1523953D03*
X540937Y1589884D03*
Y1594876D03*
X535981D03*
Y1589884D03*
X542011Y1611796D03*
Y1599884D03*
Y1604876D03*
X534907Y1611796D03*
Y1599790D03*
Y1604876D03*
X542011Y1616788D03*
X540937Y1621796D03*
Y1626788D03*
X534907Y1616788D03*
X535981Y1621796D03*
Y1626788D03*
X548610Y57990D03*
X546253Y69507D03*
X553340D03*
X545935Y77516D03*
X553821D03*
X546400Y120700D03*
X553780Y118740D03*
Y127140D03*
X547196Y195256D03*
X546800Y262800D03*
X548856Y440452D03*
X556993Y616406D03*
X550993D03*
X553993D03*
X547993D03*
X558986Y1462595D03*
X545931Y1451344D03*
X559090Y1452185D03*
X548119Y1530595D03*
X550619D03*
X552997Y1589884D03*
X548041Y1594876D03*
X552997D03*
X548041Y1589884D03*
X559027Y1611796D03*
Y1599884D03*
Y1604876D03*
X546967Y1611796D03*
X554071D03*
Y1599884D03*
Y1604876D03*
X546967Y1599884D03*
Y1604876D03*
X559027Y1616788D03*
X546967D03*
X554071D03*
X552997Y1621796D03*
Y1626788D03*
X548041D03*
Y1621796D03*
X562843Y23788D03*
X560426Y69507D03*
X570860Y118310D03*
X565210Y125819D03*
X570860Y127510D03*
X564603Y197778D03*
Y200304D03*
X573911Y212196D03*
X569004Y228571D03*
X563230Y426508D03*
X563575Y448425D03*
X569464Y462140D03*
X559993Y616406D03*
X561580Y1242740D03*
X565686Y1452895D03*
X567596Y1450295D03*
X572376D03*
X567596Y1455495D03*
X572376D03*
X565676Y1459995D03*
X560896D03*
X565676Y1465195D03*
X560896D03*
X562860Y1499360D03*
X565723Y1510800D03*
Y1514420D03*
Y1518040D03*
X566215Y1528731D03*
X572161Y1594876D03*
X565057Y1589884D03*
X560101Y1594876D03*
X565057D03*
X572161Y1589884D03*
X560101D03*
X571087Y1611796D03*
Y1599884D03*
Y1604876D03*
X566131Y1611796D03*
Y1599884D03*
Y1604876D03*
X571087Y1616788D03*
X572161Y1621796D03*
Y1626788D03*
X566131Y1616788D03*
X565057Y1621796D03*
X560101D03*
X565057Y1626788D03*
X560101D03*
X584843Y23788D03*
X580098Y96439D03*
X576510Y125819D03*
X588554Y221277D03*
X577859Y212196D03*
X588554Y229277D03*
X575917Y421390D03*
X583505Y457925D03*
X587812Y474353D03*
X577801Y466000D03*
X578830Y1238075D03*
X578071Y1244425D03*
X588630Y1255075D03*
X583630D03*
X585786Y1462595D03*
X587696Y1459995D03*
X579086Y1472295D03*
X587696Y1465195D03*
X580996Y1469695D03*
X585776D03*
X580996Y1474895D03*
X585776D03*
X585213Y1550797D03*
X580489D03*
X589177Y1589884D03*
Y1594876D03*
X577117Y1589884D03*
Y1594876D03*
X584221D03*
Y1589884D03*
X578191Y1611796D03*
X583147D03*
Y1599884D03*
X578191D03*
X583147Y1604876D03*
X578191D03*
X589177Y1621796D03*
Y1626788D03*
X578191Y1616788D03*
X583147D03*
X584221Y1621796D03*
X577117D03*
X584221Y1626788D03*
X577117D03*
X603379Y70512D03*
X594430Y463600D03*
X592612Y805986D03*
X594330Y1238075D03*
X595671Y1245688D03*
X595598Y1251075D03*
X599659Y1241734D03*
X603947Y1258575D03*
X595947D03*
X592476Y1459995D03*
X594396Y1450295D03*
X599176D03*
X592486Y1452895D03*
X594396Y1455495D03*
X599176D03*
X592476Y1465195D03*
X599387Y1550897D03*
X604111D03*
X589938D03*
X594662Y1550697D03*
X601237Y1589884D03*
Y1594876D03*
X596281D03*
Y1589884D03*
X602311Y1611796D03*
Y1599884D03*
Y1604876D03*
X590251Y1611796D03*
X595207D03*
Y1599884D03*
X590251D03*
X595207Y1604876D03*
X590251D03*
X602311Y1616788D03*
X601237Y1621796D03*
Y1626788D03*
X590251Y1616788D03*
X595207D03*
X596281Y1621796D03*
Y1626788D03*
X606843Y23788D03*
X615190Y70533D03*
X607834Y222611D03*
X612414Y227041D03*
X605796Y425585D03*
X612969Y447260D03*
X616171Y780364D03*
X606559Y796116D03*
X612871Y1248488D03*
X612947Y1252075D03*
X609159Y1240234D03*
X612447Y1258575D03*
X616527Y1390732D03*
X619286Y1452895D03*
X612586Y1462595D03*
X614496Y1459995D03*
X619276D03*
X605886Y1472295D03*
X614496Y1465195D03*
X619276D03*
X612576Y1469695D03*
X607796D03*
X612576Y1474895D03*
X607796D03*
X613560Y1550797D03*
X618285Y1550897D03*
X608836Y1550697D03*
X613297Y1589884D03*
X608341Y1594876D03*
X613297D03*
X608341Y1589884D03*
X619327Y1611796D03*
Y1599884D03*
Y1604876D03*
X607267Y1611796D03*
X614371D03*
Y1599884D03*
Y1604876D03*
X607267Y1599884D03*
Y1604876D03*
X619327Y1616788D03*
X607267D03*
X614371D03*
X613297Y1621796D03*
X608341D03*
X613297Y1626788D03*
X608341D03*
X628843Y23788D03*
X625574Y150177D03*
X623605Y219277D03*
Y228777D03*
X624760Y424569D03*
X621916Y465088D03*
X632996Y478309D03*
X621309Y483346D03*
X634288Y766646D03*
X625976Y1450295D03*
X621196D03*
X625976Y1455495D03*
X621196D03*
X632686Y1472295D03*
X632458Y1550897D03*
X623009D03*
X627734D03*
X632461Y1594876D03*
X625357Y1589884D03*
X620401Y1594876D03*
X625357D03*
X632461Y1589884D03*
X620401D03*
X631387Y1611796D03*
Y1599790D03*
Y1604876D03*
X626431Y1611796D03*
Y1599790D03*
Y1604876D03*
X631387Y1616788D03*
X632461Y1626788D03*
Y1621796D03*
X626431Y1616788D03*
X620401Y1621796D03*
X625357D03*
X620401Y1626788D03*
X625357D03*
X627958Y1654114D03*
X645151Y69507D03*
X642394Y131172D03*
X642481Y184862D03*
X643012Y201913D03*
Y199313D03*
X635200Y415425D03*
X644673Y425816D03*
X637504Y454352D03*
X636614Y512597D03*
X647354Y776911D03*
Y783604D03*
Y807029D03*
Y813722D03*
Y820415D03*
Y843840D03*
Y850533D03*
Y857226D03*
Y880651D03*
Y887344D03*
Y894037D03*
Y917462D03*
Y924155D03*
Y930848D03*
Y954273D03*
Y960966D03*
Y967659D03*
Y974352D03*
Y981045D03*
Y987737D03*
Y994430D03*
Y1004470D03*
Y1034588D03*
Y1041281D03*
Y1047974D03*
Y1054667D03*
Y1061360D03*
Y1071399D03*
Y1078092D03*
Y1101517D03*
Y1108210D03*
Y1114903D03*
Y1138328D03*
Y1145021D03*
Y1151714D03*
Y1175139D03*
Y1181832D03*
Y1188525D03*
Y1211950D03*
Y1218643D03*
Y1225336D03*
Y1248761D03*
Y1255454D03*
X642436Y1350877D03*
X646236D03*
X638436D03*
X643563Y1392581D03*
X647445Y1392605D03*
X646086Y1452895D03*
X639386Y1462595D03*
X647996Y1450295D03*
Y1455495D03*
X641296Y1459995D03*
X646076D03*
X641296Y1465195D03*
X646076D03*
X639376Y1469695D03*
X634596D03*
X639376Y1474895D03*
X634596D03*
X646631Y1550897D03*
X637182Y1550697D03*
X641906Y1550897D03*
X637417Y1589884D03*
Y1594876D03*
X643447Y1599884D03*
X638491D03*
X643447Y1604876D03*
X638491D03*
X643447Y1611796D03*
X638491D03*
X643447Y1616788D03*
X637417Y1626788D03*
X638491Y1616788D03*
X637417Y1621796D03*
X640520Y1635483D03*
X649266Y1650126D03*
X642151Y1649961D03*
X639284Y1683049D03*
X647500Y1682850D03*
X635210Y1721545D03*
X650843Y23788D03*
X649585Y29298D03*
X663703Y32574D03*
X653570Y58363D03*
X660775Y78330D03*
X649441Y177003D03*
X662740Y375240D03*
X649500Y382500D03*
X660885Y412588D03*
X650268Y479141D03*
X649771Y505736D03*
X659398Y516260D03*
X658946Y756766D03*
X651904D03*
Y760266D03*
X663496Y773564D03*
X658946Y763766D03*
X651904Y767266D03*
X658046Y786950D03*
X663496Y780257D03*
X651754Y795316D03*
X658046Y796989D03*
X663496Y803682D03*
Y810375D03*
Y817068D03*
X651754Y832127D03*
X658046Y833800D03*
Y823761D03*
X663496Y840493D03*
Y847186D03*
X658046Y860572D03*
X663496Y853879D03*
X651754Y868938D03*
X658046Y870611D03*
X663496Y877304D03*
Y883997D03*
Y890690D03*
X651754Y905750D03*
X658046Y897383D03*
Y907423D03*
X663496Y914115D03*
Y920808D03*
X658046Y934194D03*
X663496Y927501D03*
X651754Y942561D03*
X658046Y944234D03*
X663496Y950926D03*
Y957619D03*
Y964312D03*
Y971005D03*
Y977698D03*
Y984391D03*
Y991084D03*
Y997777D03*
Y1004470D03*
Y1031241D03*
Y1037934D03*
Y1044627D03*
Y1051320D03*
Y1058013D03*
Y1068052D03*
Y1074745D03*
X651754Y1089805D03*
X658046Y1081438D03*
Y1091478D03*
X663496Y1098171D03*
Y1104863D03*
X658046Y1118249D03*
X663496Y1111556D03*
X651754Y1126616D03*
X658046Y1128289D03*
X663496Y1134982D03*
Y1141675D03*
Y1148367D03*
X651754Y1163427D03*
X658046Y1155060D03*
Y1165100D03*
X663496Y1171793D03*
Y1178486D03*
X658046Y1191871D03*
X663496Y1185178D03*
X651754Y1200238D03*
X658046Y1201911D03*
X663496Y1208604D03*
Y1215297D03*
Y1221989D03*
X651754Y1237049D03*
X658046Y1238722D03*
Y1228682D03*
X663496Y1245415D03*
Y1252108D03*
X657836Y1350877D03*
X653836D03*
X650036D03*
X661713Y1373981D03*
X655702Y1391107D03*
X659559Y1391027D03*
X655873Y1428844D03*
X652189Y1421276D03*
X659486Y1452895D03*
X661396Y1450295D03*
X652776D03*
X661396Y1455495D03*
X652776D03*
X662374Y1548563D03*
X651355Y1550797D03*
X651840Y1567752D03*
X660542Y1638169D03*
X657392Y1628137D03*
X652274Y1630366D03*
X650895Y1648115D03*
X655914Y1668744D03*
X659436Y1694697D03*
X649526Y1709274D03*
X663997Y1703111D03*
X659673Y1722174D03*
X661845Y1717340D03*
X654508Y1728000D03*
X654527Y1718229D03*
X659673Y1732836D03*
X672843Y23788D03*
X668739Y45262D03*
X677594Y36205D03*
X675887Y45262D03*
X666411Y69507D03*
X678664Y88080D03*
X673751Y78092D03*
X673691Y200672D03*
X673301Y211332D03*
X671753Y397936D03*
X670000Y457844D03*
X669955Y495468D03*
X671500Y529500D03*
X677055Y776911D03*
X667896Y791970D03*
X677055Y783604D03*
Y807029D03*
Y813722D03*
Y820415D03*
X667896Y828781D03*
X677055Y843840D03*
Y850533D03*
X667896Y865592D03*
X677055Y857226D03*
Y880651D03*
Y887344D03*
Y894037D03*
X667896Y902403D03*
X677055Y917462D03*
Y924155D03*
X667896Y939214D03*
X677055Y930848D03*
Y954273D03*
Y960966D03*
Y967659D03*
Y974352D03*
Y981045D03*
Y987737D03*
Y994430D03*
Y1004470D03*
Y1034588D03*
Y1041281D03*
Y1047974D03*
Y1054667D03*
Y1061360D03*
Y1071399D03*
X667896Y1086458D03*
X677055Y1078092D03*
Y1101517D03*
Y1108210D03*
Y1114903D03*
X667896Y1123269D03*
X677055Y1138328D03*
Y1145021D03*
X667896Y1160080D03*
X677055Y1151714D03*
Y1175139D03*
Y1181832D03*
Y1188525D03*
X667896Y1196891D03*
X677055Y1211950D03*
Y1218643D03*
X667896Y1233702D03*
X677055Y1225336D03*
Y1248761D03*
Y1255454D03*
X674552Y1351988D03*
Y1349488D03*
X666176Y1450295D03*
Y1455495D03*
X666050Y1501670D03*
X672684Y1522690D03*
X674687Y1519726D03*
X665800Y1530575D03*
X674620Y1535271D03*
Y1542125D03*
X672617Y1545089D03*
Y1538235D03*
X674894Y1629042D03*
X673982Y1639289D03*
X665802Y1652337D03*
X674486Y1647842D03*
X673480Y1662668D03*
X671631Y1690786D03*
X693672Y32684D03*
X686855Y43701D03*
X679719Y59066D03*
X682946Y69982D03*
X682891Y72642D03*
X688552Y79166D03*
X681895Y82212D03*
X685783Y78768D03*
X684954Y104968D03*
X691058Y131408D03*
X684521Y152482D03*
X688521D03*
X692521D03*
X682264Y224116D03*
X691547Y386834D03*
X688249Y405628D03*
X679862Y409320D03*
X679500Y526834D03*
X691496Y575081D03*
X688078Y675493D03*
X681605Y756766D03*
X681671Y760178D03*
X688647Y756766D03*
X693197Y773564D03*
X688647Y763766D03*
X681605Y767266D03*
X687747Y786950D03*
X693197Y780257D03*
X681455Y795316D03*
X687747Y796989D03*
X693197Y803682D03*
Y810375D03*
Y817068D03*
X681455Y832127D03*
X687747Y833800D03*
Y823761D03*
X693197Y840493D03*
Y847186D03*
X687747Y860572D03*
X693197Y853879D03*
X681455Y868938D03*
X687747Y870611D03*
X693197Y877304D03*
Y883997D03*
Y890690D03*
X681455Y905750D03*
X687747Y897383D03*
Y907423D03*
X693197Y914115D03*
Y920808D03*
X687747Y934194D03*
X693197Y927501D03*
X681455Y942561D03*
X687747Y944234D03*
X693197Y950926D03*
Y957619D03*
Y964312D03*
Y971005D03*
Y977698D03*
Y984391D03*
Y991084D03*
Y997777D03*
Y1004470D03*
Y1031241D03*
Y1037934D03*
Y1044627D03*
Y1051320D03*
Y1058013D03*
Y1068052D03*
Y1074745D03*
X681455Y1089805D03*
X687747Y1081438D03*
Y1091478D03*
X693197Y1098171D03*
Y1104863D03*
X687747Y1118249D03*
X693197Y1111556D03*
X681455Y1126616D03*
X687747Y1128289D03*
X693197Y1134982D03*
Y1141675D03*
Y1148367D03*
X681455Y1163427D03*
X687747Y1155060D03*
Y1165100D03*
X693197Y1171793D03*
Y1178486D03*
X687747Y1191871D03*
X693197Y1185178D03*
X681455Y1200238D03*
X687747Y1201911D03*
X693197Y1208604D03*
Y1215297D03*
Y1221989D03*
X681455Y1237049D03*
X687747Y1238722D03*
Y1228682D03*
X693197Y1245415D03*
Y1252108D03*
X688076Y1297506D03*
Y1305206D03*
Y1300006D03*
Y1302606D03*
X683052Y1352048D03*
Y1349548D03*
X685187Y1368700D03*
Y1363500D03*
Y1366100D03*
X687577Y1425054D03*
X688120Y1519601D03*
X683352Y1530526D03*
Y1526526D03*
X682016Y1539067D03*
X688308Y1631636D03*
X693150Y1640773D03*
X682925Y1657116D03*
X686825Y1647430D03*
X685485Y1682259D03*
X694843Y23788D03*
X701839Y45112D03*
X707608Y69718D03*
X705570Y133760D03*
X704144Y122602D03*
X707243Y123946D03*
X701927Y166535D03*
Y172441D03*
Y178346D03*
Y184252D03*
Y196063D03*
Y190157D03*
Y201968D03*
Y207874D03*
Y213779D03*
Y219685D03*
X696105Y364149D03*
X696500Y529862D03*
X700500Y545862D03*
X704500Y555862D03*
X701496Y580556D03*
X697392Y601686D03*
X697642Y733401D03*
X706756Y776911D03*
X697597Y791970D03*
X706756Y783604D03*
Y807029D03*
Y813722D03*
Y820415D03*
X697597Y828781D03*
X706756Y843840D03*
Y850533D03*
X697597Y865592D03*
X706756Y857226D03*
Y880651D03*
Y887344D03*
Y894037D03*
X697597Y902403D03*
X706756Y924155D03*
Y917462D03*
X697597Y939214D03*
X706756Y930848D03*
Y954273D03*
Y960966D03*
Y967659D03*
Y974352D03*
Y981045D03*
Y987737D03*
Y994430D03*
Y1004470D03*
Y1041281D03*
Y1034588D03*
Y1047974D03*
Y1054667D03*
Y1071399D03*
Y1061360D03*
Y1078092D03*
X697597Y1086458D03*
X706756Y1101517D03*
Y1114903D03*
Y1108210D03*
X697597Y1123269D03*
X706756Y1145021D03*
Y1138328D03*
Y1151714D03*
X697597Y1160080D03*
X706756Y1175139D03*
Y1181832D03*
Y1188525D03*
X697597Y1196891D03*
X706756Y1211950D03*
Y1218643D03*
Y1225336D03*
X697597Y1233702D03*
X706756Y1248761D03*
Y1255454D03*
X697483Y1297506D03*
Y1305206D03*
Y1300006D03*
Y1302606D03*
X701771Y1351988D03*
Y1349488D03*
X699467Y1368710D03*
Y1363510D03*
Y1366110D03*
X703568Y1379476D03*
X699610Y1580523D03*
X706681Y1627361D03*
X705833Y1633568D03*
X706089Y1643411D03*
X705815Y1654918D03*
X703473Y1663001D03*
X695400Y1685887D03*
X705366Y1684064D03*
X723479Y-28508D03*
X716843Y23788D03*
X717342Y57098D03*
X720328Y344824D03*
X711500Y360862D03*
X719500D03*
X711556Y575081D03*
X714583Y587642D03*
X715037Y603278D03*
X713280Y636897D03*
X712319Y654954D03*
X711306Y756766D03*
Y760178D03*
X718348Y756766D03*
X722898Y773564D03*
X718348Y763766D03*
X711306Y767266D03*
X722898Y780257D03*
X717448Y786950D03*
X722898Y803682D03*
X711156Y795316D03*
X717448Y796989D03*
X722898Y810375D03*
Y817068D03*
X717448Y823761D03*
Y833800D03*
X711156Y832127D03*
X722898Y847186D03*
Y840493D03*
Y853879D03*
X717448Y860572D03*
X722898Y877304D03*
X717448Y870611D03*
X711156Y868938D03*
X722898Y883997D03*
Y890690D03*
X717448Y897383D03*
Y907423D03*
X711156Y905750D03*
X722898Y920808D03*
Y914115D03*
Y927501D03*
X717448Y934194D03*
X722898Y950926D03*
X717448Y944234D03*
X711156Y942561D03*
X722898Y957619D03*
Y971005D03*
Y964312D03*
Y984391D03*
Y977698D03*
Y991084D03*
Y997777D03*
Y1004470D03*
Y1031241D03*
Y1037934D03*
Y1044627D03*
Y1051320D03*
Y1058013D03*
Y1068052D03*
Y1074745D03*
X717448Y1081438D03*
X711156Y1089805D03*
X717448Y1091478D03*
X722898Y1098171D03*
Y1104863D03*
Y1111556D03*
X717448Y1118249D03*
Y1128289D03*
X711156Y1126616D03*
X722898Y1134982D03*
Y1148367D03*
Y1141675D03*
X717448Y1165100D03*
X711156Y1163427D03*
X717448Y1155060D03*
X722898Y1178486D03*
Y1171793D03*
Y1185178D03*
X717448Y1191871D03*
X722898Y1208604D03*
X711156Y1200238D03*
X717448Y1201911D03*
X722898Y1215297D03*
Y1221989D03*
X717448Y1228682D03*
Y1238722D03*
X711156Y1237049D03*
X722898Y1252108D03*
Y1245415D03*
X721361Y1297546D03*
X711954D03*
X721361Y1305246D03*
Y1302646D03*
Y1300046D03*
X711954Y1305246D03*
Y1302646D03*
Y1300046D03*
X710221Y1351988D03*
Y1349488D03*
X716707Y1385281D03*
X719137D03*
X720233Y1378525D03*
Y1381482D03*
Y1375418D03*
X722833D03*
X714277Y1385281D03*
X715033Y1378525D03*
X717633D03*
X712433D03*
X717633Y1381482D03*
X715033Y1375418D03*
X717633D03*
X712433D03*
X719186Y1403296D03*
X719137Y1390881D03*
X714277D03*
X716707D03*
X709551Y1406578D03*
X716770Y1531459D03*
X715122Y1533378D03*
X716989Y1537249D03*
X713357Y1535212D03*
X715224Y1539083D03*
X713459Y1540917D03*
X722876Y1611343D03*
X717749Y1654921D03*
X709771Y1654927D03*
X712354Y1682279D03*
X738843Y23788D03*
X728981Y39872D03*
X736791Y39832D03*
X730131Y60757D03*
X736524Y58069D03*
X730958Y71014D03*
X738044Y71526D03*
X727944Y88972D03*
X727986Y101979D03*
X729900Y98090D03*
X727986Y105477D03*
X737624Y98858D03*
X734524Y98758D03*
X735734Y111988D03*
X726720Y574910D03*
X724001Y636790D03*
X726952Y648667D03*
X736457Y776911D03*
Y783604D03*
X727298Y791970D03*
X736457Y807029D03*
Y813722D03*
Y820415D03*
X727298Y828781D03*
X736457Y843840D03*
Y850533D03*
X727298Y865592D03*
X736457Y857226D03*
Y880651D03*
Y887344D03*
Y894037D03*
X727298Y902403D03*
X736457Y924155D03*
Y917462D03*
X727298Y939214D03*
X736457Y930848D03*
Y954273D03*
Y960966D03*
Y967659D03*
Y974352D03*
Y981045D03*
Y987737D03*
Y994430D03*
Y1004470D03*
Y1034588D03*
Y1041281D03*
Y1047974D03*
Y1054667D03*
Y1071399D03*
Y1061360D03*
X727298Y1086458D03*
X736457Y1078092D03*
Y1101517D03*
Y1114903D03*
Y1108210D03*
X727298Y1123269D03*
X736457Y1145021D03*
Y1138328D03*
X727298Y1160080D03*
X736457Y1151714D03*
Y1175139D03*
Y1181832D03*
Y1188525D03*
X727298Y1196891D03*
X736457Y1211950D03*
Y1218643D03*
X727298Y1233702D03*
X736457Y1225336D03*
Y1248761D03*
Y1255454D03*
X735954Y1297546D03*
Y1305246D03*
Y1302646D03*
Y1300046D03*
X727098Y1351977D03*
X730900Y1352131D03*
X727098Y1349077D03*
X730900Y1349231D03*
X734047Y1372880D03*
X731447D03*
X734047Y1370280D03*
Y1367680D03*
X731447D03*
Y1370280D03*
X728348Y1380832D03*
Y1377875D03*
X736280Y1379580D03*
X732797Y1375380D03*
X725333Y1375418D03*
X727777Y1375434D03*
X738230Y1402898D03*
X734925Y1657826D03*
X730302Y1658050D03*
X726302Y1658022D03*
X738370Y1677909D03*
X736001Y1695509D03*
X728454Y1690491D03*
X732434Y1690660D03*
X738550Y1693215D03*
X742841Y39832D03*
X744477Y58373D03*
X744988Y49062D03*
X747488D03*
X752261Y59782D03*
X745131Y69507D03*
X750090Y72820D03*
X745712Y212760D03*
X746705Y315647D03*
X742278Y566667D03*
X753500Y675800D03*
X748049Y756766D03*
X741007D03*
Y760266D03*
X752599Y773564D03*
X741007Y767266D03*
X748049Y763766D03*
X752599Y780257D03*
X747149Y786950D03*
X752599Y803682D03*
X747149Y796989D03*
X740857Y795316D03*
X752599Y810375D03*
Y817068D03*
X747149Y823761D03*
Y833800D03*
X740857Y832127D03*
X752599Y840493D03*
Y847186D03*
Y853879D03*
X747149Y860572D03*
X752599Y877304D03*
X747149Y870611D03*
X740857Y868938D03*
X752599Y890690D03*
Y883997D03*
X747149Y897383D03*
Y907423D03*
X740857Y905750D03*
X752599Y920808D03*
Y914115D03*
X747149Y934194D03*
X752599Y927501D03*
Y950926D03*
X747149Y944234D03*
X740857Y942561D03*
X752599Y957619D03*
Y971005D03*
Y964312D03*
Y984391D03*
Y977698D03*
Y991084D03*
Y997777D03*
Y1004470D03*
Y1031241D03*
Y1037934D03*
Y1044627D03*
Y1051320D03*
Y1058013D03*
Y1068052D03*
Y1074745D03*
X747149Y1081438D03*
X740857Y1089805D03*
X752599Y1098171D03*
Y1104863D03*
X747149Y1091478D03*
X752599Y1111556D03*
X747149Y1118249D03*
Y1128289D03*
X740857Y1126616D03*
X752599Y1134982D03*
Y1148367D03*
Y1141675D03*
X740857Y1163427D03*
X747149Y1165100D03*
Y1155060D03*
X752599Y1178486D03*
Y1171793D03*
Y1185178D03*
X747149Y1191871D03*
X752599Y1208604D03*
X740857Y1200238D03*
X747149Y1201911D03*
X752599Y1215297D03*
Y1221989D03*
X747149Y1228682D03*
Y1238722D03*
X740857Y1237049D03*
X752599Y1252108D03*
Y1245415D03*
X745475Y1297246D03*
Y1304946D03*
Y1302346D03*
Y1299746D03*
X739500Y1352031D03*
Y1349131D03*
X753015Y1381582D03*
Y1378625D03*
Y1375518D03*
X747059Y1385381D03*
X745215Y1378625D03*
X747815D03*
Y1375518D03*
X745215D03*
X750415Y1381582D03*
Y1378625D03*
Y1375518D03*
X749489Y1385381D03*
X751919D03*
X751968Y1403396D03*
X751919Y1390981D03*
X747059D03*
X749489D03*
X739888Y1404849D03*
X743740Y1657327D03*
X743039Y1643326D03*
X760843Y23788D03*
X754621Y74562D03*
X754634Y105288D03*
Y108288D03*
X762173Y123898D03*
X770073Y143438D03*
X756083Y220240D03*
X757464Y284087D03*
X754556Y283976D03*
X755335Y295589D03*
X758959Y319596D03*
X753959Y343790D03*
X766158Y776911D03*
Y783604D03*
X756999Y791970D03*
X766158Y807029D03*
Y813722D03*
Y820415D03*
X756999Y828781D03*
X766158Y843840D03*
Y850533D03*
Y857226D03*
X756999Y865592D03*
X766158Y880651D03*
Y887344D03*
Y894037D03*
X756999Y902403D03*
X766158Y924155D03*
Y917462D03*
X756999Y939214D03*
X766158Y930848D03*
Y954273D03*
Y960966D03*
Y967659D03*
Y974352D03*
Y981045D03*
Y987737D03*
Y994430D03*
Y1004470D03*
Y1041281D03*
Y1034588D03*
Y1047974D03*
Y1054667D03*
Y1071399D03*
Y1061360D03*
X756999Y1086458D03*
X766158Y1078092D03*
Y1101517D03*
Y1114903D03*
Y1108210D03*
X756999Y1123269D03*
X766158Y1145021D03*
Y1138328D03*
X756999Y1160080D03*
X766158Y1151714D03*
Y1175139D03*
Y1181832D03*
Y1188525D03*
X756999Y1196891D03*
X766158Y1211950D03*
Y1218643D03*
Y1225336D03*
X756999Y1233702D03*
X766158Y1248761D03*
Y1255454D03*
X759854Y1297246D03*
Y1304946D03*
Y1302346D03*
Y1299746D03*
X761800Y1352031D03*
Y1349131D03*
X764229Y1372880D03*
X766829D03*
Y1370380D03*
Y1367780D03*
X764229D03*
Y1370380D03*
X761130Y1380932D03*
Y1377975D03*
X755615Y1375518D03*
X758115D03*
X760559Y1375534D03*
X765579Y1375480D03*
X767381Y1676594D03*
X769475Y75360D03*
X771356Y167518D03*
X773221Y296262D03*
X780618Y296345D03*
X779121Y306155D03*
X773944Y312588D03*
X780808Y419865D03*
X777900Y756766D03*
X770708D03*
Y760266D03*
X782300Y773564D03*
X770708Y767266D03*
X777900Y763766D03*
X776850Y786950D03*
X782300Y780257D03*
X776850Y796989D03*
X770558Y795316D03*
X782300Y803682D03*
Y810375D03*
Y817068D03*
X770558Y832127D03*
X776850Y823761D03*
Y833800D03*
X782300Y847186D03*
Y840493D03*
X776850Y860572D03*
X782300Y853879D03*
Y877304D03*
X776850Y870611D03*
X770558Y868938D03*
X782300Y890690D03*
Y883997D03*
X776850Y897383D03*
Y907423D03*
X770558Y905750D03*
X782300Y920808D03*
Y914115D03*
X776850Y934194D03*
X782300Y927501D03*
X776850Y944234D03*
X770558Y942561D03*
X782300Y950926D03*
Y957619D03*
Y971005D03*
Y964312D03*
Y984391D03*
Y977698D03*
Y991084D03*
Y997777D03*
Y1004470D03*
Y1031241D03*
Y1037934D03*
Y1044627D03*
Y1051320D03*
Y1058013D03*
Y1068052D03*
Y1074745D03*
X776850Y1081438D03*
X770558Y1089805D03*
X782300Y1098171D03*
Y1104863D03*
X776850Y1091478D03*
Y1118249D03*
X782300Y1111556D03*
X776850Y1128289D03*
X770558Y1126616D03*
X782300Y1134982D03*
Y1148367D03*
Y1141675D03*
X776850Y1165100D03*
X770558Y1163427D03*
X776850Y1155060D03*
X782300Y1178486D03*
Y1171793D03*
Y1185178D03*
X776850Y1191871D03*
X782300Y1208604D03*
X770558Y1200238D03*
X776850Y1201911D03*
X782300Y1215297D03*
Y1221989D03*
X776850Y1228682D03*
Y1238722D03*
X770558Y1237049D03*
X782300Y1252108D03*
Y1245415D03*
X769521Y1297199D03*
Y1304899D03*
Y1299699D03*
Y1302299D03*
X770990Y1349091D03*
Y1351991D03*
X773069Y1375500D03*
X770469D03*
X776010Y1380750D03*
X787456Y49379D03*
X797594Y282233D03*
X797444Y271469D03*
X795668Y298801D03*
X792488Y377452D03*
X797252Y459344D03*
Y471344D03*
X794425Y541425D03*
X794059Y553559D03*
X791500Y560000D03*
X785000Y563500D03*
X795858Y776911D03*
Y783604D03*
X786700Y791970D03*
X795858Y807029D03*
Y820415D03*
Y813722D03*
X786700Y828781D03*
X795858Y843840D03*
Y850533D03*
X786700Y865592D03*
X795858Y857226D03*
Y880651D03*
Y894037D03*
Y887344D03*
X786700Y902403D03*
X795858Y924155D03*
Y917462D03*
X786700Y939214D03*
X795858Y930848D03*
Y954273D03*
Y960966D03*
Y967659D03*
Y981045D03*
Y974352D03*
Y994430D03*
Y987737D03*
Y1004470D03*
Y1041281D03*
Y1034588D03*
Y1054667D03*
Y1047974D03*
Y1071399D03*
Y1061360D03*
X786700Y1086458D03*
X795858Y1078092D03*
Y1101517D03*
Y1114903D03*
Y1108210D03*
X786700Y1123269D03*
X795858Y1145021D03*
Y1138328D03*
X786700Y1160080D03*
X795858Y1151714D03*
Y1175139D03*
Y1181832D03*
Y1188525D03*
X786700Y1196891D03*
X795858Y1218643D03*
Y1211950D03*
X786700Y1233702D03*
X795858Y1225336D03*
Y1248761D03*
Y1255454D03*
X809456Y49379D03*
X806984Y265653D03*
X798621Y312773D03*
X803264Y330102D03*
X808401Y341670D03*
X811569Y387674D03*
X813175Y422687D03*
X810360Y442079D03*
X802752Y455344D03*
X812500Y504000D03*
X807450Y756766D03*
X800408D03*
Y760266D03*
X812000Y773564D03*
X800408Y767266D03*
X812000Y780257D03*
X806550Y786950D03*
X812000Y803682D03*
X806550Y796989D03*
X800258Y795316D03*
X812000Y817068D03*
Y810375D03*
X800258Y832127D03*
X806550Y833800D03*
Y823761D03*
X812000Y847186D03*
Y840493D03*
X806550Y860572D03*
X812000Y853879D03*
Y877304D03*
X806550Y870611D03*
X800258Y868938D03*
X812000Y890690D03*
Y883997D03*
X806550Y897383D03*
Y907423D03*
X800258Y905750D03*
X812000Y920808D03*
Y914115D03*
Y927501D03*
X806550Y934194D03*
X812000Y950926D03*
X800258Y942561D03*
X806550Y944234D03*
X812000Y957619D03*
Y971005D03*
Y964312D03*
Y984391D03*
Y977698D03*
Y997777D03*
Y991084D03*
Y1004470D03*
Y1044627D03*
Y1037934D03*
Y1031241D03*
Y1058013D03*
Y1051320D03*
Y1068052D03*
Y1074745D03*
X806550Y1081438D03*
X800258Y1089805D03*
X812000Y1098171D03*
Y1104863D03*
X806550Y1091478D03*
X812000Y1111556D03*
X806550Y1118249D03*
Y1128289D03*
X800258Y1126616D03*
X812000Y1134982D03*
Y1148367D03*
Y1141675D03*
X806550Y1165100D03*
X800258Y1163427D03*
X806550Y1155060D03*
X812000Y1178486D03*
Y1171793D03*
Y1185178D03*
X806550Y1191871D03*
X812000Y1208604D03*
X806550Y1201911D03*
X800258Y1200238D03*
X812000Y1221989D03*
Y1215297D03*
X806550Y1228682D03*
Y1238722D03*
X800258Y1237049D03*
X812000Y1245415D03*
Y1252108D03*
X822699Y56712D03*
X821119Y134632D03*
X825699Y139062D03*
X816322Y284369D03*
X826665Y423425D03*
X817426Y487232D03*
X824500Y514500D03*
X817441Y517941D03*
X822559Y530876D03*
X826552Y543612D03*
X823777Y560988D03*
X816400Y828781D03*
Y865592D03*
Y902403D03*
Y939214D03*
Y1086458D03*
Y1123269D03*
Y1160080D03*
Y1196891D03*
Y1233702D03*
X826112Y1269546D03*
X833407Y-26181D03*
X836660Y-26167D03*
Y-16167D03*
X833407Y-16181D03*
X839700Y-14972D03*
X833422Y-13666D03*
X836675Y-13652D03*
X833412Y-19948D03*
X836674D03*
X836675Y-23652D03*
X833422Y-23666D03*
X839700Y-24972D03*
X833412Y52D03*
X836674D03*
X833412Y-9948D03*
X836674D03*
X836675Y-3652D03*
X833422Y-3666D03*
X839700Y-4972D03*
X833407Y-6181D03*
X836660Y-6167D03*
X836675Y16348D03*
X833422Y16334D03*
X839700Y15028D03*
X833407Y13819D03*
X836660Y13833D03*
X836674Y10052D03*
X833412D03*
X836675Y6348D03*
X833422Y6334D03*
X839700Y5028D03*
X833407Y3819D03*
X836660Y3833D03*
X836659Y24250D03*
X836674Y26765D03*
X833406Y24236D03*
X839699Y25445D03*
X833421Y26751D03*
X833376Y19206D03*
X833391Y21721D03*
X831456Y49379D03*
X836127Y62681D03*
X837792Y85186D03*
X831298Y104206D03*
X834616Y94324D03*
X842865Y110296D03*
X830340Y228143D03*
X832525Y268579D03*
X829572Y296511D03*
X840288Y287593D03*
X829167Y288063D03*
X832686Y331028D03*
X836840Y382003D03*
X841862Y390441D03*
X834430Y434634D03*
X834251Y459578D03*
X835425Y477890D03*
X830743Y500740D03*
X831756Y901318D03*
X835554Y1281324D03*
X835682Y1285472D03*
X836670Y1291355D03*
X836587Y1295333D03*
X842500Y1310000D03*
Y1306000D03*
Y1302000D03*
X834017Y1333584D03*
X834071Y1342457D03*
X839188Y1348937D03*
X841203Y1361376D03*
X853456Y49379D03*
X854108Y91232D03*
X851895Y160141D03*
X853800Y265057D03*
X847939Y265092D03*
X854334Y276117D03*
X854225Y280027D03*
Y283527D03*
X857334Y276117D03*
X852780Y291559D03*
X852801Y288562D03*
X853201Y297462D03*
X856701Y304862D03*
X846275Y335575D03*
X849750Y401280D03*
X852240Y470946D03*
X849126Y530138D03*
X845126D03*
X848660Y651127D03*
X846725Y1269785D03*
X861351Y61672D03*
X858528Y262382D03*
X860834Y276817D03*
X863934Y276917D03*
X862044Y290047D03*
X862075Y398537D03*
X872020Y413300D03*
X867590Y642420D03*
X864700Y836100D03*
X859446Y1284288D03*
X875345Y51595D03*
X877462Y139540D03*
X878221Y192055D03*
X880944Y283347D03*
Y286347D03*
X875447Y301500D03*
X884740Y316000D03*
X874500Y328000D03*
X873884Y453383D03*
X886707Y1254742D03*
Y1251742D03*
X881807Y1248920D03*
Y1245920D03*
X881937Y1251857D03*
X877480Y1248844D03*
X886707Y1257742D03*
X885000Y1307500D03*
X877000Y1340241D03*
X884462Y1446974D03*
X876044Y1444317D03*
X898720Y145206D03*
X888560Y469527D03*
X902376Y594657D03*
X903556Y614062D03*
X899678Y601043D03*
X897824Y909093D03*
X891648Y1137843D03*
X900723Y1146553D03*
X896107Y1254742D03*
Y1251742D03*
X896907Y1245920D03*
Y1248920D03*
X896107Y1257742D03*
X917386Y179500D03*
Y177000D03*
Y169500D03*
Y172000D03*
Y174500D03*
Y167000D03*
X909298Y195925D03*
X909161Y203012D03*
X909320Y210098D03*
Y217185D03*
Y224271D03*
Y231358D03*
X914575Y560027D03*
X906597Y579695D03*
X907035Y590172D03*
X906597Y628426D03*
X906734Y619373D03*
X906570Y663930D03*
X906387Y818471D03*
X903941Y874000D03*
X917622Y887545D03*
X909000Y909000D03*
X905000D03*
X904719Y921792D03*
X911500Y931000D03*
X908500Y927500D03*
X909890Y950217D03*
X910066Y960332D03*
X909203Y970709D03*
X916763Y972343D03*
X908799Y985291D03*
X910707Y1254742D03*
Y1251742D03*
X905007Y1248920D03*
Y1245920D03*
X905074Y1252177D03*
X910707Y1257742D03*
X920720Y145206D03*
X919886Y167000D03*
Y169500D03*
Y172000D03*
Y174500D03*
Y177000D03*
Y179500D03*
X927134Y189386D03*
X925321Y203399D03*
X926983Y604751D03*
X927127Y619251D03*
X930926Y664791D03*
X923916Y843990D03*
X918500Y856925D03*
X930925Y860925D03*
X929603Y889000D03*
X931948Y891397D03*
X919916Y908916D03*
X920276Y900554D03*
X931877Y918168D03*
X928535Y913454D03*
X920409Y918274D03*
X918000Y928000D03*
X926062Y938727D03*
X926004Y952716D03*
X925200Y1110443D03*
Y1107843D03*
Y1117443D03*
Y1114843D03*
Y1124443D03*
Y1121843D03*
Y1131443D03*
Y1128843D03*
X920107Y1251742D03*
Y1254742D03*
Y1248920D03*
Y1245920D03*
Y1257742D03*
X924000Y1310000D03*
X920738Y1321363D03*
X927869Y1317417D03*
X923680Y1339520D03*
X919758Y1348990D03*
X931798Y1660762D03*
X923798D03*
X945006Y593609D03*
X935649Y590751D03*
X939391Y600571D03*
X946366Y668811D03*
X940391Y859947D03*
X944057Y882886D03*
X940514Y918134D03*
X933021Y933979D03*
X939670Y945169D03*
X942924Y982547D03*
X943135Y977129D03*
X938507Y1137843D03*
X945691Y1254742D03*
Y1251742D03*
X940791Y1248920D03*
Y1245920D03*
X940921Y1251857D03*
X936464Y1248844D03*
X945691Y1257742D03*
X938000Y1309500D03*
Y1301500D03*
Y1304500D03*
X933586Y1325501D03*
X933041Y1315920D03*
X944406Y1532791D03*
X939798Y1660762D03*
X955529Y614017D03*
X951839Y812730D03*
X958051Y859384D03*
X952425Y876575D03*
X948060Y891468D03*
X951367Y913648D03*
X951500Y930925D03*
X955091Y1254742D03*
Y1251742D03*
X955891Y1245920D03*
Y1248920D03*
X955000Y1267000D03*
X955091Y1257742D03*
X955000Y1271000D03*
Y1275000D03*
Y1279000D03*
X960518Y1656185D03*
X957758D03*
X957848Y1659375D03*
X960608D03*
X960558Y1662015D03*
X957798D03*
X947798Y1660762D03*
X964720Y145206D03*
X975689Y156950D03*
Y153950D03*
X971192Y219589D03*
X968692D03*
X973616Y317648D03*
X963134Y882936D03*
X968919Y1116177D03*
Y1118777D03*
Y1109177D03*
Y1111777D03*
X968800Y1130046D03*
Y1132646D03*
X968919Y1123177D03*
Y1125777D03*
X969691Y1254742D03*
Y1251742D03*
X963991Y1248920D03*
Y1245920D03*
X964058Y1252177D03*
X969691Y1257742D03*
X975000Y1307500D03*
X967500Y1340241D03*
X963120Y1520080D03*
Y1523080D03*
Y1526080D03*
X976858Y1656185D03*
X976898Y1662015D03*
X976948Y1659375D03*
X986720Y145206D03*
X988593Y189347D03*
X981445Y185389D03*
X982455Y264781D03*
Y275443D03*
X989227Y389311D03*
X992037Y485369D03*
X979091Y1251742D03*
Y1254742D03*
Y1248920D03*
Y1245920D03*
Y1257742D03*
X986486Y1523080D03*
Y1520080D03*
Y1526080D03*
X985318Y1656105D03*
X988078D03*
X979618Y1656185D03*
X985358Y1661935D03*
X988118D03*
X985408Y1659295D03*
X988168D03*
X979658Y1662015D03*
X979708Y1659375D03*
X995189Y263340D03*
Y274002D03*
X992915Y280389D03*
X1007083Y363461D03*
X996232Y424440D03*
X999304Y1282574D03*
Y1289215D03*
X999303Y1285693D03*
X1004418Y1656105D03*
X1007178D03*
X1004508Y1659295D03*
X1004458Y1661935D03*
X1008720Y145206D03*
X1020661Y146580D03*
X1023221Y191574D03*
X1019803Y218099D03*
X1017870Y294386D03*
X1009618Y396125D03*
X1021425Y404925D03*
X1013365Y433426D03*
X1008789Y488642D03*
Y493655D03*
X1012211Y547574D03*
X1015061D03*
X1015961Y554432D03*
X1007703Y759012D03*
X1007587Y800384D03*
Y802884D03*
Y811352D03*
Y813852D03*
Y822252D03*
Y824752D03*
Y833356D03*
Y835856D03*
Y844256D03*
X1021908Y1289124D03*
X1019314Y1289159D03*
X1017069Y1290346D03*
X1013500Y1312500D03*
X1013000Y1306500D03*
X1013500Y1325500D03*
X1011500Y1335000D03*
X1013500Y1344500D03*
X1009852Y1523080D03*
Y1520080D03*
Y1526080D03*
X1007268Y1659295D03*
X1007218Y1661935D03*
X1023187Y146580D03*
X1027724Y397726D03*
X1030525Y391362D03*
X1027760Y451832D03*
X1022461Y558932D03*
X1027579D03*
X1032579Y559934D03*
X1025493Y768719D03*
X1035645Y773582D03*
X1033218Y1523080D03*
Y1520080D03*
Y1526080D03*
X1033798Y1656675D03*
X1033748Y1659315D03*
X1040199Y49379D03*
X1040891Y406586D03*
X1045100Y427059D03*
X1045015Y444404D03*
X1041254Y523874D03*
X1043180Y547027D03*
X1040890Y735717D03*
X1050015Y756765D03*
Y760265D03*
X1045465Y776910D03*
X1050015Y767265D03*
X1045465Y783603D03*
X1041065Y795315D03*
X1045465Y807028D03*
Y813721D03*
Y820414D03*
X1041065Y832126D03*
X1045465Y850532D03*
Y843839D03*
Y857225D03*
X1041065Y868937D03*
X1045465Y880650D03*
Y887343D03*
Y894036D03*
X1041065Y905749D03*
X1045465Y917461D03*
Y924154D03*
Y930847D03*
X1041065Y942560D03*
X1045465Y954272D03*
Y967658D03*
Y960965D03*
Y974351D03*
Y981044D03*
Y987736D03*
Y994429D03*
Y1004469D03*
Y1041280D03*
Y1034587D03*
Y1047973D03*
Y1054666D03*
Y1061359D03*
Y1071398D03*
Y1078091D03*
X1041065Y1089804D03*
X1045465Y1101516D03*
Y1108209D03*
Y1114902D03*
X1041065Y1126615D03*
X1045465Y1138327D03*
Y1145020D03*
Y1151713D03*
X1041065Y1163426D03*
X1045465Y1175138D03*
Y1188524D03*
Y1181831D03*
X1041065Y1200237D03*
X1045465Y1211949D03*
Y1218642D03*
X1041065Y1237048D03*
X1045465Y1225335D03*
Y1248760D03*
Y1255453D03*
X1048684Y1350724D03*
X1051684D03*
X1050866Y1659548D03*
X1062199Y49379D03*
X1061456Y406560D03*
X1063614Y733409D03*
X1057057Y756765D03*
X1061607Y773563D03*
X1057057Y763765D03*
X1057207Y791969D03*
X1056157Y786949D03*
X1061607Y780256D03*
Y803681D03*
X1056157Y796988D03*
X1061607Y810374D03*
Y817067D03*
X1056157Y823760D03*
Y833799D03*
X1057207Y828780D03*
X1061607Y847185D03*
Y840492D03*
Y853878D03*
X1056157Y860571D03*
X1057207Y865591D03*
X1056157Y870610D03*
X1061607Y877303D03*
Y883996D03*
Y890689D03*
X1056157Y907422D03*
Y897382D03*
X1057207Y902402D03*
X1061607Y914114D03*
Y920807D03*
Y927500D03*
X1056157Y934193D03*
X1057207Y939213D03*
X1061607Y950925D03*
X1056157Y944233D03*
X1061607Y964311D03*
Y971004D03*
Y957618D03*
Y977697D03*
Y984390D03*
Y991083D03*
Y997776D03*
Y1004469D03*
Y1037933D03*
Y1044626D03*
Y1031240D03*
Y1051319D03*
Y1058012D03*
Y1074744D03*
Y1068051D03*
X1057207Y1086457D03*
X1056157Y1081437D03*
Y1091477D03*
X1061607Y1098170D03*
Y1104862D03*
X1056157Y1118248D03*
X1061607Y1111555D03*
Y1134981D03*
X1057207Y1123268D03*
X1056157Y1128288D03*
X1061607Y1141674D03*
Y1148366D03*
X1056157Y1155059D03*
Y1165099D03*
X1057207Y1160079D03*
X1061607Y1171792D03*
Y1178485D03*
X1056157Y1191870D03*
X1061607Y1185177D03*
X1056157Y1201910D03*
X1057207Y1196890D03*
X1061607Y1208603D03*
Y1215296D03*
Y1221988D03*
X1056157Y1238721D03*
X1057207Y1233701D03*
X1056157Y1228681D03*
X1061607Y1245414D03*
Y1252107D03*
X1060684Y1350724D03*
X1057684D03*
X1054684D03*
X1056584Y1523080D03*
Y1520080D03*
Y1526080D03*
X1063751Y1653834D03*
X1064221Y1662726D03*
X1068221Y1662778D03*
X1068827Y389734D03*
X1074800Y391262D03*
X1077418Y411322D03*
Y416763D03*
Y421922D03*
X1081133Y461516D03*
X1071239Y479655D03*
X1081632Y648854D03*
X1079716Y756765D03*
Y760265D03*
Y767265D03*
X1075166Y776910D03*
Y783603D03*
X1070766Y795315D03*
X1075166Y807028D03*
Y813721D03*
Y820414D03*
X1070766Y832126D03*
X1075166Y850532D03*
Y843839D03*
Y857225D03*
X1070766Y868937D03*
X1075166Y880650D03*
Y887343D03*
Y894036D03*
X1070766Y905749D03*
X1075166Y917461D03*
Y924154D03*
Y930847D03*
X1070766Y942560D03*
X1075166Y954272D03*
Y967658D03*
Y960965D03*
Y974351D03*
Y981044D03*
Y987736D03*
Y994429D03*
Y1004469D03*
Y1034587D03*
Y1041280D03*
Y1047973D03*
Y1054666D03*
Y1061359D03*
Y1071398D03*
Y1078091D03*
X1070766Y1089804D03*
X1075166Y1101516D03*
Y1108209D03*
Y1114902D03*
X1070766Y1126615D03*
X1075166Y1138327D03*
Y1145020D03*
Y1151713D03*
X1070766Y1163426D03*
X1075166Y1175138D03*
Y1188524D03*
Y1181831D03*
X1070766Y1200237D03*
X1075166Y1211949D03*
Y1218642D03*
X1070766Y1237048D03*
X1075166Y1225335D03*
Y1248760D03*
Y1255453D03*
X1070949Y1337752D03*
X1067929Y1337702D03*
X1079215Y1357390D03*
X1076615D03*
X1071908Y1361660D03*
X1080889Y1367253D03*
X1076615Y1360497D03*
X1079215D03*
X1078459Y1367253D03*
Y1372853D03*
X1080889D03*
X1073733Y1388198D03*
X1068094Y1654099D03*
X1084199Y49379D03*
X1086936Y370532D03*
X1083583Y395195D03*
X1093722Y427960D03*
X1087000Y477500D03*
X1096473Y484391D03*
Y489391D03*
X1088730Y509362D03*
X1086758Y756765D03*
X1091308Y773563D03*
X1086758Y763765D03*
X1086908Y791969D03*
X1091308Y780256D03*
X1085858Y786949D03*
X1091308Y803681D03*
X1085858Y796988D03*
X1091308Y810374D03*
Y817067D03*
X1085858Y823760D03*
Y833799D03*
X1086908Y828780D03*
X1091308Y840492D03*
Y847185D03*
Y853878D03*
X1085858Y860571D03*
X1086908Y865591D03*
X1085858Y870610D03*
X1091308Y877303D03*
Y883996D03*
Y890689D03*
X1085858Y907422D03*
Y897382D03*
X1086908Y902402D03*
X1091308Y914114D03*
Y920807D03*
X1085858Y934193D03*
X1091308Y927500D03*
X1086908Y939213D03*
X1085858Y944233D03*
X1091308Y950925D03*
Y964311D03*
Y971004D03*
Y957618D03*
Y977697D03*
Y984390D03*
Y991083D03*
Y997776D03*
Y1004469D03*
Y1031240D03*
Y1037933D03*
Y1044626D03*
Y1051319D03*
Y1058012D03*
Y1074744D03*
Y1068051D03*
X1086908Y1086457D03*
X1085858Y1081437D03*
Y1091477D03*
X1091308Y1098170D03*
Y1104862D03*
X1085858Y1118248D03*
X1091308Y1111555D03*
Y1134981D03*
X1086908Y1123268D03*
X1085858Y1128288D03*
X1091308Y1141674D03*
Y1148366D03*
X1085858Y1155059D03*
Y1165099D03*
X1086908Y1160079D03*
X1091308Y1171792D03*
Y1178485D03*
X1085858Y1191870D03*
X1091308Y1185177D03*
X1085858Y1201910D03*
X1086908Y1196890D03*
X1091308Y1208603D03*
Y1215296D03*
Y1221988D03*
X1085858Y1238721D03*
Y1228681D03*
X1086908Y1233701D03*
X1091308Y1245414D03*
Y1252107D03*
X1095809Y1337824D03*
X1087015Y1357390D03*
X1095629Y1352252D03*
Y1349652D03*
Y1354852D03*
X1089515Y1357390D03*
X1091959Y1357406D03*
X1084415Y1357390D03*
X1081815D03*
X1092905Y1363394D03*
Y1360437D03*
X1083319Y1367253D03*
X1081815Y1360497D03*
X1084415D03*
X1081815Y1363454D03*
X1084415D03*
X1083319Y1372853D03*
X1083368Y1385268D03*
X1096469Y1643468D03*
X1090143Y1643625D03*
X1091026Y1653031D03*
X1092030Y1720841D03*
X1106199Y49379D03*
X1101942Y395361D03*
X1109416Y756765D03*
Y760265D03*
Y767265D03*
X1104866Y776910D03*
Y783603D03*
X1100466Y795315D03*
X1104866Y807028D03*
Y813721D03*
Y820414D03*
X1100466Y832126D03*
X1104866Y850532D03*
Y843839D03*
Y857225D03*
X1100466Y868937D03*
X1104866Y880650D03*
Y887343D03*
Y894036D03*
X1100466Y905749D03*
X1104866Y917461D03*
Y924154D03*
Y930847D03*
X1100466Y942560D03*
X1104866Y954272D03*
Y967658D03*
Y960965D03*
Y974351D03*
Y981044D03*
Y987736D03*
Y994429D03*
Y1004469D03*
Y1034587D03*
Y1041280D03*
Y1047973D03*
Y1054666D03*
Y1071398D03*
Y1061359D03*
Y1078091D03*
X1100466Y1089804D03*
X1104866Y1101516D03*
Y1108209D03*
Y1114902D03*
X1100466Y1126615D03*
X1104866Y1138327D03*
Y1145020D03*
Y1151713D03*
X1100466Y1163426D03*
X1104866Y1175138D03*
Y1188524D03*
Y1181831D03*
X1100466Y1200237D03*
X1104866Y1211949D03*
Y1218642D03*
X1100466Y1237048D03*
X1104866Y1225335D03*
Y1248760D03*
Y1255453D03*
X1103529Y1337792D03*
X1109289Y1337752D03*
X1098409Y1337824D03*
X1109215Y1357390D03*
X1098229Y1352252D03*
Y1349652D03*
X1096979Y1357352D03*
X1098229Y1354852D03*
X1104448Y1361680D03*
X1109215Y1360497D03*
X1111059Y1367253D03*
Y1372853D03*
X1103888Y1386721D03*
X1102230Y1384770D03*
X1105000Y1682132D03*
X1109521Y1724109D03*
X1113943Y452055D03*
X1116458Y756765D03*
X1121008Y773563D03*
X1116459Y763765D03*
X1116608Y791969D03*
X1121008Y780256D03*
X1115558Y786949D03*
X1121008Y803681D03*
X1115558Y796988D03*
X1121008Y810374D03*
Y817067D03*
X1115558Y823760D03*
Y833799D03*
X1116608Y828780D03*
X1121008Y847185D03*
Y840492D03*
Y853878D03*
X1115558Y860571D03*
X1116608Y865591D03*
X1115558Y870610D03*
X1121008Y877303D03*
Y883996D03*
Y890689D03*
X1115558Y907422D03*
Y897382D03*
X1116608Y902402D03*
X1121008Y914114D03*
Y920807D03*
X1115558Y934193D03*
X1121008Y927500D03*
X1116608Y939213D03*
X1115558Y944233D03*
X1121008Y950925D03*
Y964311D03*
Y971004D03*
Y957618D03*
Y977697D03*
Y984390D03*
Y991083D03*
Y997776D03*
Y1004469D03*
Y1031240D03*
Y1037933D03*
Y1044626D03*
Y1051319D03*
Y1058012D03*
Y1074744D03*
Y1068051D03*
X1116608Y1086457D03*
X1115558Y1081437D03*
Y1091477D03*
X1121008Y1098170D03*
Y1104862D03*
X1115558Y1118248D03*
X1121008Y1111555D03*
Y1134981D03*
X1116608Y1123268D03*
X1115558Y1128288D03*
X1121008Y1141674D03*
Y1148366D03*
X1115558Y1155059D03*
Y1165099D03*
X1116608Y1160079D03*
X1121008Y1171792D03*
Y1178485D03*
X1115558Y1191870D03*
X1121008Y1185177D03*
X1115558Y1201910D03*
X1116608Y1196890D03*
X1121008Y1208603D03*
Y1215296D03*
Y1221988D03*
X1115558Y1238721D03*
Y1228681D03*
X1116608Y1233701D03*
X1121008Y1245414D03*
Y1252107D03*
X1119615Y1357390D03*
X1122115D03*
X1124559Y1357406D03*
X1117015Y1357390D03*
X1111815D03*
X1114415D03*
X1117015Y1363454D03*
Y1360497D03*
X1115919Y1372853D03*
X1125505Y1363394D03*
Y1360437D03*
X1115919Y1367253D03*
X1113489D03*
X1114415Y1363454D03*
X1111815Y1360497D03*
X1114415D03*
X1113489Y1372853D03*
X1115968Y1385268D03*
X1117946Y1467955D03*
X1117828Y1473091D03*
X1118326Y1594118D03*
X1118004Y1584908D03*
X1113785Y1601462D03*
X1117263Y1601526D03*
X1115394Y1620306D03*
X1120376Y1641684D03*
X1125487Y1641754D03*
X1125771Y1652189D03*
X1120595Y1652037D03*
X1120200Y1646597D03*
X1116000Y1671029D03*
X1125732Y1666072D03*
X1120303Y1682055D03*
X1113948Y1714244D03*
X1128199Y49379D03*
X1142830Y53186D03*
X1139200Y380533D03*
Y385698D03*
X1127471Y404788D03*
X1132387Y615658D03*
X1139117Y756765D03*
Y760265D03*
Y767265D03*
X1134567Y776910D03*
Y783603D03*
X1130167Y795315D03*
X1134567Y807028D03*
Y813721D03*
Y820414D03*
X1130167Y832126D03*
X1134567Y850532D03*
Y843839D03*
Y857225D03*
X1130167Y868937D03*
X1134567Y880650D03*
Y887343D03*
Y894036D03*
X1130167Y905749D03*
X1134567Y917461D03*
Y924154D03*
Y930847D03*
X1130167Y942560D03*
X1134567Y954272D03*
Y967658D03*
Y960965D03*
Y974351D03*
Y981044D03*
Y987736D03*
Y994429D03*
Y1004469D03*
Y1034587D03*
Y1041280D03*
Y1047973D03*
Y1054666D03*
Y1061359D03*
Y1071398D03*
X1130167Y1089804D03*
X1134567Y1078091D03*
Y1101516D03*
Y1108209D03*
Y1114902D03*
X1130167Y1126615D03*
X1134567Y1138327D03*
Y1145020D03*
X1130167Y1163426D03*
X1134567Y1151713D03*
Y1175138D03*
Y1188524D03*
Y1181831D03*
X1130167Y1200237D03*
X1134567Y1211949D03*
Y1218642D03*
X1130167Y1237048D03*
X1134567Y1225335D03*
Y1248760D03*
Y1255453D03*
X1136219Y1337794D03*
X1133619D03*
X1130829Y1352252D03*
Y1349652D03*
Y1354852D03*
X1128229Y1352252D03*
Y1349652D03*
X1129579Y1357352D03*
X1128229Y1354852D03*
X1137218Y1361660D03*
X1136588Y1386721D03*
X1134930Y1384770D03*
X1137846Y1453487D03*
X1135043Y1553371D03*
X1137523Y1579453D03*
X1136173Y1573638D03*
X1131790Y1597984D03*
X1131832Y1607245D03*
X1132168Y1620860D03*
X1138752Y1624627D03*
X1130772Y1641753D03*
X1130684Y1646949D03*
X1130245Y1652189D03*
X1140117Y1671421D03*
X1132209Y1672033D03*
X1129230Y1666174D03*
X1137492Y1685240D03*
X1128934Y1688600D03*
X1150199Y49379D03*
X1155577Y73939D03*
X1147813Y492319D03*
X1146159Y756765D03*
X1150709Y773563D03*
X1146160Y763765D03*
X1146309Y791969D03*
X1145259Y786949D03*
X1150709Y780256D03*
X1145259Y796988D03*
X1150709Y803681D03*
Y810374D03*
Y817067D03*
X1146309Y828780D03*
X1145259Y823760D03*
Y833799D03*
X1150709Y840492D03*
Y847185D03*
X1146309Y865591D03*
X1145259Y860571D03*
X1150709Y853878D03*
X1145259Y870610D03*
X1150709Y877303D03*
Y883996D03*
Y890689D03*
X1145259Y907422D03*
X1146309Y902402D03*
X1145259Y897382D03*
X1150709Y914114D03*
Y920807D03*
X1145259Y934193D03*
X1146309Y939213D03*
X1150709Y927500D03*
X1145259Y944233D03*
X1150709Y950925D03*
Y964311D03*
Y971004D03*
Y957618D03*
Y977697D03*
Y984390D03*
Y991083D03*
Y997776D03*
Y1004469D03*
Y1031240D03*
Y1037933D03*
Y1044626D03*
Y1051319D03*
Y1058012D03*
Y1074744D03*
Y1068051D03*
X1146309Y1086457D03*
X1145259Y1081437D03*
Y1091477D03*
X1150709Y1098170D03*
Y1104862D03*
X1145259Y1118248D03*
X1150709Y1111555D03*
Y1134981D03*
X1146309Y1123268D03*
X1145259Y1128288D03*
X1150709Y1141674D03*
Y1148366D03*
X1145259Y1155059D03*
X1146309Y1160079D03*
X1145259Y1165099D03*
X1150709Y1171792D03*
Y1178485D03*
X1145259Y1191870D03*
X1150709Y1185177D03*
X1145259Y1201910D03*
X1146309Y1196890D03*
X1150709Y1208603D03*
Y1215296D03*
Y1221988D03*
X1145259Y1238721D03*
X1146309Y1233701D03*
X1145259Y1228681D03*
X1150709Y1245414D03*
Y1252107D03*
X1154839Y1337834D03*
X1145819D03*
X1143219D03*
X1152315Y1357390D03*
X1154815D03*
X1147115D03*
X1149715D03*
X1141915D03*
X1144515D03*
X1147115Y1360497D03*
X1149715Y1363454D03*
Y1360497D03*
X1147115Y1363454D03*
X1146189Y1372853D03*
X1148619D03*
Y1367253D03*
X1146189D03*
X1141915Y1360497D03*
X1144515D03*
X1143759Y1367253D03*
Y1372853D03*
X1148668Y1385268D03*
X1150458Y1433146D03*
X1144118Y1449628D03*
X1151384Y1556029D03*
X1143063Y1580334D03*
X1152186Y1570567D03*
X1149278Y1589453D03*
X1145060Y1588837D03*
X1141645Y1640017D03*
X1146316Y1649422D03*
X1143127Y1649068D03*
X1144107Y1671118D03*
X1146477Y1658441D03*
X1168687Y74202D03*
X1163113Y481691D03*
X1165589Y569118D03*
X1168818Y756765D03*
Y760265D03*
X1164268Y776910D03*
X1168818Y767265D03*
X1164268Y783603D03*
X1159868Y795315D03*
X1164268Y807028D03*
Y820414D03*
Y813721D03*
X1159868Y832126D03*
X1164268Y850532D03*
Y843839D03*
Y857225D03*
X1159868Y868937D03*
X1164268Y880650D03*
Y887343D03*
Y894036D03*
X1159868Y905749D03*
X1164268Y917461D03*
Y924154D03*
Y930847D03*
X1159868Y942560D03*
X1164268Y954272D03*
Y960965D03*
Y967658D03*
Y974351D03*
Y981044D03*
Y987736D03*
Y994429D03*
Y1004469D03*
Y1034587D03*
Y1041280D03*
Y1047973D03*
Y1054666D03*
Y1061359D03*
Y1071398D03*
X1159868Y1089804D03*
X1164268Y1078091D03*
Y1101516D03*
Y1108209D03*
Y1114902D03*
X1159868Y1126615D03*
X1164268Y1138327D03*
Y1145020D03*
X1159868Y1163426D03*
X1164268Y1151713D03*
Y1175138D03*
Y1181831D03*
Y1188524D03*
X1159868Y1200237D03*
X1164268Y1211949D03*
Y1218642D03*
X1159868Y1237048D03*
X1164268Y1225335D03*
Y1248760D03*
Y1255453D03*
X1167509Y1337884D03*
X1164909D03*
X1157439Y1337834D03*
X1160929Y1352252D03*
X1163529D03*
X1160929Y1349652D03*
X1163529D03*
X1162279Y1357352D03*
X1163529Y1354852D03*
X1157259Y1357406D03*
X1170138Y1361800D03*
X1158205Y1363394D03*
Y1360437D03*
X1169488Y1386721D03*
X1167830Y1384770D03*
X1161311Y1548204D03*
X1172523Y1573250D03*
X1160031Y1591163D03*
X1162144Y1658042D03*
X1159741Y1669759D03*
X1169187Y1687117D03*
X1174958Y-24648D03*
Y5352D03*
Y15352D03*
X1177429Y89556D03*
Y93556D03*
X1185952Y432202D03*
Y440202D03*
Y448202D03*
X1185707Y465272D03*
Y460202D03*
Y470392D03*
X1185117Y571807D03*
X1181445Y592868D03*
X1175860Y756765D03*
X1180410Y773563D03*
X1175860Y763765D03*
X1176010Y791969D03*
X1180410Y780256D03*
X1174960Y786949D03*
X1180410Y803681D03*
X1174960Y796988D03*
X1180410Y817067D03*
Y810374D03*
X1176010Y828780D03*
X1174960Y833799D03*
Y823760D03*
X1180410Y847185D03*
Y840492D03*
X1176010Y865591D03*
X1180410Y853878D03*
X1174960Y860571D03*
X1180410Y877303D03*
X1174960Y870610D03*
X1180410Y890689D03*
Y883996D03*
X1176010Y902402D03*
X1174960Y897382D03*
Y907422D03*
X1180410Y914114D03*
Y920807D03*
X1176010Y939213D03*
X1174960Y934193D03*
X1180410Y927500D03*
X1174960Y944233D03*
X1180410Y950925D03*
Y957618D03*
Y964311D03*
Y971004D03*
Y977697D03*
Y984390D03*
Y991083D03*
Y997776D03*
Y1004469D03*
Y1031240D03*
Y1037933D03*
Y1044626D03*
Y1051319D03*
Y1058012D03*
Y1068051D03*
Y1074744D03*
X1176010Y1086457D03*
X1174960Y1081437D03*
Y1091477D03*
X1180410Y1098170D03*
Y1104862D03*
X1174960Y1118248D03*
X1180410Y1111555D03*
X1176010Y1123268D03*
X1174960Y1128288D03*
X1180410Y1134981D03*
Y1141674D03*
Y1148366D03*
X1176010Y1160079D03*
X1174960Y1155059D03*
Y1165099D03*
X1180410Y1171792D03*
Y1178485D03*
X1174960Y1191870D03*
X1180410Y1185177D03*
X1176010Y1196890D03*
X1174960Y1201910D03*
X1180410Y1208603D03*
Y1215296D03*
Y1221988D03*
X1176010Y1233701D03*
X1174960Y1238721D03*
Y1228681D03*
X1180410Y1245414D03*
Y1252107D03*
X1182615Y1357390D03*
X1185215D03*
X1177415D03*
X1174815D03*
X1180015D03*
X1182615Y1363454D03*
Y1360497D03*
X1180015Y1363454D03*
X1174815Y1360497D03*
X1177415D03*
X1180015D03*
X1176659Y1367253D03*
Y1372853D03*
X1179089D03*
X1181519D03*
Y1367253D03*
X1179089D03*
X1181568Y1385268D03*
X1185000Y1396500D03*
Y1401000D03*
X1184100Y1410000D03*
X1185000Y1405500D03*
X1178400Y1433000D03*
X1181324Y1485895D03*
X1183234Y1483295D03*
Y1488495D03*
X1181314Y1492995D03*
X1176534D03*
X1174624Y1495595D03*
X1181314Y1498195D03*
X1176534D03*
X1180047Y1533247D03*
X1181853Y1561731D03*
X1172523Y1562350D03*
X1179187Y1666429D03*
X1175454Y1668046D03*
X1178932Y1686698D03*
X1185676Y1697249D03*
X1194199Y49379D03*
X1198694Y57015D03*
X1191488Y87125D03*
Y91125D03*
X1200518Y100875D03*
X1189701Y173187D03*
X1201157Y431875D03*
X1189540Y481691D03*
X1188192Y589263D03*
X1191646Y589567D03*
X1195729Y591022D03*
X1198519Y756765D03*
Y760265D03*
X1193969Y776910D03*
X1198519Y767265D03*
X1193969Y783603D03*
X1189569Y795315D03*
X1193969Y807028D03*
Y820414D03*
Y813721D03*
X1189569Y832126D03*
X1193969Y850532D03*
Y843839D03*
Y857225D03*
X1189569Y868937D03*
X1193969Y880650D03*
Y887343D03*
Y894036D03*
X1189569Y905749D03*
X1193969Y917461D03*
Y924154D03*
Y930847D03*
Y954272D03*
X1189569Y942560D03*
X1193969Y960965D03*
Y967658D03*
Y974351D03*
Y981044D03*
Y987736D03*
Y994429D03*
Y1004469D03*
Y1034587D03*
Y1041280D03*
Y1047973D03*
Y1054666D03*
Y1061359D03*
Y1071398D03*
X1189569Y1089804D03*
X1193969Y1078091D03*
Y1101516D03*
Y1108209D03*
Y1114902D03*
X1189569Y1126615D03*
X1193969Y1138327D03*
Y1145020D03*
X1189569Y1163426D03*
X1193969Y1151713D03*
Y1175138D03*
Y1181831D03*
Y1188524D03*
X1189569Y1200237D03*
X1193969Y1211949D03*
Y1218642D03*
X1189569Y1237048D03*
X1193969Y1225335D03*
Y1248760D03*
Y1255453D03*
X1196159Y1326549D03*
X1193659Y1326589D03*
Y1324049D03*
X1196259D03*
X1193659Y1321549D03*
X1196259D03*
X1199899Y1338065D03*
X1193829Y1352252D03*
X1196429D03*
X1193829Y1349652D03*
X1196429D03*
X1193829Y1354852D03*
X1190159Y1357406D03*
X1195179Y1357352D03*
X1196429Y1354852D03*
X1187715Y1357390D03*
X1191105Y1363394D03*
Y1360437D03*
X1200690Y1384572D03*
X1194000Y1418000D03*
X1187925Y1417000D03*
X1194000Y1428500D03*
Y1433000D03*
X1187925Y1440400D03*
X1188014Y1483295D03*
Y1488495D03*
X1194724Y1505295D03*
X1196634Y1502695D03*
Y1507895D03*
X1196127Y1583797D03*
X1195261Y1622884D03*
X1200217D03*
X1195050Y1620040D03*
X1195261Y1627876D03*
X1200217D03*
Y1654796D03*
X1195261D03*
X1200217Y1659788D03*
X1195261D03*
X1192903Y1666276D03*
X1189462Y1691366D03*
X1196767Y1712261D03*
X1196814Y1726261D03*
X1215528Y172395D03*
X1214156Y292066D03*
X1214856Y421018D03*
X1213866Y455376D03*
X1208400Y591631D03*
X1201440Y668138D03*
X1207177Y668115D03*
X1205561Y756765D03*
X1210111Y773563D03*
X1205561Y763765D03*
X1205711Y791969D03*
X1210111Y780256D03*
X1204661Y786949D03*
X1210111Y803681D03*
X1204661Y796988D03*
X1210111Y817067D03*
Y810374D03*
X1205711Y828780D03*
X1204661Y833799D03*
Y823760D03*
X1210111Y847185D03*
Y840492D03*
X1205711Y865591D03*
X1210111Y853878D03*
X1204661Y860571D03*
X1210111Y877303D03*
X1204661Y870610D03*
X1210111Y890689D03*
Y883996D03*
X1205711Y902402D03*
X1204661Y897382D03*
Y907422D03*
X1210111Y914114D03*
Y920807D03*
X1205711Y939213D03*
X1204661Y934193D03*
X1210111Y927500D03*
X1204661Y944233D03*
X1210111Y950925D03*
Y957618D03*
Y964311D03*
Y971004D03*
Y977697D03*
Y984390D03*
Y991083D03*
Y997776D03*
Y1004469D03*
Y1031240D03*
Y1037933D03*
Y1044626D03*
Y1051319D03*
Y1058012D03*
Y1068051D03*
Y1074744D03*
X1205711Y1086457D03*
X1204661Y1081437D03*
Y1091477D03*
X1210111Y1098170D03*
Y1104862D03*
X1204661Y1118248D03*
X1210111Y1111555D03*
X1205711Y1123268D03*
X1204661Y1128288D03*
X1210111Y1134981D03*
Y1141674D03*
Y1148366D03*
X1205711Y1160079D03*
X1204661Y1155059D03*
Y1165099D03*
X1210111Y1171792D03*
Y1178485D03*
X1204661Y1191870D03*
X1210111Y1185177D03*
X1205711Y1196890D03*
X1204661Y1201910D03*
X1210111Y1208603D03*
Y1215296D03*
Y1221988D03*
X1205711Y1233701D03*
X1204661Y1228681D03*
Y1238721D03*
X1210111Y1245414D03*
Y1252107D03*
X1205189Y1321492D03*
Y1323992D03*
X1202689Y1321492D03*
Y1324032D03*
X1211299Y1338105D03*
X1202399D03*
X1215415Y1357390D03*
X1212815D03*
X1210215D03*
X1207615D03*
X1202988Y1361490D03*
X1215415Y1363454D03*
Y1360497D03*
X1212815Y1363454D03*
Y1360497D03*
X1210215D03*
X1207615D03*
X1214319Y1372853D03*
X1211889D03*
X1209459D03*
Y1367253D03*
X1214319D03*
X1211889D03*
X1214368Y1385268D03*
X1202288Y1386721D03*
X1202484Y1402467D03*
X1203334Y1492995D03*
X1208114D03*
X1210034Y1483295D03*
X1214814D03*
X1208124Y1485895D03*
X1210034Y1488495D03*
X1214814D03*
X1201424Y1495595D03*
X1203334Y1498195D03*
X1208114D03*
X1201414Y1502695D03*
Y1507895D03*
X1200851Y1583797D03*
X1205576Y1583897D03*
X1210300Y1583697D03*
X1215025Y1583897D03*
X1207321Y1622884D03*
X1212277D03*
X1201291Y1637876D03*
Y1632884D03*
X1206247D03*
Y1637876D03*
X1213351D03*
Y1632884D03*
X1207321Y1627876D03*
X1212277D03*
X1207321Y1654796D03*
X1206247Y1649788D03*
X1201291D03*
X1212277Y1654796D03*
X1213351Y1649788D03*
X1206247Y1644796D03*
X1201291D03*
X1213351D03*
X1207321Y1659788D03*
X1212277D03*
X1204804Y1691375D03*
X1216199Y49379D03*
X1230156Y292066D03*
X1222094Y286948D03*
X1219463Y1338122D03*
X1229809Y1338105D03*
X1226629Y1352252D03*
X1229229D03*
X1226629Y1349652D03*
X1229229D03*
X1222959Y1357406D03*
X1227979Y1357352D03*
X1226629Y1354852D03*
X1229229D03*
X1220515Y1357390D03*
X1218015D03*
X1223905Y1363394D03*
Y1360437D03*
X1230134Y1492995D03*
X1228224Y1495595D03*
X1221524Y1505295D03*
X1230134Y1498195D03*
X1228214Y1502695D03*
X1223434D03*
Y1507895D03*
X1228214D03*
X1219749Y1583897D03*
X1224474Y1583697D03*
X1229198Y1583797D03*
X1219381Y1622884D03*
X1224337D03*
X1218307Y1637876D03*
Y1632884D03*
X1230367Y1637876D03*
X1225411D03*
X1230367Y1632884D03*
X1225411D03*
X1219381Y1627876D03*
X1224337D03*
Y1654796D03*
X1219381D03*
X1218307Y1649788D03*
X1225411D03*
X1230367D03*
X1218307Y1644796D03*
X1225411D03*
X1230367D03*
X1224337Y1659788D03*
X1219381D03*
X1219738Y1717011D03*
Y1731011D03*
X1236844Y-34348D03*
X1236829Y-36863D03*
X1236798Y-31476D03*
X1236813Y-28961D03*
X1240097Y-34334D03*
X1243122Y-35654D03*
X1240082Y-36849D03*
X1236877Y-26227D03*
X1236932Y-19948D03*
X1236942Y-13666D03*
X1236927Y-16181D03*
X1236892Y-23712D03*
X1240130Y-26213D03*
X1240194Y-19948D03*
X1240195Y-13652D03*
X1243220Y-14972D03*
X1240180Y-16167D03*
X1240145Y-23698D03*
X1243170Y-25018D03*
X1236932Y-9948D03*
Y52D03*
X1236942Y-3666D03*
X1236927Y-6181D03*
X1240194Y-9948D03*
Y52D03*
X1240195Y-3652D03*
X1243220Y-4972D03*
X1240180Y-6167D03*
X1236927Y13819D03*
X1236942Y16334D03*
X1236932Y10052D03*
X1236942Y6334D03*
X1236927Y3819D03*
X1240180Y13833D03*
X1243220Y15028D03*
X1240195Y16348D03*
X1240194Y10052D03*
X1240195Y6348D03*
X1243220Y5028D03*
X1240180Y3833D03*
X1236911Y21721D03*
X1236896Y19206D03*
X1236941Y26751D03*
X1236926Y24236D03*
X1243219Y25445D03*
X1240194Y26765D03*
X1240179Y24250D03*
X1238199Y49379D03*
X1245606Y1314351D03*
Y1311244D03*
X1240899Y1315460D03*
X1240240Y1339578D03*
X1232409Y1338105D03*
X1242500Y1430075D03*
X1237100Y1442500D03*
X1242500Y1437075D03*
X1234924Y1485895D03*
X1241614Y1483295D03*
X1236834D03*
X1241614Y1488495D03*
X1236834D03*
X1234914Y1492995D03*
Y1498195D03*
X1233923Y1583897D03*
X1238647D03*
X1243372D03*
X1231441Y1622884D03*
X1236397D03*
X1243501D03*
X1237471Y1637876D03*
Y1632884D03*
X1242427Y1637876D03*
Y1632884D03*
X1236397Y1627876D03*
X1231441D03*
X1243501D03*
X1231441Y1654796D03*
X1236397D03*
X1237471Y1649788D03*
X1243501Y1654796D03*
X1242427Y1649788D03*
X1237471Y1644796D03*
X1242427D03*
X1231441Y1659788D03*
X1236397D03*
X1243501D03*
X1260199Y49379D03*
X1256064Y101100D03*
X1254094Y286948D03*
X1245825Y305275D03*
X1260227Y407128D03*
Y411128D03*
X1248902Y470733D03*
X1257016Y467253D03*
X1246490Y483302D03*
X1257450Y1291721D03*
X1260050D03*
X1249650D03*
X1247050D03*
X1258506Y1311244D03*
X1256006D03*
X1253406Y1314351D03*
X1250806D03*
X1253406Y1311244D03*
X1250806D03*
X1248206Y1314351D03*
Y1311244D03*
X1252310Y1321107D03*
X1249880D03*
X1252310Y1326707D03*
X1253406Y1317308D03*
X1250806D03*
X1247450Y1326707D03*
Y1321107D03*
X1249880Y1326707D03*
X1252359Y1339122D03*
X1252315Y1417085D03*
X1254905Y1417026D03*
X1256934Y1492995D03*
X1255024Y1495595D03*
X1248324Y1505295D03*
X1256934Y1498195D03*
X1255014Y1502695D03*
X1250234D03*
X1255014Y1507895D03*
X1250234D03*
X1248096Y1583897D03*
X1252820Y1583697D03*
X1257544Y1583897D03*
X1248457Y1622884D03*
X1255561D03*
X1254487Y1637876D03*
Y1632884D03*
X1249531Y1637876D03*
Y1632884D03*
X1248457Y1627876D03*
X1255561D03*
X1248457Y1654796D03*
X1254487Y1649788D03*
X1249531D03*
X1255561Y1654796D03*
X1254487Y1644796D03*
X1249531D03*
X1248657Y1659588D03*
X1255561Y1659788D03*
X1266146Y121022D03*
X1263582Y164051D03*
Y160051D03*
Y180551D03*
Y176051D03*
Y172051D03*
Y168051D03*
Y185051D03*
X1270094Y286948D03*
X1262156Y292066D03*
X1270670Y1291624D03*
X1268070D03*
X1261896Y1314291D03*
X1260950Y1311260D03*
X1267220Y1306106D03*
Y1308706D03*
Y1303506D03*
X1265970Y1311206D03*
X1264620Y1303506D03*
Y1306106D03*
Y1308706D03*
X1273869Y1315300D03*
X1261896Y1317248D03*
X1273175Y1340547D03*
X1271517Y1338596D03*
X1275124Y1485895D03*
X1261724D03*
X1263634Y1483295D03*
X1268414D03*
X1263634Y1488495D03*
X1268414D03*
X1261714Y1492995D03*
Y1498195D03*
X1262269Y1583897D03*
X1266993Y1583797D03*
X1267621Y1622884D03*
X1260517D03*
X1272577D03*
X1261591Y1637876D03*
X1266547D03*
X1261591Y1632884D03*
X1266547D03*
X1273651Y1637876D03*
Y1632790D03*
X1267621Y1627876D03*
X1260517D03*
X1272577D03*
X1260517Y1654796D03*
X1267621D03*
X1266547Y1649788D03*
X1261591D03*
X1272577Y1654796D03*
X1273651Y1649788D03*
X1266547Y1644796D03*
X1261591D03*
X1273651D03*
X1260517Y1659788D03*
X1267621D03*
X1272577D03*
X1282199Y49379D03*
X1278111Y150030D03*
X1285391Y142553D03*
X1286094Y286948D03*
X1278156Y292066D03*
X1277598Y404428D03*
X1282165Y408987D03*
X1288202Y405741D03*
X1288902Y1311216D03*
X1286302Y1314323D03*
X1283702D03*
X1286302Y1311216D03*
X1283702D03*
X1278502Y1314323D03*
X1281102D03*
Y1311216D03*
X1278502D03*
X1285206Y1326679D03*
X1286302Y1317280D03*
X1283702D03*
X1285206Y1321079D03*
X1282776D03*
Y1326679D03*
X1280346Y1321079D03*
Y1326679D03*
X1285255Y1339094D03*
X1277034Y1483295D03*
X1281814D03*
X1277034Y1488495D03*
X1281814D03*
X1284510Y1556953D03*
X1278012Y1581563D03*
X1279681Y1622884D03*
X1284637D03*
X1278607Y1637876D03*
Y1632790D03*
X1285711Y1637876D03*
Y1632884D03*
X1279681Y1627876D03*
X1284637D03*
X1279681Y1654796D03*
X1278607Y1649788D03*
X1284637Y1654796D03*
X1285711Y1649788D03*
X1278607Y1644796D03*
X1285711D03*
X1279681Y1659788D03*
X1284637D03*
X1304199Y49379D03*
X1300668Y125739D03*
Y133739D03*
Y129739D03*
X1306431Y149330D03*
X1300668Y145739D03*
X1292082Y166051D03*
Y162051D03*
Y171551D03*
Y184051D03*
X1302094Y298066D03*
Y286948D03*
X1294156Y292066D03*
X1293277Y401125D03*
X1296228Y408125D03*
X1299076Y530023D03*
X1297487Y590607D03*
X1302890Y1291759D03*
X1298350Y1291721D03*
X1295750D03*
X1300116Y1306078D03*
Y1303478D03*
Y1308678D03*
X1298866Y1311178D03*
X1294792Y1314263D03*
X1297516Y1306078D03*
Y1303478D03*
Y1308678D03*
X1291402Y1311216D03*
X1293846Y1311232D03*
X1294792Y1317220D03*
X1304421Y1338539D03*
X1304596Y1492995D03*
X1302686Y1495595D03*
X1304596Y1498195D03*
X1291819Y1563595D03*
X1294319D03*
X1300560Y1554261D03*
X1291741Y1622884D03*
X1296697D03*
X1303801D03*
X1290667Y1637876D03*
Y1632884D03*
X1297771Y1637876D03*
Y1632884D03*
X1302727Y1637876D03*
Y1632884D03*
X1296697Y1627876D03*
X1291741D03*
X1303801D03*
X1291741Y1654796D03*
X1296697D03*
X1297771Y1649788D03*
X1290667D03*
X1303801Y1654796D03*
X1302727Y1649788D03*
X1297771Y1644796D03*
X1290667D03*
X1302727D03*
X1291741Y1659788D03*
X1296697D03*
X1303801D03*
X1306449Y92185D03*
X1306431Y152830D03*
X1310156Y292066D03*
X1305600Y1291759D03*
X1316606Y1314266D03*
Y1311159D03*
X1314006Y1314266D03*
Y1311159D03*
X1319206Y1314266D03*
Y1311159D03*
X1311406Y1314266D03*
Y1311159D03*
X1306799Y1315440D03*
X1315680Y1326622D03*
X1318110D03*
X1316606Y1317223D03*
X1319206D03*
X1318110Y1321022D03*
X1315680D03*
X1313250D03*
Y1326622D03*
X1318159Y1339037D03*
X1306079Y1340490D03*
X1314580Y1425240D03*
X1310580D03*
X1318580D03*
X1309386Y1485895D03*
X1311296Y1483295D03*
X1316076D03*
X1311296Y1488495D03*
X1316076D03*
X1309376Y1492995D03*
Y1498195D03*
X1308290Y1533380D03*
X1309423Y1543800D03*
Y1547420D03*
Y1551040D03*
X1309915Y1561731D03*
X1308757Y1622884D03*
X1315861D03*
X1309831Y1637876D03*
Y1632884D03*
X1314787Y1637876D03*
Y1632884D03*
X1308757Y1627876D03*
X1315861D03*
X1308757Y1654796D03*
X1309831Y1649788D03*
X1315861Y1654796D03*
X1314787Y1649788D03*
X1309831Y1644796D03*
X1314787D03*
X1308757Y1659788D03*
X1315861D03*
X1326199Y49379D03*
X1334156Y292066D03*
X1326094Y286948D03*
X1330277Y857388D03*
X1329477Y1222158D03*
X1331202Y1211488D03*
X1332680Y1291861D03*
X1330080D03*
X1333020Y1308621D03*
X1331770Y1311121D03*
X1333020Y1306021D03*
Y1303421D03*
X1330420Y1306021D03*
Y1303421D03*
Y1308621D03*
X1327696Y1314206D03*
X1321806Y1311159D03*
X1324306D03*
X1326750Y1311175D03*
X1327696Y1317163D03*
X1334580Y1425240D03*
X1330580D03*
X1326580D03*
X1322580D03*
X1331396Y1492995D03*
X1322786Y1505295D03*
X1329486Y1495595D03*
X1331396Y1498195D03*
X1324696Y1502695D03*
X1329476D03*
X1324696Y1507895D03*
X1329476D03*
X1328913Y1583797D03*
X1333638Y1583897D03*
X1324189Y1583797D03*
X1327921Y1622884D03*
X1320817D03*
X1332877D03*
X1321891Y1637876D03*
X1326847D03*
X1321891Y1632884D03*
X1326847D03*
X1333951Y1637876D03*
Y1632884D03*
X1327921Y1627876D03*
X1320817D03*
X1332877D03*
X1320817Y1654796D03*
X1327921D03*
X1326847Y1649788D03*
X1321891D03*
X1332877Y1654796D03*
X1333951Y1649788D03*
X1326847Y1644796D03*
X1321891D03*
X1333951D03*
X1320817Y1659788D03*
X1327921D03*
X1332877D03*
X1348199Y49379D03*
X1351750Y72826D03*
X1339840Y72860D03*
X1342094Y286948D03*
X1339347Y857388D03*
X1337975Y1177999D03*
X1338142Y1181642D03*
X1338440Y1291949D03*
X1335670Y1291899D03*
X1346806Y1311359D03*
X1349406D03*
X1346806Y1314466D03*
X1349406D03*
X1344206Y1311359D03*
Y1314466D03*
X1339429Y1315570D03*
X1348480Y1326822D03*
X1349406Y1317423D03*
X1346050Y1321222D03*
Y1326822D03*
X1348480Y1321222D03*
X1338879Y1340690D03*
X1337221Y1338739D03*
X1346580Y1425240D03*
X1342580D03*
X1338580D03*
X1336176Y1492995D03*
X1338096Y1483295D03*
X1342876D03*
X1336186Y1485895D03*
X1338096Y1488495D03*
X1342876D03*
X1349586Y1505295D03*
X1336176Y1498195D03*
X1343087Y1583897D03*
X1347811D03*
X1338362Y1583697D03*
X1339981Y1622884D03*
X1344937D03*
X1338907Y1637876D03*
Y1632884D03*
X1346011Y1637876D03*
Y1632884D03*
X1339981Y1627876D03*
X1344937D03*
X1339981Y1654796D03*
X1338907Y1649788D03*
X1344937Y1654796D03*
X1346011Y1649788D03*
X1338907Y1644796D03*
X1346011D03*
X1339981Y1659788D03*
X1344937D03*
X1361550Y67264D03*
X1350156Y292066D03*
X1358094Y286948D03*
X1354257Y675765D03*
X1364490Y1293694D03*
X1361830Y1291809D03*
X1360496Y1314406D03*
X1363220Y1308821D03*
X1364570Y1311321D03*
X1363220Y1306221D03*
Y1303621D03*
X1359550Y1311375D03*
X1352006Y1311359D03*
X1357106D03*
X1354606D03*
X1352006Y1314466D03*
X1360496Y1317363D03*
X1350910Y1326822D03*
X1352006Y1317423D03*
X1350910Y1321222D03*
X1350959Y1339237D03*
X1362580Y1425240D03*
X1358580D03*
X1354580D03*
X1350580D03*
X1362986Y1485895D03*
X1364896Y1483295D03*
Y1488495D03*
X1358196Y1492995D03*
X1362976D03*
X1356286Y1495595D03*
X1358196Y1498195D03*
X1362976D03*
X1356276Y1502695D03*
X1351496D03*
X1356276Y1507895D03*
X1351496D03*
X1357260Y1583797D03*
X1361985Y1583897D03*
X1352536Y1583697D03*
X1352041Y1622884D03*
X1356997D03*
X1364101D03*
X1350967Y1637876D03*
Y1632884D03*
X1358071Y1637876D03*
Y1632884D03*
X1363027Y1637876D03*
Y1632884D03*
X1356997Y1627876D03*
X1352041D03*
X1364101D03*
X1352041Y1654796D03*
X1356997D03*
X1358071Y1649788D03*
X1350967D03*
X1364101Y1654796D03*
X1363027Y1649788D03*
X1358071Y1644796D03*
X1350967D03*
X1363027D03*
X1352041Y1659788D03*
X1356997D03*
X1364101D03*
X1370199Y49379D03*
X1371259Y98000D03*
X1366156Y292066D03*
X1377862Y485552D03*
Y511052D03*
X1368305Y1307340D03*
X1365820Y1308821D03*
X1368305Y1309840D03*
X1365820Y1306221D03*
Y1303621D03*
X1372149Y1334890D03*
X1379388Y1330690D03*
Y1333797D03*
X1378632Y1340553D03*
X1376788Y1330690D03*
Y1333797D03*
X1378632Y1346153D03*
X1371422Y1359024D03*
X1368922D03*
X1379101Y1418621D03*
X1368299Y1425240D03*
X1372164Y1423810D03*
X1375341Y1421268D03*
X1369676Y1483295D03*
Y1488495D03*
X1376386Y1505295D03*
X1378296Y1502695D03*
Y1507895D03*
X1376158Y1583897D03*
X1366709D03*
X1371434D03*
X1369057Y1622884D03*
X1376161D03*
X1370131Y1637876D03*
Y1632790D03*
X1375087Y1637876D03*
Y1632790D03*
X1369057Y1627876D03*
X1376161D03*
X1369057Y1654796D03*
X1370131Y1649788D03*
X1376161Y1654796D03*
X1375087Y1649788D03*
X1370131Y1644796D03*
X1375087D03*
X1369057Y1659788D03*
X1376161D03*
X1392199Y49379D03*
X1389688Y1330690D03*
X1392132Y1330706D03*
X1393078Y1333737D03*
Y1336694D03*
X1383492Y1340553D03*
X1381062D03*
X1381988Y1336754D03*
X1384588D03*
X1387188Y1330690D03*
X1381988D03*
Y1333797D03*
X1384588Y1330690D03*
Y1333797D03*
X1383541Y1358568D03*
X1381062Y1346153D03*
X1383492D03*
X1383284Y1415973D03*
X1387308Y1413643D03*
X1392021Y1410360D03*
X1389786Y1485895D03*
X1391696Y1483295D03*
Y1488495D03*
X1384996Y1492995D03*
X1389776D03*
X1383086Y1495595D03*
X1384996Y1498195D03*
X1389776D03*
X1383076Y1502695D03*
Y1507895D03*
X1390331Y1583897D03*
X1380882Y1583697D03*
X1385606Y1583897D03*
X1381117Y1622884D03*
X1382191Y1637876D03*
X1387147D03*
X1382191Y1632884D03*
X1387147D03*
X1381117Y1627876D03*
Y1654796D03*
X1382191Y1649788D03*
X1387147D03*
X1382191Y1644796D03*
X1387147D03*
X1392068Y1667907D03*
X1381918D03*
X1381117Y1659788D03*
X1387620Y1721418D03*
X1385061D03*
X1403500Y458377D03*
X1402452Y642825D03*
X1405716Y1310618D03*
X1401740Y1311980D03*
X1399240D03*
X1408690Y1324803D03*
X1396302Y1328152D03*
Y1325552D03*
X1398902Y1328152D03*
Y1325552D03*
X1396302Y1322952D03*
X1398902D03*
X1401406Y1334918D03*
X1397652Y1330652D03*
X1398375Y1403688D03*
X1401764Y1399928D03*
X1405207Y1395480D03*
X1408543Y1391826D03*
X1395463Y1406918D03*
X1403186Y1485895D03*
X1405096Y1483295D03*
X1396476D03*
X1405096Y1488495D03*
X1396476D03*
X1409456Y1537872D03*
X1406074Y1581563D03*
X1395055Y1583797D03*
X1398058Y1619683D03*
X1409660Y1619853D03*
X1397367Y1639951D03*
X1402425Y1649532D03*
X1414199Y49379D03*
X1414000Y460362D03*
X1415426Y1042765D03*
Y1038765D03*
X1424561Y1305566D03*
X1420690Y1324803D03*
X1417690D03*
X1414690D03*
X1411690D03*
X1424163Y1373240D03*
X1411508Y1388384D03*
X1414950Y1384942D03*
X1417491Y1381183D03*
X1420774Y1377106D03*
X1409876Y1483295D03*
Y1488495D03*
X1423735Y1536715D03*
X1412572Y1556953D03*
X1421232Y1606126D03*
X1422914Y1601663D03*
X1421392Y1621706D03*
X1416357Y1644027D03*
X1420042Y1649716D03*
X1433817Y-34648D03*
Y-4648D03*
Y5352D03*
X1436199Y49379D03*
X1434513Y106950D03*
X1439232Y596291D03*
X1425437Y1308184D03*
X1426202Y1310752D03*
X1427314Y1313482D03*
X1428458Y1316481D03*
X1429517Y1319447D03*
X1430312Y1322412D03*
X1431106Y1325219D03*
X1426441Y1369427D03*
X1428559Y1365296D03*
X1430465Y1361060D03*
X1438798Y1495595D03*
X1430431Y1563595D03*
X1427931D03*
X1424971Y1566764D03*
Y1564264D03*
X1435584Y1596545D03*
X1430075Y1613904D03*
X1430319Y1623504D03*
X1425390Y1635496D03*
X1433327Y1643287D03*
X1446869Y105129D03*
X1451353Y116158D03*
X1443551Y539318D03*
Y535318D03*
X1453345Y1015473D03*
Y1019016D03*
Y1022559D03*
X1445498Y1485895D03*
X1447408Y1483295D03*
X1452188D03*
X1447408Y1488495D03*
X1452188D03*
X1445488Y1492995D03*
X1440708D03*
X1445488Y1498195D03*
X1440708D03*
X1444200Y1533240D03*
X1445535Y1551040D03*
Y1547420D03*
Y1543800D03*
X1446027Y1561731D03*
X1445500Y1611500D03*
X1448500Y1601000D03*
X1442579Y1673303D03*
X1447579D03*
X1452579D03*
X1453950Y1681450D03*
X1458199Y49379D03*
X1459682Y450372D03*
X1468395Y487582D03*
X1464257Y552977D03*
Y564977D03*
X1468257Y696265D03*
X1460926Y1015473D03*
X1467926D03*
X1460926Y1019016D03*
Y1022559D03*
X1467926Y1019016D03*
Y1022559D03*
X1467508Y1492995D03*
X1458898Y1505295D03*
X1465598Y1495595D03*
X1467508Y1498195D03*
X1460808Y1502695D03*
X1465588D03*
X1460808Y1507895D03*
X1465588D03*
X1465025Y1583797D03*
X1460301D03*
X1464391Y1622884D03*
X1459435D03*
X1465465Y1637876D03*
Y1632884D03*
X1459435Y1627876D03*
X1464391D03*
Y1654796D03*
X1465465Y1649788D03*
Y1644796D03*
X1459435Y1654796D03*
X1464391Y1659788D03*
X1466500Y1666000D03*
X1469034Y1667794D03*
X1459435Y1659788D03*
X1456852Y1673320D03*
X1466599Y1679401D03*
X1466260Y1675155D03*
X1460457Y1685160D03*
X1480199Y49379D03*
X1483820Y122713D03*
X1482257Y552977D03*
Y560477D03*
Y567977D03*
X1481934Y699670D03*
X1480300Y697750D03*
X1472288Y1492995D03*
X1474208Y1483295D03*
X1478988D03*
X1472298Y1485895D03*
X1474208Y1488495D03*
X1478988D03*
X1472288Y1498195D03*
X1479199Y1583897D03*
X1483923D03*
X1469750D03*
X1474474Y1583697D03*
X1476451Y1622884D03*
X1471495D03*
X1483555D03*
X1470421Y1632884D03*
Y1637876D03*
X1482481D03*
X1477525D03*
X1482481Y1632884D03*
X1477525D03*
X1471495Y1627876D03*
X1483555D03*
X1476451D03*
X1471495Y1654796D03*
X1470421Y1649788D03*
X1476451Y1654796D03*
X1483555D03*
X1482481Y1649788D03*
X1477525D03*
X1470421Y1644796D03*
X1477525D03*
X1482481D03*
X1471495Y1659788D03*
X1476451D03*
X1483555D03*
X1471616Y1670098D03*
X1479375Y1685984D03*
X1495539Y131237D03*
X1492237Y123842D03*
X1489757Y552977D03*
X1497257D03*
Y560477D03*
X1489757Y567977D03*
X1497257D03*
X1494371Y594462D03*
X1492673Y828513D03*
X1494386Y1178743D03*
X1499098Y1485895D03*
X1494308Y1492995D03*
X1499088D03*
X1492398Y1495595D03*
X1485698Y1505295D03*
X1494308Y1498195D03*
X1499088D03*
X1492388Y1502695D03*
X1487608D03*
X1492388Y1507895D03*
X1487608D03*
X1493372Y1583797D03*
X1498097Y1583897D03*
X1488648Y1583697D03*
X1488511Y1622884D03*
X1495615D03*
X1494541Y1637876D03*
X1489585D03*
X1494541Y1632884D03*
X1489585D03*
X1488511Y1627876D03*
X1495615D03*
X1488511Y1654796D03*
X1495615D03*
X1489585Y1649788D03*
X1494541D03*
X1489585Y1644796D03*
X1494541D03*
X1488511Y1659788D03*
X1495615D03*
X1502199Y49379D03*
X1514576Y219730D03*
X1513348Y253954D03*
X1500757Y537438D03*
X1504757Y537378D03*
X1508757Y537456D03*
X1512757Y537477D03*
X1513382Y697750D03*
X1499243Y803513D03*
X1501730Y811872D03*
X1501338Y825147D03*
X1513470Y1178265D03*
X1504470D03*
X1505788Y1483295D03*
X1501008D03*
X1505788Y1488495D03*
X1501008D03*
X1512498Y1505295D03*
X1512270Y1583897D03*
X1502821D03*
X1507546D03*
X1500571Y1622884D03*
X1512631D03*
X1507675D03*
X1501645Y1637876D03*
Y1632884D03*
X1506601Y1637876D03*
Y1632884D03*
X1513705Y1637876D03*
Y1632884D03*
X1500571Y1627876D03*
X1512631D03*
X1507675D03*
X1500571Y1654796D03*
X1501645Y1649788D03*
X1507675Y1654796D03*
X1512631D03*
X1513705Y1649788D03*
X1506601D03*
X1501645Y1644796D03*
X1513705D03*
X1506601D03*
X1500571Y1659788D03*
X1507675D03*
X1512831Y1659588D03*
X1524124Y47570D03*
X1522917Y119912D03*
X1529384Y201245D03*
X1516452Y249724D03*
X1514900Y251839D03*
X1515016Y699670D03*
X1515192Y814294D03*
X1525898Y1485895D03*
X1527808Y1483295D03*
Y1488495D03*
X1521108Y1492995D03*
X1525888D03*
X1525898Y1505295D03*
X1519198Y1495595D03*
X1521108Y1498195D03*
X1525888D03*
X1519188Y1502695D03*
X1527808D03*
X1514408D03*
X1519188Y1507895D03*
X1514408D03*
X1526443Y1583897D03*
X1516994Y1583697D03*
X1521718Y1583897D03*
X1524691Y1622884D03*
X1519735D03*
X1518661Y1637876D03*
Y1632884D03*
X1525765Y1637876D03*
Y1632884D03*
X1519735Y1627876D03*
X1524691D03*
X1518661Y1649788D03*
X1524691Y1654796D03*
X1519735D03*
X1525765Y1649788D03*
X1518661Y1644796D03*
X1525765D03*
X1524991Y1659788D03*
X1519735D03*
X1530064Y-27930D03*
X1530049Y-30445D03*
X1533317Y-27916D03*
X1536342Y-29236D03*
X1533302Y-30431D03*
X1530048Y-20028D03*
X1530063Y-17513D03*
X1530018Y-25058D03*
X1530033Y-22543D03*
X1533301Y-20014D03*
X1533316Y-17499D03*
X1536341Y-18819D03*
X1543862Y75343D03*
X1539756Y71839D03*
X1534776D03*
X1539756Y66847D03*
X1534776D03*
X1532866Y69340D03*
X1536542Y300819D03*
Y304819D03*
X1539693Y535212D03*
X1542902Y543641D03*
X1540850Y1240863D03*
X1539298Y1485895D03*
X1541208Y1483295D03*
X1532588D03*
X1541208Y1488495D03*
X1532588D03*
X1542186Y1581563D03*
X1531167Y1583797D03*
X1536751Y1622884D03*
X1531795D03*
X1530721Y1637876D03*
Y1632884D03*
X1537825Y1637876D03*
X1542781D03*
X1537825Y1632790D03*
X1542781D03*
X1531795Y1627876D03*
X1536751D03*
X1531795Y1654796D03*
X1530721Y1649788D03*
X1536751Y1654796D03*
X1542781Y1649788D03*
X1537825D03*
X1530721Y1644796D03*
X1542781D03*
X1537825D03*
X1531795Y1659788D03*
X1536751D03*
X1550965Y3001D03*
X1555568Y17045D03*
Y22037D03*
X1553601Y19541D03*
X1555452Y25977D03*
X1553452Y23981D03*
X1548496D03*
X1546496Y25977D03*
X1554520Y37106D03*
X1547434D03*
X1554520Y48720D03*
X1547434D03*
X1556776Y71839D03*
X1550756Y72850D03*
X1545776D03*
X1554866Y69340D03*
X1556776Y66847D03*
X1550756Y77842D03*
X1545776D03*
X1552981Y220826D03*
X1555481Y218326D03*
X1553913Y298119D03*
X1558480Y302678D03*
X1545960Y565162D03*
X1551887Y606938D03*
X1555570Y1235968D03*
X1555367Y1248078D03*
X1555303Y1242557D03*
X1547062Y1258468D03*
X1553811Y1264488D03*
X1545988Y1483295D03*
Y1488495D03*
X1548684Y1556953D03*
X1555993Y1563595D03*
X1558493D03*
X1548811Y1622884D03*
X1543855D03*
X1555915D03*
X1549885Y1637876D03*
X1554841D03*
X1549885Y1632884D03*
X1554841D03*
X1543855Y1627876D03*
X1548811D03*
X1555915D03*
X1543855Y1654796D03*
X1555915D03*
X1548811D03*
X1554841Y1649788D03*
X1549885D03*
X1554841Y1644796D03*
X1549885D03*
X1543855Y1659788D03*
X1555915D03*
X1548811D03*
X1572965Y3001D03*
X1569742Y17045D03*
X1560548D03*
X1567774Y19541D03*
X1569742Y22037D03*
X1560548D03*
X1562669Y23981D03*
X1567625D03*
X1560669Y25977D03*
X1569625D03*
X1562557Y19541D03*
X1561607Y37106D03*
X1568693D03*
Y48720D03*
X1561607D03*
X1572756Y72847D03*
X1561756Y71839D03*
X1565866Y75340D03*
X1567776Y72847D03*
X1561756Y66847D03*
X1572756Y77839D03*
X1567776D03*
X1564517Y299432D03*
X1569592Y294816D03*
X1572283Y301816D03*
X1562995Y789522D03*
X1569518Y806684D03*
X1564267Y1253158D03*
X1573560Y1485895D03*
X1573550Y1492995D03*
X1568770D03*
X1566860Y1495595D03*
X1573550Y1498195D03*
X1568770D03*
X1572230Y1533000D03*
X1573597Y1543800D03*
Y1547420D03*
Y1551040D03*
X1564839Y1554561D03*
X1560871Y1622884D03*
X1572931D03*
X1567975D03*
X1561945Y1637876D03*
Y1632884D03*
X1566901Y1637876D03*
Y1632884D03*
X1560871Y1627876D03*
X1572931D03*
X1567975D03*
X1560871Y1654796D03*
X1561945Y1649788D03*
X1567975Y1654796D03*
X1572931D03*
X1566901Y1649788D03*
X1561945Y1644796D03*
X1566901D03*
X1560871Y1659788D03*
X1567975D03*
X1572931D03*
X1583915Y17045D03*
X1574722D03*
X1581947Y19541D03*
X1583915Y22037D03*
X1576730Y19541D03*
X1574722Y22037D03*
X1576842Y23981D03*
X1581798D03*
X1574842Y25977D03*
X1583798D03*
X1575780Y37106D03*
X1582867D03*
Y48720D03*
X1575780D03*
X1587866Y75340D03*
X1578776Y71839D03*
X1583756D03*
X1576866Y69340D03*
X1578776Y66847D03*
X1583756D03*
X1574546Y251294D03*
X1575370Y1252770D03*
X1581327Y1252858D03*
X1586835Y1271918D03*
X1583007Y1288958D03*
X1577913Y1341623D03*
X1575504Y1356103D03*
X1578336D03*
X1575470Y1483295D03*
X1580250D03*
X1575470Y1488495D03*
X1580250D03*
X1586960Y1505295D03*
X1574089Y1561731D03*
X1588363Y1583797D03*
X1584991Y1622884D03*
X1580035D03*
X1574005Y1637876D03*
Y1632884D03*
X1578961Y1637876D03*
Y1632884D03*
X1586065Y1637876D03*
Y1632884D03*
X1580035Y1627876D03*
X1584991D03*
X1574005Y1649788D03*
X1580035Y1654796D03*
X1578961Y1649788D03*
X1584991Y1654796D03*
X1586065Y1649788D03*
X1574005Y1644796D03*
X1578961D03*
X1586065D03*
X1580035Y1659788D03*
X1584991D03*
X1594965Y3001D03*
X1603072Y17045D03*
X1598092D03*
X1588895D03*
X1603072Y22037D03*
X1598092D03*
X1596121Y19541D03*
X1590903D03*
X1588895Y22037D03*
X1595972Y23981D03*
X1591016D03*
X1589016Y25977D03*
X1597972D03*
X1589953Y37106D03*
X1597040D03*
Y48720D03*
X1589953D03*
X1589776Y72847D03*
X1594756D03*
X1600776Y71842D03*
X1598866Y69343D03*
X1600776Y66850D03*
X1589776Y77839D03*
X1594756D03*
X1597562Y555463D03*
X1595036D03*
X1591962D03*
X1589436D03*
X1589557Y1252778D03*
X1590097Y1246768D03*
X1603507Y1306262D03*
X1601772Y1337293D03*
X1601959Y1351773D03*
X1599139Y1400464D03*
X1595570Y1492995D03*
X1600350D03*
X1602270Y1483295D03*
X1600360Y1485895D03*
X1602270Y1488495D03*
X1593660Y1495595D03*
X1595570Y1498195D03*
X1600350D03*
X1588870Y1502695D03*
X1593650D03*
X1588870Y1507895D03*
X1593650D03*
X1593087Y1583797D03*
X1597812Y1583897D03*
X1602536Y1583697D03*
X1597051Y1622884D03*
X1592095D03*
X1591021Y1637876D03*
Y1632884D03*
X1598125Y1637876D03*
X1603081D03*
X1598125Y1632884D03*
X1603081D03*
X1592095Y1627876D03*
X1597051D03*
X1592095Y1654796D03*
X1591021Y1649788D03*
X1597051Y1654796D03*
X1603081Y1649788D03*
X1598125D03*
X1591021Y1644796D03*
X1603081D03*
X1598125D03*
X1592095Y1659788D03*
X1597051D03*
X1616965Y3001D03*
X1605077Y19541D03*
X1604127Y37106D03*
Y48720D03*
X1609866Y75340D03*
X1611776Y72847D03*
X1616756D03*
X1605756Y71842D03*
Y66850D03*
X1611776Y77839D03*
X1616756D03*
X1608640Y640660D03*
X1607050Y1483295D03*
Y1488495D03*
X1613760Y1505295D03*
X1615670Y1502695D03*
Y1507895D03*
X1607261Y1583897D03*
X1611985D03*
X1616710Y1583697D03*
X1609111Y1622884D03*
X1604155D03*
X1616215D03*
X1610185Y1637876D03*
X1615141D03*
X1610185Y1632884D03*
X1615141D03*
X1604155Y1627876D03*
X1609111D03*
X1616215D03*
X1604155Y1654796D03*
X1616215D03*
X1609111D03*
X1615141Y1649788D03*
X1610185D03*
X1615141Y1644796D03*
X1610185D03*
X1604155Y1659788D03*
X1616215D03*
X1609111D03*
X1631987Y19541D03*
X1626882Y23981D03*
X1631838D03*
X1624882Y25977D03*
X1632906Y37106D03*
X1625819D03*
X1632906Y48720D03*
X1625819D03*
X1629662Y69343D03*
X1633070Y75340D03*
X1627756Y71842D03*
X1622776D03*
X1627756Y66850D03*
X1622776D03*
X1620862Y69343D03*
X1627410Y172008D03*
X1632500Y381500D03*
X1630927Y398002D03*
X1628046Y756765D03*
Y760265D03*
Y767265D03*
X1623496Y776910D03*
Y783603D03*
X1627896Y795315D03*
X1623496Y807028D03*
Y813721D03*
Y820414D03*
X1627896Y832126D03*
X1623496Y843839D03*
Y850532D03*
Y857225D03*
X1627896Y868937D03*
X1623496Y880650D03*
Y887343D03*
Y894036D03*
X1627896Y905749D03*
X1623496Y917461D03*
Y924154D03*
Y930847D03*
X1627896Y942560D03*
X1623496Y954272D03*
Y960965D03*
Y967658D03*
Y974351D03*
Y981044D03*
Y987736D03*
Y994429D03*
Y1004469D03*
Y1034587D03*
Y1041280D03*
Y1047973D03*
Y1054666D03*
Y1061359D03*
Y1071398D03*
X1627896Y1089804D03*
X1623496Y1078091D03*
Y1101516D03*
Y1108209D03*
Y1114902D03*
X1627896Y1126615D03*
X1623496Y1138327D03*
Y1145020D03*
X1627896Y1163426D03*
X1623496Y1151713D03*
Y1175138D03*
Y1181831D03*
Y1188524D03*
X1627896Y1200237D03*
X1623496Y1211949D03*
Y1218642D03*
X1627896Y1237048D03*
X1623496Y1225335D03*
Y1248760D03*
Y1255453D03*
X1627052Y1424716D03*
X1627160Y1485895D03*
X1629070Y1483295D03*
Y1488495D03*
X1622370Y1492995D03*
X1627150D03*
X1620460Y1495595D03*
X1622370Y1498195D03*
X1627150D03*
X1620450Y1502695D03*
Y1507895D03*
X1621434Y1583797D03*
X1626159Y1583897D03*
X1630883D03*
X1621171Y1622884D03*
X1628275D03*
X1622245Y1637876D03*
Y1632884D03*
X1627201Y1637876D03*
Y1632884D03*
X1621171Y1627876D03*
X1628275D03*
X1621171Y1654796D03*
X1622245Y1649788D03*
X1628275Y1654796D03*
X1627201Y1649788D03*
X1622245Y1644796D03*
X1627201D03*
X1621171Y1659788D03*
X1628275D03*
X1638965Y3001D03*
X1648128Y17045D03*
X1633954D03*
X1638934D03*
X1648128Y22037D03*
X1648011Y25977D03*
X1633954Y22037D03*
X1638934D03*
X1646160Y19541D03*
X1640943D03*
X1641055Y23981D03*
X1646011D03*
X1639055Y25977D03*
X1633838D03*
X1647079Y37106D03*
X1639993D03*
X1647079Y48720D03*
X1639993D03*
X1634980Y72847D03*
X1639960D03*
X1645980Y71839D03*
X1644070Y69340D03*
X1645980Y66847D03*
X1634980Y77839D03*
X1639960D03*
X1642240Y399603D03*
X1642135Y414202D03*
X1639800Y426982D03*
X1636800D03*
X1639800Y429982D03*
X1636800D03*
X1639800Y432982D03*
X1636800D03*
X1647110Y434177D03*
X1639800Y435982D03*
X1636800D03*
X1639800Y438982D03*
X1636800D03*
X1635088Y756765D03*
Y763765D03*
X1639638Y773563D03*
X1644038Y791969D03*
X1634188Y786949D03*
X1639638Y780256D03*
X1634188Y796988D03*
X1639638Y803681D03*
Y810374D03*
Y817067D03*
X1644038Y828780D03*
X1634188Y823760D03*
Y833799D03*
X1639638Y840492D03*
Y847185D03*
X1644038Y865591D03*
X1634188Y860571D03*
X1639638Y853878D03*
X1634188Y870610D03*
X1639638Y877303D03*
Y883996D03*
Y890689D03*
X1644038Y902402D03*
X1634188Y897382D03*
Y907422D03*
X1639638Y914114D03*
Y920807D03*
X1644038Y939213D03*
X1634188Y934193D03*
X1639638Y927500D03*
X1634188Y944233D03*
X1639638Y950925D03*
Y957618D03*
Y964311D03*
Y971004D03*
Y977697D03*
Y984390D03*
Y991083D03*
Y997776D03*
Y1004469D03*
Y1031240D03*
Y1037933D03*
Y1044626D03*
Y1051319D03*
Y1058012D03*
Y1068051D03*
Y1074744D03*
X1644038Y1086457D03*
X1634188Y1081437D03*
Y1091477D03*
X1639638Y1098170D03*
Y1104862D03*
X1634188Y1118248D03*
X1639638Y1111555D03*
X1644038Y1123268D03*
X1634188Y1128288D03*
X1639638Y1134981D03*
Y1141674D03*
Y1148366D03*
X1644038Y1160079D03*
X1634188Y1155059D03*
Y1165099D03*
X1639638Y1171792D03*
Y1178485D03*
X1634188Y1191870D03*
X1639638Y1185177D03*
X1644038Y1196890D03*
X1634188Y1201910D03*
X1639638Y1208603D03*
Y1215296D03*
Y1221988D03*
X1644038Y1233701D03*
X1634188Y1228681D03*
Y1238721D03*
X1639638Y1245414D03*
Y1252107D03*
X1641904Y1351467D03*
Y1348567D03*
X1633850Y1483295D03*
Y1488495D03*
X1647260Y1495595D03*
X1640560Y1505295D03*
X1647250Y1502695D03*
X1642470D03*
X1647250Y1507895D03*
X1642470D03*
X1640332Y1583897D03*
X1645056Y1583697D03*
X1635608Y1583897D03*
X1633231Y1622884D03*
X1645291D03*
X1640335D03*
X1634305Y1637876D03*
Y1632790D03*
X1639261Y1637876D03*
Y1632790D03*
X1646365Y1637876D03*
Y1632884D03*
X1633231Y1627876D03*
X1640335D03*
X1645291D03*
X1633231Y1654796D03*
X1634305Y1649788D03*
X1640335Y1654796D03*
X1639261Y1649788D03*
X1645291Y1654796D03*
X1646365Y1649788D03*
X1634305Y1644796D03*
X1639261D03*
X1646365D03*
X1633231Y1659788D03*
X1640335D03*
X1645291D03*
X1647700Y1674228D03*
X1648013Y1713684D03*
Y1728834D03*
X1660965Y3001D03*
X1653108Y17045D03*
X1655116Y19541D03*
X1653108Y22037D03*
X1654166Y37106D03*
Y48720D03*
X1650960Y66847D03*
X1655066Y75343D03*
X1662065Y72850D03*
X1656980D03*
X1650960Y71839D03*
X1662065Y77842D03*
X1656980D03*
X1652610Y394727D03*
X1659610D03*
X1652810Y407402D03*
X1661110Y434177D03*
X1657747Y756765D03*
Y760265D03*
Y767265D03*
X1653197Y776910D03*
Y783603D03*
X1657597Y795315D03*
X1653197Y807028D03*
Y813721D03*
Y820414D03*
X1657597Y832126D03*
X1653197Y843839D03*
Y850532D03*
Y857225D03*
X1657597Y868937D03*
X1653197Y880650D03*
Y887343D03*
Y894036D03*
X1657597Y905749D03*
X1653197Y917461D03*
Y924154D03*
Y930847D03*
X1657597Y942560D03*
X1653197Y954272D03*
Y960965D03*
Y967658D03*
Y974351D03*
Y981044D03*
Y987736D03*
Y994429D03*
Y1004469D03*
Y1034587D03*
Y1041280D03*
Y1047973D03*
Y1054666D03*
Y1061359D03*
Y1071398D03*
X1657597Y1089804D03*
X1653197Y1078091D03*
Y1101516D03*
Y1108209D03*
Y1114902D03*
X1657597Y1126615D03*
X1653197Y1138327D03*
Y1145020D03*
X1657597Y1163426D03*
X1653197Y1151713D03*
Y1175138D03*
Y1188524D03*
Y1181831D03*
X1657597Y1200237D03*
X1653197Y1211949D03*
Y1218642D03*
X1657597Y1237048D03*
X1653197Y1225335D03*
Y1248760D03*
Y1255453D03*
X1660594Y1298735D03*
X1651187D03*
X1660594Y1303935D03*
Y1306535D03*
Y1301335D03*
X1651187Y1303935D03*
Y1306535D03*
Y1301335D03*
X1650177Y1351467D03*
Y1348567D03*
X1658904Y1351467D03*
Y1348567D03*
X1662010Y1384570D03*
X1662766Y1377814D03*
X1660166D03*
X1662766Y1374707D03*
X1660166D03*
X1651301Y1378765D03*
X1662010Y1390170D03*
X1654774Y1402619D03*
X1648857Y1403424D03*
X1662465Y1444358D03*
X1653960Y1485895D03*
X1655870Y1483295D03*
X1660650D03*
X1655870Y1488495D03*
X1660650D03*
X1649170Y1492995D03*
X1653950D03*
X1649170Y1498195D03*
X1653950D03*
X1654505Y1583897D03*
X1659229Y1583797D03*
X1649780Y1583897D03*
X1651321Y1637876D03*
Y1632884D03*
Y1649788D03*
Y1644796D03*
X1653464Y1668416D03*
X1661101Y1671631D03*
X1651101Y1700478D03*
X1660541Y1704237D03*
X1677972Y25977D03*
X1676121Y19541D03*
X1675972Y23981D03*
X1671016D03*
X1669016Y25977D03*
X1677040Y37106D03*
X1669953D03*
X1677040Y48720D03*
X1669953D03*
X1677204Y75340D03*
X1672960Y71839D03*
X1667980Y66847D03*
X1672960D03*
X1667980Y71839D03*
X1666070Y69340D03*
X1663610Y394727D03*
X1664789Y756765D03*
Y763765D03*
X1669339Y773563D03*
X1673739Y791969D03*
X1663889Y786949D03*
X1669339Y780256D03*
X1663889Y796988D03*
X1669339Y803681D03*
Y810374D03*
Y817067D03*
X1673739Y828780D03*
X1663889Y823760D03*
Y833799D03*
X1669339Y840492D03*
Y847185D03*
X1673739Y865591D03*
X1663889Y860571D03*
X1669339Y853878D03*
X1663889Y870610D03*
X1669339Y877303D03*
Y883996D03*
Y890689D03*
X1673739Y902402D03*
X1663889Y897382D03*
Y907422D03*
X1669339Y914114D03*
Y920807D03*
X1673739Y939213D03*
X1663889Y934193D03*
X1669339Y927500D03*
X1663889Y944233D03*
X1669339Y950925D03*
Y957618D03*
Y964311D03*
Y971004D03*
Y977697D03*
Y984390D03*
Y991083D03*
Y997776D03*
Y1004469D03*
Y1031240D03*
Y1037933D03*
Y1044626D03*
Y1051319D03*
Y1058012D03*
Y1068051D03*
Y1074744D03*
X1673739Y1086457D03*
X1663889Y1081437D03*
Y1091477D03*
X1669339Y1098170D03*
Y1104862D03*
X1663889Y1118248D03*
X1669339Y1111555D03*
X1673739Y1123268D03*
X1663889Y1128288D03*
X1669339Y1134981D03*
Y1141674D03*
Y1148366D03*
X1673739Y1160079D03*
X1663889Y1155059D03*
Y1165099D03*
X1669339Y1171792D03*
Y1178485D03*
X1663889Y1191870D03*
X1669339Y1185177D03*
X1673739Y1196890D03*
X1663889Y1201910D03*
X1669339Y1208603D03*
Y1215296D03*
Y1221988D03*
X1673739Y1233701D03*
X1663889Y1228681D03*
Y1238721D03*
X1669339Y1245414D03*
Y1252107D03*
X1675187Y1298735D03*
Y1303935D03*
Y1306535D03*
Y1301335D03*
X1674831Y1351266D03*
Y1348366D03*
X1675901Y1377594D03*
Y1380551D03*
X1666870Y1384570D03*
X1664440D03*
X1675510Y1374723D03*
X1667966Y1374707D03*
X1670566D03*
X1665366Y1377814D03*
Y1380771D03*
Y1374707D03*
X1667966Y1377814D03*
Y1380771D03*
X1673066Y1374707D03*
X1666870Y1390170D03*
X1664440D03*
X1666919Y1402585D03*
X1671067Y1405418D03*
X1672277Y1407694D03*
X1674777D03*
X1672907Y1429928D03*
X1672273Y1420567D03*
X1666290Y1444391D03*
X1667360Y1485895D03*
X1669270Y1483295D03*
X1674050D03*
X1669270Y1488495D03*
X1674050D03*
X1673674Y1563575D03*
X1670248Y1581563D03*
X1670534Y1670149D03*
X1673245Y1673475D03*
X1664256Y1690794D03*
X1673132Y1690741D03*
X1665520Y1716877D03*
Y1732027D03*
X1682965Y3001D03*
X1692262Y17045D03*
X1678088D03*
X1683068D03*
X1692262Y22037D03*
X1692145Y25977D03*
X1678088Y22037D03*
X1683068D03*
X1690294Y19541D03*
X1685077D03*
X1690145Y23981D03*
X1685189D03*
X1683189Y25977D03*
X1684127Y37106D03*
X1691213D03*
Y48720D03*
X1684127D03*
X1679114Y72847D03*
X1688200Y69343D03*
X1690114Y66850D03*
Y71842D03*
X1684094Y72847D03*
X1679114Y77839D03*
X1684094D03*
X1687448Y756765D03*
Y760265D03*
X1682898Y776910D03*
X1687448Y767265D03*
X1682898Y783603D03*
X1687298Y795315D03*
X1682898Y807028D03*
Y820414D03*
Y813721D03*
X1687298Y832126D03*
X1682898Y850532D03*
Y843839D03*
Y857225D03*
X1687298Y868937D03*
X1682898Y880650D03*
Y894036D03*
Y887343D03*
X1687298Y905749D03*
X1682898Y917461D03*
Y924154D03*
Y930847D03*
X1687298Y942560D03*
X1682898Y954272D03*
Y967658D03*
Y960965D03*
Y981044D03*
Y974351D03*
Y994429D03*
Y987736D03*
Y1004469D03*
Y1041280D03*
Y1034587D03*
Y1054666D03*
Y1047973D03*
Y1061359D03*
Y1071398D03*
Y1078091D03*
X1687298Y1089804D03*
X1682898Y1101516D03*
Y1108209D03*
Y1114902D03*
X1687298Y1126615D03*
X1682898Y1138327D03*
Y1145020D03*
Y1151713D03*
X1687298Y1163426D03*
X1682898Y1175138D03*
Y1188524D03*
Y1181831D03*
X1687298Y1200237D03*
X1682898Y1211949D03*
Y1218642D03*
Y1225335D03*
X1687298Y1237048D03*
X1682898Y1248760D03*
Y1255453D03*
X1684708Y1298435D03*
Y1303635D03*
Y1306235D03*
Y1301035D03*
X1687233Y1351320D03*
X1679133Y1351420D03*
X1687233Y1348420D03*
X1679133Y1348520D03*
X1679180Y1372169D03*
X1681780D03*
X1679180Y1366969D03*
X1681780D03*
Y1369569D03*
X1679180D03*
X1683896Y1378765D03*
X1692948Y1377914D03*
Y1374807D03*
X1680530Y1374669D03*
X1685963Y1402187D03*
X1687621Y1404138D03*
X1684172Y1538135D03*
X1682561Y1552726D03*
X1691226Y1563526D03*
X1680558Y1555690D03*
X1691226Y1559526D03*
X1682494Y1568271D03*
Y1575125D03*
X1680491Y1578089D03*
Y1571235D03*
X1689880Y1572067D03*
X1679420Y1683597D03*
X1683013Y1713684D03*
X1680519Y1726825D03*
X1689383Y1729187D03*
X1704965Y3001D03*
X1697242Y17045D03*
X1699250Y19541D03*
X1697242Y22037D03*
X1698300Y37106D03*
X1705381Y37108D03*
X1698300Y48720D03*
X1705386D03*
X1701114Y72847D03*
X1706094D03*
X1699204Y75340D03*
X1695094Y66850D03*
Y71842D03*
X1706094Y77839D03*
X1701114D03*
X1694490Y756765D03*
Y763765D03*
X1699040Y773563D03*
X1703440Y791969D03*
X1699040Y780256D03*
X1693590Y786949D03*
X1699040Y803681D03*
X1693590Y796988D03*
X1699040Y817067D03*
Y810374D03*
X1693590Y823760D03*
X1703440Y828780D03*
X1693590Y833799D03*
X1699040Y847185D03*
Y840492D03*
Y853878D03*
X1693590Y860571D03*
X1703440Y865591D03*
X1693590Y870610D03*
X1699040Y877303D03*
Y883996D03*
Y890689D03*
X1693590Y907422D03*
X1703440Y902402D03*
X1693590Y897382D03*
X1699040Y914114D03*
Y920807D03*
X1693590Y934193D03*
X1699040Y927500D03*
X1703440Y939213D03*
X1693590Y944233D03*
X1699040Y950925D03*
Y964311D03*
Y971004D03*
Y957618D03*
Y977697D03*
Y984390D03*
Y997776D03*
Y991083D03*
Y1004469D03*
Y1044626D03*
Y1037933D03*
Y1031240D03*
Y1058012D03*
Y1051319D03*
Y1074744D03*
Y1068051D03*
X1703440Y1086457D03*
X1693590Y1081437D03*
Y1091477D03*
X1699040Y1104862D03*
Y1098170D03*
Y1111555D03*
X1693590Y1118248D03*
X1699040Y1134981D03*
X1703440Y1123268D03*
X1693590Y1128288D03*
X1699040Y1141674D03*
Y1148366D03*
X1693590Y1155059D03*
Y1165099D03*
X1703440Y1160079D03*
X1699040Y1171792D03*
Y1178485D03*
X1693590Y1191870D03*
X1699040Y1185177D03*
X1693590Y1201910D03*
X1703440Y1196890D03*
X1699040Y1208603D03*
Y1221988D03*
Y1215296D03*
X1693590Y1228681D03*
Y1238721D03*
X1703440Y1233701D03*
X1699040Y1245414D03*
Y1252107D03*
X1699087Y1298435D03*
Y1303635D03*
Y1306235D03*
Y1301035D03*
X1695533Y1351320D03*
Y1348420D03*
X1694792Y1384670D03*
X1700748Y1377914D03*
Y1380871D03*
Y1374807D03*
X1703348D03*
X1705848D03*
X1698148Y1377914D03*
X1695548D03*
X1698148Y1380871D03*
X1695548Y1374807D03*
X1698148D03*
X1699652Y1384670D03*
X1697222D03*
X1699652Y1390270D03*
X1694792D03*
X1697222D03*
X1699701Y1402685D03*
X1700520Y1716877D03*
X1702777Y1723593D03*
X1695166Y1717606D03*
X1720148Y22910D03*
X1710886Y82208D03*
X1715550Y102923D03*
X1721400Y374462D03*
X1718241Y652105D03*
X1717149Y756765D03*
Y760265D03*
X1712599Y776910D03*
X1717149Y767265D03*
X1712599Y783603D03*
Y807028D03*
X1716999Y795315D03*
X1712599Y820414D03*
Y813721D03*
X1716999Y832126D03*
X1712599Y850532D03*
Y843839D03*
Y857225D03*
X1716999Y868937D03*
X1712599Y880650D03*
Y894036D03*
Y887343D03*
X1716999Y905749D03*
X1712599Y917461D03*
Y924154D03*
Y930847D03*
X1716999Y942560D03*
X1712599Y954272D03*
Y967658D03*
Y960965D03*
Y981044D03*
Y974351D03*
Y994429D03*
Y987736D03*
Y1004469D03*
Y1041280D03*
Y1034587D03*
Y1054666D03*
Y1047973D03*
Y1061359D03*
Y1071398D03*
Y1078091D03*
X1716999Y1089804D03*
X1712599Y1101516D03*
Y1108209D03*
Y1114902D03*
X1716999Y1126615D03*
X1712599Y1138327D03*
Y1145020D03*
Y1151713D03*
X1716999Y1163426D03*
X1712599Y1175138D03*
Y1188524D03*
Y1181831D03*
X1716999Y1200237D03*
X1712599Y1218642D03*
Y1211949D03*
Y1225335D03*
X1716999Y1237048D03*
X1712599Y1248760D03*
Y1255453D03*
X1721754Y1299488D03*
X1708754Y1298388D03*
X1721847Y1307298D03*
X1721754Y1304688D03*
X1708754Y1300988D03*
X1721754Y1302088D03*
X1708754Y1303588D03*
Y1306188D03*
X1718813Y1348450D03*
Y1351350D03*
X1709533Y1351520D03*
Y1348620D03*
X1711962Y1367069D03*
X1714562D03*
X1711962Y1369669D03*
X1714562D03*
X1719902Y1368509D03*
Y1365909D03*
Y1363409D03*
X1708678Y1380621D03*
Y1377664D03*
X1716267Y1375178D03*
X1713312Y1374769D03*
X1708292Y1374823D03*
X1720210Y1435330D03*
X1719893Y1594940D03*
Y1612940D03*
Y1599740D03*
Y1603040D03*
Y1606340D03*
Y1609640D03*
X1722133Y1725340D03*
X1727111Y-38849D03*
Y-28849D03*
X1726965Y3001D03*
X1732286Y28208D03*
X1728786D03*
X1725286D03*
X1727336Y57024D03*
X1726596Y61784D03*
X1729836Y57024D03*
X1726596Y64284D03*
X1726814Y102968D03*
X1733344Y134953D03*
X1736474D03*
X1730364Y177588D03*
X1725400Y372062D03*
X1737260Y368132D03*
X1732660Y372692D03*
X1725500Y383662D03*
X1723259Y653641D03*
X1726334Y670345D03*
X1724191Y756765D03*
Y763765D03*
X1728741Y773563D03*
X1733141Y791969D03*
X1723291Y786949D03*
X1728741Y780256D03*
Y803681D03*
X1723291Y796988D03*
X1728741Y817067D03*
Y810374D03*
X1733141Y828780D03*
X1723291Y823760D03*
Y833799D03*
X1728741Y847185D03*
Y840492D03*
Y853878D03*
X1733141Y865591D03*
X1723291Y860571D03*
Y870610D03*
X1728741Y877303D03*
Y883996D03*
Y890689D03*
X1723291Y907422D03*
X1733141Y902402D03*
X1723291Y897382D03*
X1728741Y914114D03*
Y920807D03*
X1723291Y934193D03*
X1728741Y927500D03*
X1733141Y939213D03*
X1723291Y944233D03*
X1728741Y950925D03*
Y964311D03*
Y971004D03*
Y957618D03*
Y977697D03*
Y984390D03*
Y997776D03*
Y991083D03*
Y1004469D03*
Y1044626D03*
Y1037933D03*
Y1031240D03*
Y1058012D03*
Y1051319D03*
Y1074744D03*
Y1068051D03*
X1733141Y1086457D03*
X1723291Y1081437D03*
Y1091477D03*
X1728741Y1104862D03*
Y1098170D03*
Y1111555D03*
X1723291Y1118248D03*
X1728741Y1134981D03*
X1733141Y1123268D03*
X1723291Y1128288D03*
X1728741Y1141674D03*
Y1148366D03*
X1723291Y1155059D03*
X1733141Y1160079D03*
X1723291Y1165099D03*
X1728741Y1171792D03*
Y1178485D03*
X1723291Y1191870D03*
X1728741Y1185177D03*
X1723291Y1201910D03*
X1733141Y1196890D03*
X1728741Y1208603D03*
Y1221988D03*
Y1215296D03*
X1733141Y1233701D03*
X1723291Y1228681D03*
Y1238721D03*
X1728741Y1245414D03*
Y1252107D03*
X1732624Y1299718D03*
X1732717Y1307528D03*
X1732624Y1302318D03*
Y1304918D03*
X1735202Y1368279D03*
Y1365679D03*
Y1363179D03*
X1723917Y1380518D03*
Y1377178D03*
X1737126Y1403838D03*
Y1401238D03*
X1722810Y1435330D03*
X1737541Y1543707D03*
X1734575Y1562068D03*
X1724323Y1676965D03*
X1748965Y3001D03*
X1752008Y25146D03*
X1748116Y37058D03*
X1745451Y119585D03*
X1747448Y121413D03*
X1750325Y179827D03*
X1750851Y216427D03*
X1748325D03*
X1752461Y255337D03*
Y252337D03*
X1742652Y671494D03*
X1746850Y756765D03*
Y760265D03*
X1742300Y776910D03*
X1746850Y767265D03*
X1742300Y783603D03*
X1746700Y795315D03*
X1742300Y807028D03*
Y820414D03*
Y813721D03*
X1746700Y832126D03*
X1742300Y850532D03*
Y843839D03*
Y857225D03*
X1746700Y868937D03*
X1742300Y880650D03*
Y894036D03*
Y887343D03*
X1746700Y905749D03*
X1742300Y917461D03*
Y924154D03*
Y930847D03*
X1746700Y942560D03*
X1742300Y954272D03*
Y960965D03*
Y967658D03*
Y981044D03*
Y974351D03*
Y994429D03*
Y987736D03*
Y1004469D03*
Y1041280D03*
Y1034587D03*
Y1054666D03*
Y1047973D03*
Y1061359D03*
Y1071398D03*
Y1078091D03*
X1746700Y1089804D03*
X1742300Y1101516D03*
Y1108209D03*
Y1114902D03*
X1746700Y1126615D03*
X1742300Y1138327D03*
Y1145020D03*
Y1151713D03*
X1746700Y1163426D03*
X1742300Y1175138D03*
Y1188524D03*
Y1181831D03*
X1746700Y1200237D03*
X1742300Y1218642D03*
Y1211949D03*
Y1225335D03*
X1746700Y1237048D03*
X1742300Y1248760D03*
Y1255453D03*
X1743072Y1432211D03*
X1743188Y1543871D03*
Y1547871D03*
X1740587Y1547946D03*
X1737738Y1548021D03*
X1740400Y1543682D03*
X1752364Y1556323D03*
Y1559430D03*
X1744564Y1556323D03*
Y1559430D03*
X1749764Y1556323D03*
Y1559430D03*
X1747164Y1556323D03*
Y1559430D03*
X1752564Y1562537D03*
X1751518Y1566186D03*
X1740079Y1559505D03*
X1740188Y1556371D03*
X1746558Y1566186D03*
X1749038D03*
X1749964Y1562537D03*
X1751518Y1571786D03*
X1746558D03*
X1749038D03*
X1739640Y1713383D03*
Y1728533D03*
X1762420Y17031D03*
X1763840Y37790D03*
X1753398Y48720D03*
X1760485D03*
X1759666Y57708D03*
X1764366Y57508D03*
X1758047Y68637D03*
X1758539Y87153D03*
Y83653D03*
X1758534Y79743D03*
X1765034Y80443D03*
X1766244Y93673D03*
X1766911Y179890D03*
X1752851Y179827D03*
X1757385Y179890D03*
X1764385D03*
X1759911D03*
X1757951Y216427D03*
X1755425D03*
X1762485Y216490D03*
X1765011D03*
X1758859Y251544D03*
Y248544D03*
X1766399Y251361D03*
Y248361D03*
X1753892Y756765D03*
Y763765D03*
X1758442Y773563D03*
X1762842Y791969D03*
X1752992Y786949D03*
X1758442Y780256D03*
Y803681D03*
X1752992Y796988D03*
X1758442Y817067D03*
Y810374D03*
X1752992Y823760D03*
Y833799D03*
X1762842Y828780D03*
X1758442Y847185D03*
Y840492D03*
X1752992Y860571D03*
X1758442Y853878D03*
X1762842Y865591D03*
X1752992Y870610D03*
X1758442Y877303D03*
Y883996D03*
Y890689D03*
X1752992Y907422D03*
Y897382D03*
X1762842Y902402D03*
X1758442Y914114D03*
Y920807D03*
X1752992Y934193D03*
X1758442Y927500D03*
X1762842Y939213D03*
X1752992Y944233D03*
X1758442Y950925D03*
Y964311D03*
Y971004D03*
Y957618D03*
Y977697D03*
Y984390D03*
Y997776D03*
Y991083D03*
Y1004469D03*
Y1044626D03*
Y1037933D03*
Y1031240D03*
Y1058012D03*
Y1051319D03*
Y1074744D03*
Y1068051D03*
X1752992Y1081437D03*
X1762842Y1086457D03*
X1752992Y1091477D03*
X1758442Y1104862D03*
Y1098170D03*
X1752992Y1118248D03*
X1758442Y1111555D03*
Y1134981D03*
X1752992Y1128288D03*
X1762842Y1123268D03*
X1758442Y1141674D03*
Y1148366D03*
X1752992Y1155059D03*
Y1165099D03*
X1762842Y1160079D03*
X1758442Y1171792D03*
Y1178485D03*
X1752992Y1191870D03*
X1758442Y1185177D03*
X1752992Y1201910D03*
X1762842Y1196890D03*
X1758442Y1208603D03*
Y1221988D03*
Y1215296D03*
X1752992Y1228681D03*
Y1238721D03*
X1762842Y1233701D03*
X1758442Y1245414D03*
Y1252107D03*
X1758238Y1556238D03*
X1761108Y1556339D03*
Y1559446D03*
X1761079Y1562605D03*
X1755038Y1556238D03*
X1765709Y1556050D03*
X1754479Y1585905D03*
X1754763Y1641665D03*
X1752864Y1716383D03*
X1770965Y3001D03*
X1772886Y37430D03*
X1768134Y80543D03*
X1771385Y179890D03*
X1773911D03*
X1778500Y183790D03*
X1769585Y215090D03*
X1772111D03*
X1776585D03*
X1779111D03*
X1778874Y253799D03*
Y256799D03*
X1770520Y364148D03*
Y368148D03*
X1771236Y557224D03*
X1776550Y756765D03*
Y760265D03*
X1772000Y776910D03*
X1776550Y767265D03*
X1772000Y783603D03*
Y807028D03*
X1776400Y795315D03*
X1772000Y813721D03*
Y820414D03*
X1776400Y832126D03*
X1772000Y850532D03*
Y843839D03*
Y857225D03*
X1776400Y868937D03*
X1772000Y880650D03*
Y894036D03*
Y887343D03*
X1776400Y905749D03*
X1772000Y917461D03*
Y924154D03*
Y930847D03*
X1776400Y942560D03*
X1772000Y954272D03*
Y967658D03*
Y960965D03*
Y981044D03*
Y974351D03*
Y994429D03*
Y987736D03*
Y1004469D03*
Y1041280D03*
Y1034587D03*
Y1047973D03*
Y1054666D03*
Y1061359D03*
Y1071398D03*
Y1078091D03*
X1776400Y1089804D03*
X1772000Y1101516D03*
Y1108209D03*
Y1114902D03*
X1776400Y1126615D03*
X1772000Y1138327D03*
Y1145020D03*
Y1151713D03*
X1776400Y1163426D03*
X1772000Y1175138D03*
Y1188524D03*
Y1181831D03*
X1776400Y1200237D03*
X1772000Y1218642D03*
Y1211949D03*
Y1225335D03*
X1776400Y1237048D03*
X1772000Y1248760D03*
Y1255453D03*
X1776188Y1543871D03*
Y1546871D03*
X1769188D03*
Y1543871D03*
X1768688Y1552871D03*
Y1549871D03*
X1772688Y1543871D03*
Y1546871D03*
X1776113Y1541172D03*
X1769113D03*
X1772613D03*
X1780307Y1559430D03*
Y1556323D03*
X1775979Y1556805D03*
Y1559805D03*
X1782301Y1566186D03*
X1768209Y1556000D03*
X1769826Y1562559D03*
X1782301Y1571786D03*
X1792965Y3001D03*
X1796781Y46686D03*
X1785144Y86973D03*
Y89973D03*
X1783448Y212957D03*
X1795794Y253719D03*
X1787534Y253769D03*
X1795794Y256719D03*
X1787534Y256769D03*
X1795479Y408056D03*
X1795468Y421334D03*
X1783592Y756765D03*
X1788142Y773563D03*
X1792542Y791969D03*
X1782692Y786949D03*
X1788142Y780256D03*
X1782692Y796988D03*
X1788142Y803681D03*
Y817067D03*
Y810374D03*
X1782692Y823760D03*
Y833799D03*
X1792542Y828780D03*
X1788142Y847185D03*
Y840492D03*
Y853878D03*
X1792542Y865591D03*
X1782692Y860571D03*
Y870610D03*
X1788142Y877303D03*
Y883996D03*
Y890689D03*
X1782692Y907422D03*
Y897382D03*
X1792542Y902402D03*
X1788142Y914114D03*
Y920807D03*
X1782692Y934193D03*
X1788142Y927500D03*
X1792542Y939213D03*
X1782692Y944233D03*
X1788142Y950925D03*
Y964311D03*
Y971004D03*
Y957618D03*
Y977697D03*
Y984390D03*
Y997776D03*
Y991083D03*
Y1004469D03*
Y1044626D03*
Y1037933D03*
Y1031240D03*
Y1058012D03*
Y1051319D03*
Y1074744D03*
Y1068051D03*
X1782692Y1081437D03*
X1792542Y1086457D03*
X1782692Y1091477D03*
X1788142Y1098170D03*
Y1104862D03*
X1782692Y1118248D03*
X1788142Y1111555D03*
Y1134981D03*
X1782692Y1128288D03*
X1792542Y1123268D03*
X1788142Y1141674D03*
Y1148366D03*
X1782692Y1155059D03*
Y1165099D03*
X1792542Y1160079D03*
X1788142Y1171792D03*
Y1178485D03*
X1782692Y1191870D03*
X1788142Y1185177D03*
X1782692Y1201910D03*
X1792542Y1196890D03*
X1788142Y1208603D03*
Y1221988D03*
Y1215296D03*
X1782692Y1228681D03*
Y1238721D03*
X1792542Y1233701D03*
X1788142Y1245414D03*
Y1252107D03*
X1796838Y1556125D03*
X1788107Y1556323D03*
X1793833Y1556195D03*
X1790633D03*
X1788107Y1559430D03*
X1788307Y1562537D03*
X1787261Y1566186D03*
X1782907Y1559430D03*
Y1556323D03*
X1784781Y1566186D03*
X1785507Y1559430D03*
Y1556323D03*
X1785707Y1562537D03*
X1796257Y1561255D03*
Y1558755D03*
X1787261Y1571786D03*
X1784781D03*
X1788679Y1585805D03*
X1807515Y56461D03*
X1807546Y59443D03*
X1807296Y255033D03*
X1804174Y253739D03*
Y256739D03*
X1803129Y362293D03*
X1802929Y385293D03*
X1804688Y1545871D03*
Y1542371D03*
Y1552871D03*
Y1549371D03*
X1801688Y1545871D03*
Y1542371D03*
Y1552871D03*
Y1549371D03*
X1804688Y1555871D03*
X1801688D03*
X1804688Y1559371D03*
X1818615Y49379D03*
X1818155Y149325D03*
X1819529Y320321D03*
X1820307Y373829D03*
X1820656Y388051D03*
X1820144Y398052D03*
X1819374Y410432D03*
X1818874Y423932D03*
X1840615Y49379D03*
X1853692Y308447D03*
G54D40*
X311115Y1214093D03*
X310957Y1219126D03*
X388805Y1218420D03*
X388647Y1223453D03*
X386461Y1235718D03*
X386303Y1240751D03*
X1898799Y1810398D03*
X1908799D03*
X1931395Y572237D03*
X1921395D03*
X1942395Y1184617D03*
X1940886Y1810370D03*
X1963362Y572379D03*
X1952395Y1184617D03*
X1950886Y1810370D03*
X1973362Y572379D03*
X1984482Y1184589D03*
X1992856Y1810550D03*
X1982856D03*
X2005452Y572389D03*
X1994482Y1184589D03*
X2015452Y572389D03*
X2036452Y1184769D03*
X2026452D03*
X2047419Y572531D03*
X2057419D03*
X2078539Y1184741D03*
X2068539D03*
G54D56*
X828780Y1684890D03*
X818780D03*
X828780Y1694890D03*
X818780D03*
X828780Y1704890D03*
X818780D03*
X828780Y1714890D03*
X818780D03*
X853780Y1684890D03*
Y1694890D03*
Y1704890D03*
Y1714890D03*
X863780Y1684890D03*
Y1694890D03*
Y1704890D03*
Y1714890D03*
X888780Y1684890D03*
Y1694890D03*
Y1704890D03*
Y1714890D03*
X898780Y1684890D03*
Y1694890D03*
Y1704890D03*
Y1714890D03*
X918780Y1704890D03*
X958780Y1684890D03*
Y1694890D03*
Y1704890D03*
Y1714890D03*
X968780Y1684890D03*
Y1694890D03*
Y1704890D03*
Y1714890D03*
X993780Y1684890D03*
Y1694890D03*
Y1704890D03*
Y1714890D03*
X1003780Y1684890D03*
Y1694890D03*
Y1704890D03*
Y1714890D03*
X1028780Y1684890D03*
X1038780D03*
X1028780Y1694890D03*
X1038780D03*
X1028780Y1704890D03*
Y1714890D03*
X1038780Y1704890D03*
Y1714890D03*
G54D29*
X182947Y1507512D03*
X186530Y1521453D03*
X185688Y1519195D03*
X186860Y1514243D03*
X186579Y1536063D03*
X177579Y1528725D03*
Y1523810D03*
X183051Y1542425D03*
X185966Y1592380D03*
Y1624292D03*
X188254Y1507295D03*
X192979D03*
X197703D03*
X191254Y1521453D03*
X195979D03*
X200703D03*
X196309Y1514243D03*
X201033D03*
X191584D03*
X187081Y1528853D03*
X191805D03*
X196530D03*
X201254D03*
X196029Y1536063D03*
X200753D03*
X191304D03*
X197703Y1542641D03*
X188254D03*
X192979D03*
X198026Y1592380D03*
X193766D03*
X192006Y1602380D03*
X199786D03*
X193766Y1624292D03*
X198026D03*
X199786Y1614292D03*
X192006D03*
X202427Y1507295D03*
X207152D03*
X211876D03*
X216601D03*
X205427Y1521453D03*
X210152D03*
X214876D03*
X205758Y1514243D03*
X215206D03*
X210482D03*
X205978Y1528853D03*
X210703D03*
X215427D03*
X214926Y1536063D03*
X211876Y1542641D03*
X202427D03*
X207152D03*
X216601D03*
X210086Y1592380D03*
X205826D03*
X216126Y1602380D03*
X204066D03*
X211846D03*
X205826Y1624292D03*
X210086D03*
X216126Y1614292D03*
X211846D03*
X204066D03*
X221325Y1507295D03*
X226049D03*
X230774D03*
X219601Y1521453D03*
X224325D03*
X229049D03*
X219931Y1514243D03*
X224655D03*
X229380D03*
X220152Y1528853D03*
X224876D03*
X229600D03*
X224375Y1536063D03*
X226049Y1542641D03*
X230774D03*
X221325D03*
X229946Y1592380D03*
X217886D03*
X222146D03*
X223906Y1602380D03*
X228186D03*
X229946Y1624292D03*
X222146D03*
X217886D03*
X228186Y1614292D03*
X223906D03*
X235498Y1507295D03*
X240223D03*
X244947D03*
X243223Y1521453D03*
X238498D03*
X233774D03*
X234104Y1514243D03*
X238828D03*
X243553D03*
X243774Y1528853D03*
X239049D03*
X234325D03*
X238548Y1536063D03*
X240223Y1542641D03*
X235498D03*
X244947D03*
X242006Y1592380D03*
X234206D03*
X246266D03*
X235966Y1602380D03*
X240246D03*
X246266Y1624292D03*
X242006D03*
X234206D03*
X240246Y1614292D03*
X235966D03*
X241141Y1679320D03*
Y1683857D03*
X233267Y1675383D03*
Y1679920D03*
Y1684454D03*
X241141Y1688391D03*
Y1693493D03*
Y1698030D03*
X233267Y1689556D03*
Y1694093D03*
Y1698627D03*
X241141Y1702564D03*
Y1707666D03*
Y1712203D03*
Y1716737D03*
X233267Y1703729D03*
Y1708266D03*
Y1712800D03*
X241141Y1721840D03*
Y1726377D03*
Y1730911D03*
X233267Y1717903D03*
Y1722440D03*
Y1726974D03*
X259120Y1507295D03*
X249671D03*
X254396D03*
X257396Y1521453D03*
X252672D03*
X247947D03*
X248277Y1514243D03*
X257726D03*
X257947Y1528853D03*
X253223D03*
X248498D03*
X257446Y1536063D03*
X247997D03*
X254396Y1542641D03*
X259120D03*
X249671D03*
X258326Y1592380D03*
X254066D03*
X248026Y1602380D03*
X252306D03*
X260086D03*
X258326Y1624292D03*
X254066D03*
X248026Y1614292D03*
X252306D03*
X260086D03*
X256889Y1679320D03*
Y1683857D03*
X249015Y1684454D03*
Y1679920D03*
Y1675383D03*
X256889Y1688391D03*
Y1693493D03*
Y1698030D03*
X249015Y1698627D03*
Y1694093D03*
Y1689556D03*
X256889Y1702564D03*
Y1707666D03*
Y1712203D03*
Y1716737D03*
X249015Y1712800D03*
Y1708266D03*
Y1703729D03*
X256889Y1721840D03*
Y1726377D03*
Y1730911D03*
X249015Y1726974D03*
Y1722440D03*
Y1717903D03*
X262141Y1521453D03*
X262777Y1536063D03*
X270386Y1592380D03*
X266126D03*
X264366Y1602380D03*
X272146D03*
X270386Y1624292D03*
X266126D03*
X272146Y1614292D03*
X264366D03*
X272637Y1679320D03*
Y1683857D03*
X264763Y1684454D03*
Y1679920D03*
Y1675383D03*
X272637Y1688391D03*
Y1693493D03*
Y1698030D03*
X264763Y1698627D03*
Y1694093D03*
Y1689556D03*
X272637Y1702564D03*
Y1707666D03*
Y1712203D03*
Y1716737D03*
X264763Y1712800D03*
Y1708266D03*
Y1703729D03*
X272637Y1721840D03*
Y1726377D03*
Y1730911D03*
X264763Y1726974D03*
Y1722440D03*
Y1717903D03*
X290246Y1592380D03*
X278186D03*
X282446D03*
X276426Y1602380D03*
X284206D03*
X288486D03*
X290236Y1624292D03*
X282446D03*
X278186D03*
X288486Y1614292D03*
X284206D03*
X276426D03*
X288385Y1683857D03*
Y1679320D03*
X280511Y1684454D03*
Y1679920D03*
Y1675383D03*
X288385Y1688391D03*
Y1693494D03*
Y1698031D03*
X280511Y1698627D03*
Y1694093D03*
Y1689556D03*
X288385Y1712204D03*
Y1716738D03*
Y1702565D03*
Y1707667D03*
X280511Y1712800D03*
Y1708266D03*
Y1703729D03*
X288385Y1721840D03*
Y1726377D03*
Y1730911D03*
X280511Y1726974D03*
Y1722440D03*
Y1717903D03*
X305641Y1528725D03*
Y1523810D03*
X302306Y1592380D03*
X294506D03*
X296266Y1602380D03*
X300546D03*
X302306Y1624292D03*
X294516D03*
X300546Y1614292D03*
X296266D03*
X300196Y1675383D03*
Y1679920D03*
Y1684454D03*
Y1689556D03*
Y1694093D03*
Y1698627D03*
Y1703729D03*
Y1708266D03*
Y1712800D03*
Y1717903D03*
Y1722440D03*
Y1726974D03*
X309886Y1028056D03*
X315437Y1031245D03*
X317288Y1040812D03*
X309886D03*
X317288Y1034434D03*
X309886D03*
X315437Y1044001D03*
X309886Y1047190D03*
X311736Y1056757D03*
X309886Y1053568D03*
X315437Y1050379D03*
X317288Y1053568D03*
Y1059946D03*
X309886D03*
X313587D03*
X315437Y1063135D03*
X317288Y1072702D03*
X309886D03*
Y1066324D03*
X315437Y1069513D03*
X317288Y1079080D03*
X309886D03*
X315437Y1082269D03*
Y1088647D03*
X309886Y1085458D03*
Y1091836D03*
X317288D03*
X309886Y1104592D03*
X315437Y1101403D03*
X317288Y1098214D03*
X309886D03*
X315437Y1107781D03*
X309886Y1110970D03*
X317288D03*
X309886Y1117348D03*
X317288D03*
X309886Y1123726D03*
X315437Y1120537D03*
Y1126915D03*
X309886Y1130103D03*
X317288D03*
X309886Y1136481D03*
X315437Y1139670D03*
X317288Y1136481D03*
X309886Y1142859D03*
X317288Y1149237D03*
X309886D03*
X315437Y1146048D03*
X317288Y1155615D03*
X309886D03*
X313587D03*
X308036Y1158804D03*
X311736Y1165182D03*
X320988Y1155615D03*
Y1161993D03*
X311009Y1507514D03*
X316316Y1507295D03*
X321041D03*
X319316Y1521453D03*
X314592D03*
X313750Y1519195D03*
X314922Y1514243D03*
X319646D03*
X319867Y1528853D03*
X315143D03*
X319366Y1536063D03*
X314641D03*
X311113Y1542425D03*
X316316Y1542641D03*
X321041D03*
X318626Y1592380D03*
X306566D03*
X314366D03*
X308326Y1602380D03*
X312606D03*
X320386D03*
X314366Y1624292D03*
X318626D03*
X306566D03*
X320386Y1614292D03*
X312606D03*
X308326D03*
X315944Y1675383D03*
Y1679920D03*
Y1684454D03*
X308070Y1683857D03*
Y1679320D03*
X315944Y1689556D03*
Y1694093D03*
Y1698627D03*
X308070Y1698030D03*
Y1693493D03*
Y1688391D03*
X315944Y1703729D03*
Y1708266D03*
Y1712800D03*
X308070Y1716737D03*
Y1712203D03*
Y1707666D03*
Y1702564D03*
X315944Y1722440D03*
Y1726974D03*
X308070Y1730911D03*
Y1726377D03*
Y1721840D03*
X315944Y1717903D03*
X328390Y1028056D03*
X335791D03*
X322839Y1031245D03*
Y1037623D03*
Y1044001D03*
X328390Y1040812D03*
Y1034434D03*
X330240Y1031245D03*
Y1037623D03*
Y1044001D03*
X335791Y1040812D03*
Y1034434D03*
X328390Y1047190D03*
X322839Y1050379D03*
Y1056757D03*
X326539D03*
X328390Y1053568D03*
Y1059946D03*
X324689D03*
X330240Y1050379D03*
Y1056757D03*
X335791Y1047190D03*
Y1053568D03*
Y1059946D03*
X328390Y1072702D03*
X330240Y1069513D03*
X335791Y1072702D03*
Y1066324D03*
X322839Y1063135D03*
X330240D03*
X322839Y1069513D03*
X328390Y1066324D03*
X322839Y1075891D03*
X330240D03*
X328390Y1079080D03*
X322839Y1088647D03*
X328390Y1085458D03*
X330240Y1088647D03*
X322839Y1082269D03*
X330240D03*
X335791Y1079080D03*
Y1085458D03*
X328390Y1091836D03*
X322839Y1095025D03*
X330240D03*
X328390Y1104592D03*
Y1098214D03*
X322839Y1101403D03*
X330240D03*
X335791Y1091836D03*
Y1104592D03*
Y1098214D03*
X322839Y1107781D03*
X330240D03*
X328390Y1110970D03*
Y1117348D03*
X330240Y1114159D03*
X322839D03*
X335791Y1110970D03*
Y1117348D03*
X330240Y1126915D03*
X322839D03*
X328390Y1123726D03*
X330240Y1120537D03*
X322839D03*
Y1133293D03*
X330240D03*
X328390Y1130103D03*
X335791Y1123726D03*
X335792Y1130105D03*
X328390Y1142859D03*
X322839Y1139670D03*
X328390Y1136481D03*
X330240Y1139670D03*
X328390Y1149237D03*
X330240Y1146048D03*
X322839D03*
X335791Y1136481D03*
Y1142859D03*
Y1149237D03*
X328390Y1155615D03*
X330240Y1152426D03*
X322839D03*
X326539Y1158804D03*
X330240D03*
X333941D03*
X322839D03*
X328390Y1161993D03*
X330240Y1165182D03*
X335791Y1155615D03*
Y1161993D03*
X330489Y1507295D03*
X335214D03*
X325765D03*
X333489Y1521453D03*
X328765D03*
X324041D03*
X324371Y1514243D03*
X329095D03*
X333820D03*
X334040Y1528853D03*
X329316D03*
X324592D03*
X324091Y1536063D03*
X328815D03*
X325765Y1542641D03*
X330489D03*
X335214D03*
X330686Y1592380D03*
X326426D03*
X324666Y1602380D03*
X332446D03*
X326426Y1624292D03*
X330686D03*
X332446Y1614292D03*
X324666D03*
X331692Y1675383D03*
Y1679920D03*
Y1684454D03*
X323818Y1683857D03*
Y1679320D03*
X331692Y1689556D03*
Y1694093D03*
Y1698627D03*
X323818Y1698030D03*
Y1693493D03*
Y1688391D03*
X331692Y1703729D03*
Y1708266D03*
Y1712800D03*
X323818Y1716737D03*
Y1712203D03*
Y1707666D03*
Y1702564D03*
Y1721840D03*
X331692Y1717903D03*
Y1722440D03*
Y1726974D03*
X323818Y1730911D03*
Y1726377D03*
X348744Y1031245D03*
X341343D03*
X343193Y1040812D03*
X348744Y1037623D03*
X343193Y1034434D03*
X348744Y1044001D03*
X341343D03*
X350595Y1059946D03*
X337642Y1056757D03*
X348744D03*
X343193Y1053568D03*
X341343Y1050379D03*
X348744D03*
X343193Y1059946D03*
X339492D03*
X341343Y1063135D03*
X348744D03*
X341343Y1069513D03*
X343193Y1072702D03*
X348744Y1069513D03*
X343193Y1079080D03*
X348744Y1075891D03*
X341343Y1082269D03*
X348744D03*
X341343Y1088647D03*
X348744D03*
Y1095025D03*
X343193Y1091836D03*
X348744Y1101403D03*
X341343D03*
X343193Y1098214D03*
X341343Y1107781D03*
X348744D03*
X343193Y1110970D03*
Y1117348D03*
X348744Y1114159D03*
Y1120537D03*
X341343D03*
Y1126915D03*
X348744D03*
Y1133293D03*
X343193Y1130103D03*
X341343Y1139670D03*
X343193Y1136481D03*
X348744Y1139670D03*
X343193Y1149237D03*
X348744Y1146048D03*
X341343D03*
X348744Y1152426D03*
X337642Y1158804D03*
X341343D03*
X348744D03*
X339492Y1155615D03*
X343193D03*
X346894D03*
X337642Y1165182D03*
X343193Y1161993D03*
X346894D03*
X348744Y1165182D03*
X339938Y1507295D03*
X344663D03*
X349387D03*
X347663Y1521453D03*
X342938D03*
X338214D03*
X338544Y1514243D03*
X343268D03*
X347993D03*
X348214Y1528853D03*
X343489D03*
X338765D03*
X342988Y1536063D03*
X339938Y1542641D03*
X344663D03*
X349387D03*
X338486Y1592380D03*
X342746D03*
X350546D03*
X336726Y1602380D03*
X344506D03*
X348786D03*
X350546Y1624292D03*
X342746D03*
X338486D03*
X348786Y1614292D03*
X344506D03*
X336726D03*
X347440Y1675383D03*
Y1679920D03*
Y1684454D03*
X339566Y1683857D03*
Y1679320D03*
X347440Y1694093D03*
Y1698627D03*
X339566Y1698030D03*
Y1693493D03*
Y1688391D03*
X347440Y1689556D03*
Y1703729D03*
Y1708266D03*
Y1712800D03*
X339566Y1716737D03*
Y1712203D03*
Y1707666D03*
Y1702564D03*
X347440Y1717903D03*
Y1722440D03*
Y1726974D03*
X339566Y1730911D03*
Y1726377D03*
Y1721840D03*
X354295Y1028056D03*
X361697D03*
Y1040812D03*
X356146Y1044001D03*
X354295Y1040812D03*
Y1034434D03*
X356146Y1031245D03*
Y1037623D03*
X361697Y1034434D03*
X354295Y1047190D03*
X361697D03*
X354295Y1053568D03*
Y1059946D03*
X363547Y1056757D03*
X356146D03*
Y1050379D03*
X361697Y1053568D03*
X365398Y1059946D03*
X361697D03*
X352445Y1056757D03*
X356146Y1063135D03*
X354295Y1072702D03*
Y1066324D03*
X356146Y1069513D03*
X361697Y1066324D03*
Y1072702D03*
X356146Y1075891D03*
X354295Y1079080D03*
X361697D03*
X354295Y1085458D03*
X356146Y1088647D03*
X361697Y1085458D03*
X356146Y1082269D03*
X354295Y1091836D03*
X361697D03*
X356146Y1095025D03*
X354295Y1104592D03*
Y1098214D03*
X361697Y1104592D03*
X356146Y1101403D03*
X361697Y1098214D03*
X356146Y1107781D03*
X354295Y1110970D03*
X361697D03*
Y1117348D03*
X356146Y1114159D03*
X354295Y1117348D03*
Y1123726D03*
X356146Y1126915D03*
Y1120537D03*
X361697Y1123726D03*
X356146Y1133293D03*
X361697Y1130103D03*
X354296Y1130105D03*
X354295Y1136481D03*
X356146Y1139670D03*
X361697Y1136481D03*
X354295Y1142859D03*
X361697D03*
Y1149237D03*
X356146Y1146048D03*
X354295Y1149237D03*
X363547Y1165182D03*
X356146D03*
X361697Y1161993D03*
X363547Y1158804D03*
X356146D03*
X359847D03*
X352445D03*
X365398Y1155615D03*
X356146Y1152426D03*
X361697Y1155615D03*
X354295D03*
Y1161993D03*
X354111Y1507295D03*
X358836D03*
X363560D03*
X361836Y1521453D03*
X357111D03*
X352387D03*
X352717Y1514243D03*
X357442D03*
X362166D03*
X362387Y1528853D03*
X357662D03*
X352938D03*
X352437Y1536063D03*
X354111Y1542641D03*
X358836D03*
X363560D03*
X362606Y1592380D03*
X354806D03*
X356566Y1602380D03*
X360846D03*
X354806Y1624292D03*
X360846Y1614292D03*
X356566D03*
X362606Y1624292D03*
X355314Y1683857D03*
Y1679320D03*
Y1688391D03*
Y1698030D03*
Y1693493D03*
Y1716737D03*
Y1712203D03*
Y1707666D03*
Y1702564D03*
Y1730911D03*
Y1726377D03*
Y1721840D03*
X380201Y1028056D03*
X367248Y1031245D03*
Y1044001D03*
X369099Y1034434D03*
Y1040812D03*
X374650Y1031245D03*
X380201Y1040812D03*
Y1034434D03*
X374650Y1037623D03*
Y1044001D03*
X367248Y1050379D03*
X380201Y1047190D03*
X369099Y1053568D03*
Y1059946D03*
X380201Y1053568D03*
X378351Y1056757D03*
X374650Y1050379D03*
Y1056757D03*
X380201Y1059946D03*
X376500D03*
X367248Y1063135D03*
Y1069513D03*
X374650Y1063135D03*
X369099Y1072702D03*
X380201D03*
X374650Y1069513D03*
X367248Y1088647D03*
Y1082269D03*
X374650Y1075891D03*
X369099Y1079080D03*
X380201Y1085458D03*
X374650Y1088647D03*
Y1082269D03*
X367248Y1101403D03*
X369099Y1091836D03*
X374650Y1095025D03*
X369099Y1098214D03*
X380201Y1104592D03*
Y1098214D03*
X374650Y1101403D03*
X367248Y1107781D03*
X374650D03*
X369099Y1110970D03*
Y1117348D03*
X380201D03*
X374650Y1114159D03*
X367248Y1120537D03*
Y1126915D03*
X374650Y1120537D03*
Y1126915D03*
X380201Y1130103D03*
X374650Y1133293D03*
X369099Y1130103D03*
X367248Y1139670D03*
Y1146048D03*
X380201Y1142859D03*
X374650Y1139670D03*
X369099Y1136481D03*
Y1149237D03*
X374650Y1146048D03*
X380201Y1155615D03*
X369099D03*
X372799D03*
X374650Y1152426D03*
X378351Y1158804D03*
X374650D03*
X376500Y1161993D03*
X377523Y1222274D03*
X372730Y1216782D03*
X367697Y1216624D03*
X377733Y1507295D03*
X368285D03*
X373009D03*
X376009Y1521453D03*
X380734D03*
X366560D03*
X371285D03*
X376339Y1514243D03*
X366890D03*
X371615D03*
X376560Y1528853D03*
X367111D03*
X371836D03*
X376059Y1536063D03*
X366610D03*
X377733Y1542641D03*
X368285D03*
X373009D03*
X374666Y1592380D03*
X366866D03*
X380696Y1602380D03*
X368626Y1602286D03*
X372906Y1602380D03*
X374666Y1624292D03*
X380696Y1614292D03*
X372906D03*
X368626D03*
X366866Y1624292D03*
X387603Y1028056D03*
X395004D03*
X393154Y1044001D03*
X385752Y1031245D03*
Y1037623D03*
Y1044001D03*
X395004Y1040812D03*
X387603Y1034434D03*
Y1040812D03*
X395004Y1034434D03*
X393154Y1031245D03*
Y1037623D03*
X395004Y1047190D03*
X387603D03*
Y1053568D03*
X391303Y1059946D03*
X395004Y1053568D03*
X385752Y1050379D03*
X393154Y1056757D03*
Y1050379D03*
X382051Y1063135D03*
Y1069513D03*
X393154Y1063135D03*
X395004Y1066324D03*
X387603D03*
X383902D03*
X391303Y1072702D03*
Y1066324D03*
X393154Y1069513D03*
X385752D03*
Y1063135D03*
X389453Y1069513D03*
Y1063135D03*
X382051Y1075891D03*
Y1088647D03*
Y1082269D03*
X393154Y1075891D03*
X387603Y1079080D03*
X383902D03*
X391303D03*
X395004D03*
X393154Y1082269D03*
X391303Y1085458D03*
X393154Y1088647D03*
X385752Y1075891D03*
X389453D03*
X385752Y1088647D03*
Y1082269D03*
X389453Y1088647D03*
Y1082269D03*
X382051Y1095025D03*
X383902Y1091836D03*
X393154Y1095025D03*
X391303Y1091836D03*
X395004D03*
X387603D03*
X391303Y1098214D03*
Y1104592D03*
X395004D03*
X387603D03*
X383902D03*
X385752Y1095025D03*
X389453D03*
X382051Y1107781D03*
Y1114159D03*
X383902Y1110970D03*
X387603D03*
X393154Y1107781D03*
X391303Y1110970D03*
X395004D03*
X391303Y1117348D03*
X393154Y1114159D03*
X391304Y1130105D03*
X382051Y1126915D03*
Y1120537D03*
Y1133293D03*
X383902Y1123726D03*
X387603D03*
X393154Y1126915D03*
X391303Y1123726D03*
X395004D03*
X393154Y1120537D03*
Y1133293D03*
X382051Y1139670D03*
Y1146048D03*
X393154Y1139670D03*
X395004Y1136481D03*
X391303D03*
X383902D03*
X387603D03*
X391303Y1142859D03*
X393154Y1146048D03*
X395004Y1149237D03*
X383902D03*
X387603D03*
X389453Y1158804D03*
X391303Y1155615D03*
X395004D03*
X383902D03*
X387603D03*
Y1161993D03*
X382458Y1507295D03*
X387182D03*
X390203Y1521453D03*
X385458D03*
X385788Y1514243D03*
X381285Y1528853D03*
X386009D03*
X385508Y1536063D03*
X390839D03*
X382458Y1542641D03*
X387182D03*
X398705Y1028056D03*
X409795Y1028064D03*
X398705Y1034434D03*
X402406Y1040812D03*
X400555Y1031245D03*
Y1037623D03*
Y1044001D03*
X409795Y1034442D03*
Y1040820D03*
X402406Y1047190D03*
X409807D03*
X402406Y1053568D03*
X407957Y1056757D03*
X402406Y1059946D03*
X409807Y1053568D03*
X400555Y1056757D03*
Y1050379D03*
X407957D03*
X398705Y1066324D03*
X404256Y1063135D03*
X402406Y1072702D03*
X404256Y1069513D03*
X406107Y1066324D03*
X409807D03*
X402406D03*
X396855Y1069513D03*
Y1063135D03*
X407957Y1069513D03*
Y1063135D03*
X400555Y1069513D03*
Y1063135D03*
X398705Y1079080D03*
X404256Y1075891D03*
X406107Y1079080D03*
X409807D03*
X402406D03*
X404256Y1088647D03*
X402406Y1085458D03*
X404256Y1082269D03*
X396855Y1075891D03*
X407957D03*
X400555D03*
X396855Y1088647D03*
Y1082269D03*
X407957Y1088647D03*
Y1082269D03*
X400555Y1088647D03*
Y1082269D03*
X398705Y1091836D03*
Y1104592D03*
X404256Y1095025D03*
X406107Y1091836D03*
X409807D03*
X402406D03*
Y1098214D03*
Y1104592D03*
X396855Y1095025D03*
X407957D03*
X400555D03*
X398705Y1110970D03*
X404256Y1107781D03*
X406107Y1110970D03*
X409807D03*
X402406D03*
X404256Y1114159D03*
X402406Y1117348D03*
X398705Y1123726D03*
X406107D03*
X409807D03*
X404256Y1120537D03*
X402406Y1123726D03*
X404256Y1126915D03*
Y1133293D03*
X402406Y1130103D03*
X398705Y1136481D03*
Y1149237D03*
X402406Y1142859D03*
X404256Y1139670D03*
X406107Y1136481D03*
X409807D03*
X402406D03*
X404256Y1146048D03*
X406107Y1149237D03*
X409807D03*
X398705Y1155615D03*
Y1161993D03*
X406107Y1155615D03*
X409807D03*
X402406D03*
X400555Y1158804D03*
X409807Y1161993D03*
X400555Y1165182D03*
X424598Y1040820D03*
X417197D03*
X413508Y1059946D03*
X417209Y1047190D03*
X424610D03*
Y1053568D03*
X422760Y1056757D03*
X424610Y1059946D03*
X417209Y1053568D03*
X415358Y1056757D03*
Y1050379D03*
X422760D03*
X413508Y1072702D03*
Y1066324D03*
X415358Y1063135D03*
X424610Y1072702D03*
Y1066324D03*
X420910D03*
X417209D03*
X415358Y1069513D03*
X419059Y1063135D03*
Y1069513D03*
X422760Y1063135D03*
X411658Y1069513D03*
Y1063135D03*
X422760Y1069513D03*
X413508Y1079080D03*
Y1085458D03*
X415358Y1075891D03*
X420910Y1079080D03*
X424610D03*
X417209D03*
X424610Y1085458D03*
X415358Y1088647D03*
Y1082269D03*
X419059Y1075891D03*
X422760D03*
X411658D03*
X419059Y1082269D03*
Y1088647D03*
X422760Y1082269D03*
X411658Y1088647D03*
Y1082269D03*
X422760Y1088647D03*
X413508Y1091836D03*
Y1098214D03*
Y1104592D03*
X415358Y1095025D03*
X420910Y1091836D03*
X424610D03*
X417209D03*
X420910Y1104592D03*
X424610D03*
Y1098214D03*
X417209Y1104592D03*
X415358Y1101403D03*
X419059Y1095025D03*
Y1101403D03*
X422760Y1095025D03*
Y1101403D03*
X411658Y1095025D03*
X413508Y1110970D03*
Y1117348D03*
X415358Y1107781D03*
X424610Y1110970D03*
X420910D03*
X417209D03*
X424610Y1117348D03*
X415358Y1114159D03*
Y1120537D03*
Y1126915D03*
X424610Y1123726D03*
X420910D03*
X417209D03*
X415358Y1133293D03*
X413508Y1123726D03*
Y1130103D03*
X424611Y1130105D03*
X413508Y1142859D03*
Y1136481D03*
X424610Y1142859D03*
Y1136481D03*
X420910D03*
X415358Y1139670D03*
X417209Y1136481D03*
X420910Y1149237D03*
X417209D03*
X415358Y1146048D03*
X413508Y1155615D03*
X411658Y1158804D03*
X424610Y1155615D03*
X420910D03*
X417209D03*
X422760Y1158804D03*
Y1165182D03*
X420910Y1161993D03*
X430162Y1056757D03*
Y1050379D03*
X432012Y1047190D03*
Y1053568D03*
X435713Y1059946D03*
X428311D03*
X432012D03*
X426461Y1063135D03*
X430162D03*
X426461Y1069513D03*
X433862Y1063135D03*
X435713Y1072702D03*
Y1066324D03*
X428311Y1072702D03*
Y1066324D03*
X432012Y1072702D03*
Y1066324D03*
X430162Y1075891D03*
X426461D03*
X430162Y1088647D03*
X426461D03*
Y1082269D03*
X433862Y1075891D03*
X435713Y1079080D03*
Y1085458D03*
X433862Y1088647D03*
X428311Y1079080D03*
X432012D03*
X428311Y1085458D03*
X432012D03*
X426461Y1095025D03*
X430162Y1101403D03*
X426461D03*
X435713Y1091836D03*
Y1098214D03*
Y1104592D03*
X433862Y1101403D03*
X428311Y1098214D03*
Y1091836D03*
X432012Y1098214D03*
Y1091836D03*
X430162Y1107781D03*
X426461D03*
Y1114159D03*
X433862Y1107781D03*
X435713Y1110970D03*
Y1117348D03*
X426461Y1126915D03*
X430162Y1120537D03*
X426461D03*
X430162Y1133293D03*
X426461D03*
X435713Y1123726D03*
X433862Y1120537D03*
X435713Y1130103D03*
X433862Y1133293D03*
X426461Y1139670D03*
Y1146048D03*
X428311Y1149237D03*
X435713Y1136481D03*
Y1142859D03*
Y1149237D03*
X432012D03*
X430162Y1158804D03*
X435713Y1155615D03*
Y1161993D03*
X454204Y1040820D03*
X446790Y1047190D03*
Y1053568D03*
Y1059946D03*
X454192Y1047190D03*
X448641Y1056757D03*
X454192Y1053568D03*
X448641Y1050379D03*
X454192Y1059946D03*
X450491D03*
X446790Y1066324D03*
Y1072702D03*
X452341Y1063135D03*
X448641D03*
X454192Y1066324D03*
Y1072702D03*
X450491Y1066324D03*
Y1072702D03*
X446790Y1079080D03*
Y1085458D03*
X452341Y1075891D03*
X448641D03*
X452341Y1088647D03*
X448641D03*
X454192Y1079080D03*
X450491D03*
X454192Y1085458D03*
X450491D03*
X446790Y1091836D03*
Y1098214D03*
Y1104592D03*
X452341Y1101403D03*
X448641D03*
X454192Y1091836D03*
Y1098214D03*
X450491Y1091836D03*
Y1098214D03*
X446790Y1110970D03*
Y1117348D03*
X452341Y1107781D03*
X448641D03*
X446790Y1123726D03*
Y1130103D03*
X448641Y1120537D03*
X452341D03*
Y1133293D03*
X448641D03*
X446790Y1136481D03*
Y1142859D03*
Y1149237D03*
X454192D03*
X450491D03*
X446790Y1155615D03*
Y1161993D03*
X454192Y1155615D03*
X447120Y1507512D03*
X452427Y1507295D03*
X450703Y1521453D03*
X451033Y1514243D03*
X449861Y1519195D03*
X451254Y1528853D03*
X450752Y1536063D03*
X441752Y1523810D03*
Y1528725D03*
X452427Y1542641D03*
X447224Y1542425D03*
X450139Y1592380D03*
Y1624292D03*
X469007Y1040820D03*
X461606D03*
X461593Y1047190D03*
Y1053568D03*
X456042Y1056757D03*
X457893Y1059946D03*
X456042Y1050379D03*
X468995Y1047190D03*
Y1053568D03*
Y1059946D03*
X463444Y1056757D03*
Y1050379D03*
X456042Y1063135D03*
Y1069513D03*
X457893Y1072702D03*
Y1066324D03*
X461593D03*
X467145Y1063135D03*
X468995Y1072702D03*
Y1066324D03*
X467145Y1069513D03*
X465294Y1066324D03*
X463444Y1063135D03*
Y1069513D03*
X459743Y1063135D03*
Y1069513D03*
X456042Y1075891D03*
X461593Y1079080D03*
X457893D03*
X456042Y1088647D03*
X457893Y1085458D03*
X456042Y1082269D03*
X467145Y1075891D03*
X468995Y1079080D03*
X465294D03*
X468995Y1085458D03*
X467145Y1088647D03*
Y1082269D03*
X463444Y1075891D03*
X459743D03*
X463444Y1082269D03*
Y1088647D03*
X459743Y1082269D03*
Y1088647D03*
X457893Y1091836D03*
X461593D03*
X456042Y1095025D03*
X457893Y1098214D03*
X456042Y1101403D03*
X457893Y1104592D03*
X461593D03*
X467145Y1095025D03*
X468995Y1091836D03*
X465294D03*
X468995Y1104592D03*
X465294D03*
X468995Y1098214D03*
X467145Y1101403D03*
X463444D03*
Y1095025D03*
X459743Y1101403D03*
Y1095025D03*
X456042Y1107781D03*
X457893Y1110970D03*
X461593D03*
X457893Y1117348D03*
X456042Y1114159D03*
X468995Y1110970D03*
X465294D03*
X467145Y1107781D03*
Y1114159D03*
X468995Y1117348D03*
X456042Y1126915D03*
X461593Y1123726D03*
X457893D03*
X456042Y1120537D03*
Y1133293D03*
X468995Y1123726D03*
X467145Y1120537D03*
X465294Y1123726D03*
X467145Y1126915D03*
X468995Y1130103D03*
X467145Y1133293D03*
X457893Y1130104D03*
X456042Y1139670D03*
X461593Y1136481D03*
X457893D03*
Y1142859D03*
X456042Y1146048D03*
X461593Y1149237D03*
X468995Y1142859D03*
X467145Y1139670D03*
X468995Y1136481D03*
X465294D03*
X467145Y1146048D03*
X465294Y1149237D03*
X459743Y1158804D03*
Y1152426D03*
X465294Y1155615D03*
X457152Y1507295D03*
X461876D03*
X466600D03*
X469600Y1521453D03*
X464876D03*
X460152D03*
X455427D03*
X455757Y1514243D03*
X460482D03*
X465206D03*
X469931D03*
X470151Y1528853D03*
X465427D03*
X460703D03*
X455978D03*
X464926Y1536063D03*
X460202D03*
X455477D03*
X466600Y1542641D03*
X457152D03*
X461876D03*
X469999Y1592380D03*
X457939D03*
X462199D03*
X463959Y1602380D03*
X456179D03*
X468239D03*
X457939Y1624292D03*
X463959Y1614292D03*
X456179D03*
X468239D03*
X469999Y1624292D03*
X462199D03*
X480097Y1028056D03*
X478247Y1037623D03*
Y1044001D03*
X480097Y1034434D03*
X483798Y1040812D03*
X481948Y1031245D03*
X476400Y1040820D03*
X476397Y1047190D03*
Y1053568D03*
X470845Y1056757D03*
X478247D03*
X470845Y1050379D03*
X478247D03*
X483798Y1047190D03*
Y1053568D03*
X480097Y1059946D03*
X478247Y1063135D03*
X472696Y1066324D03*
X476397D03*
X478247Y1069513D03*
X483798Y1066324D03*
X480097Y1072702D03*
Y1066324D03*
X474546Y1063135D03*
Y1069513D03*
X481948Y1063135D03*
Y1069513D03*
X470845Y1063135D03*
Y1069513D03*
X478247Y1075891D03*
X476397Y1079080D03*
X472696D03*
X478247Y1088647D03*
Y1082269D03*
X483798Y1079080D03*
X480097D03*
Y1085458D03*
X474546Y1075891D03*
X481948D03*
X470845D03*
X474546Y1082269D03*
Y1088647D03*
X481948Y1082269D03*
Y1088647D03*
X470845Y1082269D03*
Y1088647D03*
X480097Y1104592D03*
X483798D03*
X480097Y1098214D03*
X478247Y1095025D03*
X472696Y1091836D03*
X476397D03*
X480097D03*
X483798D03*
X474546Y1095025D03*
X481948D03*
X470845D03*
X472696Y1110970D03*
X476397D03*
X478247Y1107781D03*
Y1114159D03*
X483798Y1110970D03*
X480097D03*
Y1117348D03*
X476397Y1123726D03*
X472696D03*
X478247Y1120537D03*
Y1126915D03*
Y1133293D03*
X483798Y1123726D03*
X480097D03*
Y1130103D03*
X478247Y1139670D03*
X476397Y1136481D03*
X472696D03*
X476397Y1149237D03*
X472696D03*
X478247Y1146048D03*
X483798Y1136481D03*
X480097D03*
Y1142859D03*
X483798Y1149237D03*
X476397Y1155615D03*
X474546Y1152426D03*
X470845Y1158804D03*
X481948D03*
X471325Y1507295D03*
X476049D03*
X480774D03*
X483774Y1521453D03*
X479049D03*
X474325D03*
X474655Y1514243D03*
X479379D03*
X484104D03*
X484325Y1528853D03*
X479600D03*
X474876D03*
X479099Y1536063D03*
X476049Y1542641D03*
X471325D03*
X480774D03*
X482059Y1592380D03*
X474259D03*
X476019Y1602380D03*
X480299D03*
X482059Y1624292D03*
X476019Y1614292D03*
X474259Y1624292D03*
X480299Y1614292D03*
X494901Y1028056D03*
X487499D03*
X485649Y1044001D03*
X494901Y1034434D03*
X491200Y1040812D03*
X487499Y1034434D03*
X489349Y1031245D03*
X493050Y1037623D03*
X485649D03*
X493050Y1044001D03*
X496751Y1031245D03*
X498601Y1040812D03*
X491200Y1047190D03*
X493050Y1056757D03*
X491200Y1059946D03*
Y1053568D03*
X485649Y1056757D03*
X493050Y1050379D03*
X485649D03*
X498601Y1047190D03*
Y1053568D03*
X489349Y1063135D03*
X494901Y1066324D03*
X491200D03*
X487499D03*
X491200Y1072702D03*
X489349Y1069513D03*
X498601Y1066324D03*
X485649Y1063135D03*
Y1069513D03*
X496751Y1063135D03*
Y1069513D03*
X493050Y1063135D03*
Y1069513D03*
X489349Y1082269D03*
X498601Y1079080D03*
X494901D03*
X489349Y1075891D03*
X487499Y1079080D03*
X491200D03*
Y1085458D03*
X489349Y1088647D03*
X485649Y1075891D03*
X496751D03*
X493050D03*
X485649Y1082269D03*
Y1088647D03*
X496751Y1082269D03*
Y1088647D03*
X493050Y1082269D03*
Y1088647D03*
X494901Y1091836D03*
X487499D03*
X491200D03*
X489349Y1095025D03*
X494901Y1104592D03*
X491200Y1098214D03*
Y1104592D03*
X487499D03*
X498601Y1091836D03*
Y1104592D03*
X496751Y1101403D03*
X485649Y1095025D03*
X496751D03*
X493050D03*
X491200Y1110970D03*
X489349Y1114159D03*
X491200Y1117348D03*
X498601Y1110970D03*
X494901D03*
X489349Y1107781D03*
X487499Y1110970D03*
X494901Y1123726D03*
X489349Y1126915D03*
X491200Y1123726D03*
X487499D03*
X489349Y1120537D03*
X491200Y1130103D03*
X489349Y1133293D03*
X498601Y1123726D03*
X494901Y1136481D03*
X489349Y1139670D03*
X491200Y1136481D03*
X487499D03*
X491200Y1142859D03*
X494901Y1149237D03*
X489349Y1146048D03*
X487499Y1149237D03*
X498601Y1136481D03*
Y1149237D03*
X487499Y1155615D03*
X485649Y1152426D03*
X493050Y1158804D03*
X498601Y1155615D03*
X496751Y1152426D03*
X485498Y1507295D03*
X490222D03*
X499671D03*
X494947D03*
X497947Y1521453D03*
X493222D03*
X488498D03*
X488828Y1514243D03*
X493553D03*
X498277D03*
X498498Y1528853D03*
X493773D03*
X489049D03*
X488548Y1536063D03*
X494947Y1542641D03*
X485498D03*
X490222D03*
X499671D03*
X498379Y1592380D03*
X486319D03*
X494119D03*
X488079Y1602380D03*
X492359D03*
X498379Y1624292D03*
X488079Y1614292D03*
X486319Y1624292D03*
X494119D03*
X492359Y1614292D03*
X497440Y1684454D03*
Y1679920D03*
Y1675383D03*
Y1698627D03*
Y1694093D03*
Y1689556D03*
Y1712800D03*
Y1708266D03*
Y1703729D03*
Y1726974D03*
Y1722440D03*
Y1717903D03*
X502302Y1028056D03*
X513405D03*
X507853Y1037623D03*
X500452D03*
X502302Y1034434D03*
X507853Y1044001D03*
X500452D03*
X507853Y1031245D03*
X513405Y1034434D03*
Y1040812D03*
X507853Y1056757D03*
Y1050379D03*
X500452Y1056757D03*
X504153D03*
X500452Y1050379D03*
X502302Y1059946D03*
X506003D03*
X513405Y1053568D03*
Y1059946D03*
X507853Y1063135D03*
X500452D03*
X507853Y1069513D03*
X500452D03*
X502302Y1072702D03*
X513405D03*
X507853Y1075891D03*
X500452D03*
X507853Y1088647D03*
X500452D03*
X502302Y1085458D03*
X507853Y1082269D03*
X500452D03*
X513405Y1079080D03*
X507853Y1095025D03*
X500452D03*
X502302Y1098214D03*
X507853Y1101403D03*
X502302Y1104592D03*
X513405Y1091836D03*
Y1098214D03*
X507853Y1107781D03*
X500452D03*
X507853Y1114159D03*
X502302Y1117348D03*
X500452Y1114159D03*
X513405Y1110970D03*
Y1117348D03*
X507853Y1120537D03*
X500452D03*
X507853Y1126915D03*
X500452D03*
X507853Y1133293D03*
X500452D03*
X502302Y1130103D03*
X513405Y1130104D03*
X507853Y1139670D03*
X500452D03*
X502302Y1142859D03*
X507853Y1146048D03*
X500452D03*
X513405Y1136481D03*
Y1149237D03*
X511554Y1165182D03*
X509704Y1155615D03*
X507853Y1152426D03*
X502302Y1155615D03*
X507853Y1158804D03*
X504153D03*
X513405Y1155615D03*
X504396Y1507295D03*
X509120D03*
X513844D03*
X512120Y1521453D03*
X507396D03*
X502671D03*
X503001Y1514243D03*
X507726D03*
X512450D03*
X512671Y1528853D03*
X507947D03*
X503222D03*
X512170Y1536063D03*
X502721D03*
X513844Y1542641D03*
X504396D03*
X509120D03*
X510439Y1592380D03*
X506179D03*
X512199Y1602380D03*
X500139D03*
X504419D03*
X512199Y1614292D03*
X500139D03*
X506179Y1624292D03*
X510439D03*
X504419Y1614292D03*
X505314Y1679320D03*
Y1683857D03*
X513188Y1684454D03*
Y1679920D03*
Y1675383D03*
X505314Y1688391D03*
Y1693493D03*
Y1698030D03*
X513188Y1698627D03*
Y1694093D03*
Y1689556D03*
X505314Y1707666D03*
Y1712203D03*
X513188Y1712800D03*
Y1708266D03*
Y1703729D03*
X505314Y1716737D03*
Y1702564D03*
Y1721840D03*
Y1726377D03*
Y1730911D03*
X513188Y1726974D03*
Y1722440D03*
Y1717903D03*
X520806Y1028056D03*
X528208D03*
X526357Y1037623D03*
Y1044001D03*
Y1031245D03*
X515255D03*
X520806Y1040812D03*
Y1034434D03*
X515255Y1044001D03*
X528208Y1040812D03*
Y1034434D03*
X520806Y1047190D03*
X526357Y1050379D03*
Y1056757D03*
X520806Y1053568D03*
X515255Y1050379D03*
X518956Y1056757D03*
X520806Y1059946D03*
X517105D03*
X528208Y1047190D03*
Y1053568D03*
Y1059946D03*
X526357Y1063135D03*
X515255D03*
X526357Y1069513D03*
X520806Y1066324D03*
Y1072702D03*
X515255Y1069513D03*
X528208Y1066324D03*
Y1072702D03*
X526357Y1075891D03*
X520806Y1079080D03*
X526357Y1088647D03*
Y1082269D03*
X520806Y1085458D03*
X515255Y1088647D03*
Y1082269D03*
X528208Y1079080D03*
Y1085458D03*
X526357Y1095025D03*
X520806Y1091836D03*
X526357Y1101403D03*
X520806Y1104592D03*
Y1098214D03*
X515255Y1101403D03*
X528208Y1091836D03*
Y1104592D03*
Y1098214D03*
X526357Y1107781D03*
X520806Y1110970D03*
X515255Y1107781D03*
X526357Y1114159D03*
X520806Y1117348D03*
X528208Y1110970D03*
Y1117348D03*
Y1130104D03*
X526357Y1120537D03*
Y1126915D03*
X520806Y1123726D03*
X515255Y1120537D03*
Y1126915D03*
X526357Y1133293D03*
X520806Y1130103D03*
X528208Y1123726D03*
X515255Y1139670D03*
X520806Y1142859D03*
X526357Y1139670D03*
X520806Y1136481D03*
X526357Y1146048D03*
X520806Y1149237D03*
X515255Y1146048D03*
X528208Y1136481D03*
Y1142859D03*
Y1149237D03*
X526357Y1152426D03*
Y1158804D03*
X520806Y1155615D03*
X517105D03*
X522657Y1158804D03*
X515255D03*
X517105Y1161993D03*
X528208Y1155615D03*
X518569Y1507295D03*
X523293D03*
X526314Y1521453D03*
X521569D03*
X516845D03*
X521899Y1514243D03*
X522120Y1528853D03*
X517396D03*
X521619Y1536063D03*
X526950D03*
X523293Y1542641D03*
X518569D03*
X518239Y1592380D03*
X522499D03*
X524259Y1602380D03*
X528539D03*
X516479D03*
X524259Y1614292D03*
X518239Y1624292D03*
X522499D03*
X528539Y1614292D03*
X516479D03*
X521062Y1679320D03*
Y1683857D03*
X528936Y1684454D03*
Y1679920D03*
Y1675383D03*
X521062Y1688391D03*
Y1693493D03*
Y1698030D03*
X528936Y1698627D03*
Y1694093D03*
Y1689556D03*
X521062Y1716737D03*
Y1702564D03*
Y1707666D03*
Y1712203D03*
X528936Y1712800D03*
Y1708266D03*
Y1703729D03*
X521062Y1721840D03*
Y1726377D03*
Y1730911D03*
X528936Y1726974D03*
Y1722440D03*
Y1717903D03*
X539310Y1028056D03*
X541160Y1031245D03*
X533759D03*
X539310Y1034434D03*
Y1040812D03*
X533759Y1037623D03*
X541160Y1044001D03*
X533759D03*
X543011Y1059946D03*
X530058Y1056757D03*
X541160Y1050379D03*
X539310Y1053568D03*
X533759Y1050379D03*
Y1056757D03*
X539310Y1059946D03*
X531908D03*
X541160Y1063135D03*
X533759D03*
X541160Y1069513D03*
X539310Y1072702D03*
X533759Y1069513D03*
Y1075891D03*
X539310Y1079080D03*
X541160Y1088647D03*
X533759D03*
X541160Y1082269D03*
X533759D03*
X539310Y1091836D03*
X533759Y1095025D03*
X539310Y1098214D03*
X541160Y1101403D03*
X533759D03*
X541160Y1107781D03*
X533759D03*
X539310Y1110970D03*
Y1117348D03*
X533759Y1114159D03*
X541160Y1120537D03*
X533759D03*
X541160Y1126915D03*
X533759D03*
X539310Y1130103D03*
X533759Y1133293D03*
X541160Y1139670D03*
X539310Y1136481D03*
X533759Y1139670D03*
Y1146048D03*
X541160D03*
X539310Y1149237D03*
X543011Y1155615D03*
X533759Y1158804D03*
X530058D03*
X539310Y1155615D03*
X535609D03*
X533759Y1152426D03*
X543011Y1161993D03*
X542359Y1592380D03*
X530299D03*
X534559D03*
X536319Y1602380D03*
X540599D03*
X542359Y1624292D03*
X536319Y1614292D03*
X530299Y1624292D03*
X534559D03*
X540599Y1614292D03*
X536810Y1679320D03*
Y1683857D03*
X544684Y1684454D03*
Y1679920D03*
Y1675383D03*
X536810Y1688391D03*
Y1693493D03*
Y1698030D03*
X544684Y1698627D03*
Y1694093D03*
Y1689556D03*
X536810Y1716737D03*
Y1702564D03*
Y1707666D03*
Y1712203D03*
X544684Y1712800D03*
Y1708266D03*
Y1703729D03*
X536810Y1721840D03*
Y1726377D03*
Y1730911D03*
X544684Y1726974D03*
Y1722440D03*
Y1717903D03*
X554113Y1028056D03*
X546712D03*
Y1040812D03*
Y1034434D03*
X552263Y1031245D03*
X554113Y1040812D03*
X552263Y1037623D03*
X554113Y1034434D03*
X552263Y1044001D03*
X559664Y1031245D03*
Y1037623D03*
Y1044001D03*
X546712Y1047190D03*
X554113D03*
X544861Y1056757D03*
X546712Y1053568D03*
Y1059946D03*
X552263Y1056757D03*
X555964D03*
X554113Y1053568D03*
X552263Y1050379D03*
X554113Y1059946D03*
X557814D03*
X559664Y1050379D03*
Y1056757D03*
X552263Y1063135D03*
X546712Y1072702D03*
Y1066324D03*
X552263Y1069513D03*
X554113Y1066324D03*
Y1072702D03*
X559664Y1063135D03*
Y1069513D03*
X552263Y1075891D03*
X546712Y1079080D03*
X554113D03*
X546712Y1085458D03*
X552263Y1088647D03*
X554113Y1085458D03*
X552263Y1082269D03*
X559664Y1075891D03*
Y1088647D03*
Y1082269D03*
X546712Y1091836D03*
X554113D03*
X552263Y1095025D03*
Y1101403D03*
X554113Y1098214D03*
X546712Y1104592D03*
Y1098214D03*
X554113Y1104592D03*
X559664Y1095025D03*
Y1101403D03*
X552263Y1107781D03*
X554113Y1110970D03*
X546712D03*
X554113Y1117348D03*
X552263Y1114159D03*
X546712Y1117348D03*
X559664Y1107781D03*
Y1114159D03*
X546712Y1123726D03*
X554113D03*
X552263Y1120537D03*
Y1126915D03*
Y1133293D03*
X554113Y1130103D03*
X559664Y1120537D03*
Y1126915D03*
Y1133293D03*
X546712Y1130104D03*
X552263Y1139670D03*
X554113Y1136481D03*
X546712D03*
X554113Y1142859D03*
X546712D03*
Y1149237D03*
X552263Y1146048D03*
X554113Y1149237D03*
X559664Y1139670D03*
Y1146048D03*
X555964Y1165182D03*
X554113Y1155615D03*
X552263Y1152426D03*
X555964Y1158804D03*
X552263D03*
X548562D03*
X546712Y1155615D03*
X554113Y1161993D03*
X559664Y1152426D03*
Y1158804D03*
X558679Y1592380D03*
X546619D03*
X554419D03*
X548379Y1602380D03*
X552659D03*
X558679Y1624292D03*
X548379Y1614292D03*
X546619Y1624292D03*
X554419D03*
X552659Y1614292D03*
X552558Y1679320D03*
Y1683857D03*
Y1688391D03*
Y1693493D03*
Y1698030D03*
Y1716737D03*
Y1702564D03*
Y1707666D03*
Y1712203D03*
Y1721840D03*
Y1726377D03*
Y1730911D03*
X565216Y1028056D03*
X572617D03*
X567066Y1031245D03*
X565215Y1034434D03*
Y1040812D03*
X572617Y1034434D03*
Y1040812D03*
X567066Y1044001D03*
X565215Y1059946D03*
X572617Y1047190D03*
X567066Y1050379D03*
X572617Y1053568D03*
X570767Y1056757D03*
X565215Y1053568D03*
X572617Y1059946D03*
X568916D03*
X567066Y1063135D03*
X572617Y1066324D03*
Y1072702D03*
X567066Y1069513D03*
X565215Y1072702D03*
Y1079080D03*
X572617D03*
X567066Y1088647D03*
X572617Y1085458D03*
X567066Y1082269D03*
X572617Y1091836D03*
X565215D03*
X572617Y1104592D03*
Y1098214D03*
X567066Y1101403D03*
X565215Y1098214D03*
X567066Y1107781D03*
X572617Y1110970D03*
X565215D03*
X572617Y1117348D03*
X565215D03*
X572617Y1123726D03*
X567066Y1120537D03*
Y1126915D03*
X572617Y1130103D03*
X565215D03*
X572617Y1136481D03*
X565215Y1149237D03*
X572617D03*
X567066Y1146048D03*
X572617Y1142859D03*
X567066Y1139670D03*
X565215Y1136481D03*
X574467Y1158804D03*
X565215Y1155615D03*
X568916D03*
X572617D03*
X561515D03*
X565215Y1161993D03*
X569814Y1523810D03*
Y1528725D03*
X570739Y1592380D03*
X566479D03*
X572499Y1602380D03*
X560439D03*
X564719D03*
X572499Y1614292D03*
X570739Y1624292D03*
X560439Y1614292D03*
X566479Y1624292D03*
X564719Y1614292D03*
X572243Y1683857D03*
X564369Y1684454D03*
Y1679920D03*
Y1675383D03*
X572243Y1679320D03*
X564369Y1694093D03*
Y1689556D03*
X572243Y1688391D03*
Y1693493D03*
Y1698030D03*
X564369Y1698627D03*
X572243Y1702564D03*
Y1707666D03*
Y1712203D03*
X564369Y1712800D03*
Y1708266D03*
Y1703729D03*
X572243Y1716737D03*
Y1726377D03*
Y1730911D03*
X564369Y1726974D03*
Y1722440D03*
Y1717903D03*
X572243Y1721840D03*
X577728Y906182D03*
Y912560D03*
Y918938D03*
Y925316D03*
Y931694D03*
Y938072D03*
Y944450D03*
Y950828D03*
Y957206D03*
Y963584D03*
Y969962D03*
Y976340D03*
Y982718D03*
Y989096D03*
Y995474D03*
Y1008230D03*
Y1001852D03*
X578909Y1030198D03*
Y1036576D03*
Y1042954D03*
Y1049332D03*
Y1055710D03*
Y1062088D03*
Y1074844D03*
Y1068466D03*
Y1087600D03*
Y1081222D03*
Y1093978D03*
Y1100356D03*
Y1106734D03*
Y1113112D03*
Y1119490D03*
Y1125868D03*
Y1132246D03*
Y1138623D03*
Y1145001D03*
Y1151379D03*
X578168Y1158804D03*
X575182Y1507514D03*
X580489Y1507295D03*
X585214D03*
X588214Y1521453D03*
X583489D03*
X578765D03*
X579095Y1514243D03*
X583819D03*
X588544D03*
X577923Y1519195D03*
X588765Y1528853D03*
X584040D03*
X579316D03*
X588264Y1536063D03*
X583539D03*
X578814D03*
X585214Y1542641D03*
X580489D03*
X575286Y1542425D03*
X578539Y1592380D03*
X582799D03*
X584559Y1602380D03*
X588839D03*
X576779D03*
X584559Y1614292D03*
X582799Y1624292D03*
X578539D03*
X588839Y1614292D03*
X576779D03*
X587991Y1679320D03*
Y1683857D03*
X580117Y1684454D03*
Y1679920D03*
Y1675383D03*
X587991Y1688391D03*
Y1693493D03*
Y1698030D03*
X580117Y1698627D03*
Y1694093D03*
Y1689556D03*
X587991Y1716737D03*
Y1702564D03*
Y1707666D03*
Y1712203D03*
X580117Y1712800D03*
Y1708266D03*
Y1703729D03*
X587991Y1721840D03*
Y1726377D03*
Y1730911D03*
X580117Y1726974D03*
Y1722440D03*
Y1717903D03*
X589938Y1507295D03*
X594662D03*
X599387D03*
X604111D03*
X602387Y1521453D03*
X597662D03*
X592938D03*
X593268Y1514243D03*
X597993D03*
X602717D03*
X602938Y1528853D03*
X598213D03*
X593489D03*
X592988Y1536063D03*
X589938Y1542641D03*
X604111D03*
X599387D03*
X594662D03*
X602659Y1592380D03*
X590599D03*
X594859D03*
X596619Y1602380D03*
X600899D03*
X602659Y1624292D03*
X596619Y1614292D03*
X594859Y1624292D03*
X590599D03*
X600899Y1614292D03*
X603739Y1679320D03*
Y1683857D03*
X595865Y1684454D03*
Y1679920D03*
Y1675383D03*
X603739Y1688391D03*
Y1693493D03*
Y1698030D03*
X595865Y1698627D03*
Y1694093D03*
Y1689556D03*
X603739Y1716737D03*
Y1702564D03*
Y1707666D03*
Y1712203D03*
X595865Y1712800D03*
Y1708266D03*
Y1703729D03*
X603739Y1721840D03*
Y1726377D03*
Y1730911D03*
X595865Y1726974D03*
Y1722440D03*
Y1717903D03*
X608836Y1507295D03*
X613560D03*
X618284D03*
X616560Y1521453D03*
X611836D03*
X607111D03*
X607441Y1514243D03*
X612166D03*
X616890D03*
X617111Y1528853D03*
X612387D03*
X607662D03*
X607161Y1536063D03*
X616610D03*
X613560Y1542641D03*
X618284D03*
X608836D03*
X618979Y1592380D03*
X614719D03*
X606919D03*
X608679Y1602380D03*
X612959D03*
X618979Y1624292D03*
X608679Y1614292D03*
X606919Y1624292D03*
X614719D03*
X612959Y1614292D03*
X611613Y1684454D03*
Y1679920D03*
Y1675383D03*
Y1698627D03*
Y1694093D03*
Y1689556D03*
Y1712800D03*
Y1708266D03*
Y1703729D03*
Y1726974D03*
Y1722440D03*
Y1717903D03*
X623009Y1507295D03*
X627733D03*
X632458D03*
X630733Y1521453D03*
X626009D03*
X621284D03*
X621615Y1514243D03*
X626339D03*
X631063D03*
X631284Y1528853D03*
X626560D03*
X621835D03*
X630783Y1536063D03*
X632458Y1542641D03*
X627733D03*
X623009D03*
X631039Y1592380D03*
X626779D03*
X632799Y1602286D03*
X620739Y1602380D03*
X625019D03*
X631039Y1624292D03*
X632799Y1614292D03*
X626779Y1624292D03*
X620739Y1614292D03*
X625019D03*
X619487Y1679320D03*
Y1683857D03*
Y1688391D03*
Y1693493D03*
Y1698030D03*
Y1716737D03*
Y1702564D03*
Y1707666D03*
Y1712203D03*
Y1721840D03*
Y1726377D03*
Y1730911D03*
X637182Y1507295D03*
X641906D03*
X646631D03*
X644907Y1521453D03*
X640182D03*
X635458D03*
X635788Y1514243D03*
X640512D03*
X645458Y1528853D03*
X640733D03*
X636009D03*
X640232Y1536063D03*
X646631Y1542641D03*
X641906D03*
X637182D03*
X638839Y1592380D03*
X644869Y1602380D03*
X637079D03*
X644869Y1614292D03*
X638839Y1624292D03*
X637079Y1614292D03*
X651355Y1507295D03*
X654376Y1521453D03*
X649631D03*
X649961Y1514243D03*
X650182Y1528853D03*
X649681Y1536063D03*
X655012D03*
X651355Y1542641D03*
X1185452Y1556810D03*
Y1561725D03*
X1190820Y1540512D03*
X1194733Y1547243D03*
X1196127Y1540295D03*
X1199457Y1547243D03*
X1193561Y1552195D03*
X1199127Y1554453D03*
X1194403D03*
X1199678Y1561853D03*
X1194954D03*
X1199177Y1569063D03*
X1196127Y1575641D03*
X1194452Y1569063D03*
X1190924Y1575425D03*
X1193839Y1625380D03*
X1199879Y1635380D03*
Y1647292D03*
X1193839Y1657292D03*
X1200852Y1540295D03*
X1204182Y1547243D03*
X1205576Y1540295D03*
X1208906Y1547243D03*
X1210300Y1540295D03*
X1213631Y1547243D03*
X1215025Y1540295D03*
X1213300Y1554453D03*
X1208576D03*
X1203852D03*
X1213851Y1561853D03*
X1209127D03*
X1204403D03*
X1210300Y1575641D03*
X1208626Y1569063D03*
X1203902D03*
X1200852Y1575641D03*
X1205576D03*
X1215025D03*
X1205899Y1625380D03*
X1201639D03*
X1213699D03*
X1207659Y1635380D03*
X1211939D03*
X1207659Y1647292D03*
X1211939D03*
X1201639Y1657292D03*
X1205899D03*
X1213699D03*
X1218355Y1547243D03*
X1219749Y1540295D03*
X1223079Y1547243D03*
X1227804D03*
X1229198Y1540295D03*
X1224474D03*
X1227474Y1554453D03*
X1222749D03*
X1218025D03*
X1228025Y1561853D03*
X1223300D03*
X1218576D03*
X1222799Y1569063D03*
X1219749Y1575641D03*
X1224474D03*
X1229198D03*
X1217959Y1625380D03*
X1225759D03*
X1230019D03*
X1223999Y1635380D03*
X1219719D03*
X1223999Y1647292D03*
X1219719D03*
X1217959Y1657292D03*
X1230019D03*
X1225759D03*
X1232528Y1547243D03*
X1233922Y1540295D03*
X1237253Y1547243D03*
X1241977D03*
X1243371Y1540295D03*
X1238647D03*
X1241647Y1554453D03*
X1236922D03*
X1232198D03*
X1242198Y1561853D03*
X1237473D03*
X1232749D03*
X1238647Y1575641D03*
X1232248Y1569063D03*
X1233922Y1575641D03*
X1243371D03*
X1237819Y1625380D03*
X1242079D03*
X1231779Y1635380D03*
X1236059D03*
X1243839D03*
X1236059Y1647292D03*
X1231779D03*
X1243839D03*
X1237819Y1657292D03*
X1242079D03*
X1241140Y1684454D03*
Y1679920D03*
Y1675383D03*
Y1698627D03*
Y1694093D03*
Y1689556D03*
Y1712800D03*
Y1708266D03*
Y1703729D03*
Y1726974D03*
Y1722440D03*
Y1717903D03*
X1246701Y1547243D03*
X1248096Y1540295D03*
X1251426Y1547243D03*
X1252820Y1540295D03*
X1256150Y1547243D03*
X1257544Y1540295D03*
X1255820Y1554453D03*
X1251096D03*
X1246371D03*
X1256371Y1561853D03*
X1251647D03*
X1246922D03*
X1257544Y1575641D03*
X1255870Y1569063D03*
X1246421D03*
X1248096Y1575641D03*
X1252820D03*
X1249879Y1625380D03*
X1254139D03*
X1248119Y1635380D03*
X1255899D03*
X1260179D03*
X1248119Y1647292D03*
X1255899D03*
X1260179D03*
X1254139Y1657292D03*
X1249879D03*
X1249014Y1679320D03*
Y1683857D03*
X1256888Y1684454D03*
Y1679920D03*
Y1675383D03*
X1249014Y1688391D03*
Y1693493D03*
Y1698030D03*
X1256888Y1698627D03*
Y1694093D03*
Y1689556D03*
Y1703729D03*
X1249014Y1716737D03*
Y1702564D03*
Y1707666D03*
Y1712203D03*
X1256888Y1712800D03*
Y1708266D03*
X1249014Y1721840D03*
Y1726377D03*
Y1730911D03*
X1256888Y1726974D03*
Y1722440D03*
Y1717903D03*
X1262269Y1540295D03*
X1265599Y1547243D03*
X1266993Y1540295D03*
X1270014Y1554453D03*
X1265269D03*
X1260545D03*
X1265820Y1561853D03*
X1261096D03*
X1270650Y1569063D03*
X1266993Y1575641D03*
X1265319Y1569063D03*
X1262269Y1575641D03*
X1266199Y1625380D03*
X1261939D03*
X1273999D03*
X1267959Y1635380D03*
X1272239D03*
X1267959Y1647292D03*
X1272239D03*
X1266199Y1657292D03*
X1261939D03*
X1273999D03*
X1264762Y1679320D03*
Y1683857D03*
X1272636Y1684454D03*
Y1679920D03*
Y1675383D03*
X1264762Y1688391D03*
Y1693493D03*
Y1698030D03*
X1272636Y1698627D03*
Y1694093D03*
Y1689556D03*
X1264762Y1716737D03*
Y1702564D03*
Y1707666D03*
Y1712203D03*
X1272636Y1712800D03*
Y1708266D03*
Y1703729D03*
X1264762Y1721840D03*
Y1726377D03*
Y1730911D03*
X1272636Y1726974D03*
Y1722440D03*
Y1717903D03*
X1286028Y1028055D03*
Y1034433D03*
Y1040811D03*
Y1047189D03*
Y1053567D03*
X1287878Y1056756D03*
X1289729Y1059945D03*
X1286028D03*
Y1066323D03*
Y1072701D03*
Y1079079D03*
Y1085457D03*
Y1091835D03*
Y1098213D03*
Y1104591D03*
Y1110969D03*
Y1117347D03*
Y1123725D03*
Y1130102D03*
Y1136480D03*
Y1142858D03*
Y1149236D03*
X1289729Y1155614D03*
X1286028D03*
X1284178Y1158803D03*
X1287878Y1165181D03*
X1278259Y1625380D03*
X1286059D03*
X1280019Y1635380D03*
X1284299D03*
X1280019Y1647292D03*
X1284299D03*
X1278259Y1657292D03*
X1286059D03*
X1280510Y1679320D03*
Y1683857D03*
X1288384Y1684454D03*
Y1679920D03*
Y1675383D03*
X1280510Y1688391D03*
Y1693493D03*
Y1698030D03*
X1288384Y1698627D03*
Y1694093D03*
Y1689556D03*
X1280510Y1716737D03*
Y1702564D03*
Y1707666D03*
Y1712203D03*
X1288384Y1712800D03*
Y1708266D03*
Y1703729D03*
X1280510Y1721840D03*
Y1726377D03*
Y1730911D03*
X1288384Y1726974D03*
Y1722440D03*
Y1717903D03*
X1304532Y1028055D03*
X1293430Y1034433D03*
Y1040811D03*
X1298981Y1044000D03*
Y1037622D03*
X1304532Y1034433D03*
Y1040811D03*
X1298981Y1031244D03*
X1291579D03*
Y1044000D03*
X1304532Y1047189D03*
X1291579Y1050378D03*
X1293430Y1053567D03*
Y1059945D03*
X1304532Y1053567D03*
X1298981Y1050378D03*
X1302681Y1056756D03*
X1298981D03*
X1300831Y1059945D03*
X1304532D03*
X1298981Y1063134D03*
X1291579D03*
Y1069512D03*
X1293430Y1072701D03*
X1304532D03*
Y1066323D03*
X1298981Y1069512D03*
Y1075890D03*
X1293430Y1079079D03*
X1304532D03*
Y1085457D03*
X1298981Y1088646D03*
X1291579Y1082268D03*
X1298981D03*
X1291579Y1088646D03*
X1293430Y1091835D03*
X1304532D03*
X1298981Y1095024D03*
X1293430Y1098213D03*
X1298981Y1101402D03*
X1304532Y1098213D03*
Y1104591D03*
X1291579Y1101402D03*
X1298981Y1107780D03*
X1291579D03*
X1293430Y1110969D03*
X1304532D03*
X1293430Y1117347D03*
X1298981Y1114158D03*
X1304532Y1117347D03*
X1291579Y1120536D03*
X1298981D03*
X1304532Y1123725D03*
X1291579Y1126914D03*
X1298981D03*
X1304532Y1130102D03*
X1298981Y1133292D03*
X1293430Y1130102D03*
X1304532Y1136480D03*
X1298981Y1139669D03*
X1291579D03*
X1293430Y1136480D03*
X1304532Y1142858D03*
X1291579Y1146047D03*
X1293430Y1149236D03*
X1298981Y1146047D03*
X1304532Y1149236D03*
X1293430Y1155614D03*
X1304532D03*
X1298981Y1152425D03*
X1297130Y1155614D03*
X1302681Y1158803D03*
X1298981D03*
X1304532Y1161992D03*
X1297130D03*
X1298119Y1625380D03*
X1290319D03*
X1302379D03*
X1292079Y1635380D03*
X1296359D03*
X1304139D03*
X1296359Y1647292D03*
X1292079D03*
X1304139D03*
X1298119Y1657292D03*
X1290319D03*
X1302379D03*
X1296258Y1679320D03*
Y1683857D03*
Y1688391D03*
Y1693493D03*
Y1698030D03*
Y1716737D03*
Y1702564D03*
Y1707666D03*
Y1712203D03*
Y1721840D03*
Y1726377D03*
Y1730911D03*
X1311933Y1028055D03*
X1306382Y1044000D03*
Y1037622D03*
Y1031244D03*
X1319335Y1034433D03*
X1311933Y1040811D03*
X1319335D03*
X1317485Y1031244D03*
Y1044000D03*
X1311933Y1034433D03*
X1306382Y1050378D03*
Y1056756D03*
X1311933Y1047189D03*
X1313784Y1056756D03*
X1311933Y1059945D03*
X1315634D03*
X1319335D03*
X1317485Y1050378D03*
X1319335Y1053567D03*
X1311933D03*
X1306382Y1063134D03*
Y1069512D03*
X1317485Y1063134D03*
X1319335Y1072701D03*
X1317485Y1069512D03*
X1311933Y1066323D03*
Y1072701D03*
X1306382Y1075890D03*
Y1088646D03*
Y1082268D03*
X1319335Y1079079D03*
X1311933D03*
Y1085457D03*
X1317485Y1088646D03*
Y1082268D03*
X1306382Y1095024D03*
Y1101402D03*
X1319335Y1091835D03*
X1311933D03*
Y1098213D03*
X1319335D03*
X1317485Y1101402D03*
X1311933Y1104591D03*
X1306382Y1107780D03*
Y1114158D03*
X1317485Y1107780D03*
X1319335Y1110969D03*
X1311933D03*
Y1117347D03*
X1319335D03*
X1306382Y1120536D03*
Y1126914D03*
Y1133292D03*
X1317485Y1120536D03*
X1311933Y1123725D03*
X1317485Y1126914D03*
X1319335Y1130102D03*
X1311933Y1130103D03*
X1306382Y1139669D03*
Y1146047D03*
X1319335Y1136480D03*
X1317485Y1139669D03*
X1311933Y1136480D03*
Y1142858D03*
X1317485Y1146047D03*
X1319335Y1149236D03*
X1311933D03*
X1317485Y1158803D03*
X1313784D03*
X1319335Y1161992D03*
X1311933D03*
X1306382Y1165181D03*
X1313784D03*
X1306382Y1152425D03*
Y1158803D03*
X1319335Y1155614D03*
X1315634D03*
X1311933D03*
X1310083Y1158803D03*
X1318882Y1540514D03*
X1313514Y1556810D03*
Y1561725D03*
X1318986Y1575425D03*
X1310179Y1625380D03*
X1314439D03*
X1308419Y1635380D03*
X1316199D03*
X1308419Y1647292D03*
X1316199D03*
X1310179Y1657292D03*
X1314439D03*
X1315943Y1679320D03*
Y1683857D03*
X1308069Y1684454D03*
Y1679920D03*
Y1675383D03*
X1315943Y1688391D03*
Y1693493D03*
Y1698030D03*
X1308069Y1698627D03*
Y1694093D03*
Y1689556D03*
X1315943Y1716737D03*
Y1702564D03*
Y1707666D03*
Y1712203D03*
X1308069Y1712800D03*
Y1708266D03*
Y1703729D03*
X1315943Y1721840D03*
Y1726377D03*
Y1730911D03*
X1308069Y1726974D03*
Y1722440D03*
Y1717903D03*
X1330437Y1028055D03*
X1324886Y1031244D03*
X1332288D03*
X1324886Y1044000D03*
Y1037622D03*
X1332288Y1044000D03*
X1330437Y1034433D03*
X1332288Y1037622D03*
X1330437Y1040811D03*
Y1047189D03*
X1324886Y1050378D03*
Y1056756D03*
X1332288Y1050378D03*
X1330437Y1053567D03*
X1328587Y1056756D03*
X1332288D03*
X1326737Y1059945D03*
X1330437D03*
X1332288Y1063134D03*
X1324886D03*
Y1069512D03*
X1330437Y1066323D03*
X1332288Y1069512D03*
X1330437Y1072701D03*
X1324886Y1075890D03*
X1332288D03*
X1330437Y1079079D03*
X1324886Y1088646D03*
X1330437Y1085457D03*
X1332288Y1088646D03*
X1324886Y1082268D03*
X1332288D03*
X1330437Y1091835D03*
X1324886Y1095024D03*
X1332288D03*
X1324886Y1101402D03*
X1330437Y1098213D03*
X1332288Y1101402D03*
X1330437Y1104591D03*
X1324886Y1107780D03*
X1332288D03*
X1330437Y1110969D03*
X1324886Y1114158D03*
X1332288D03*
X1330437Y1117347D03*
X1324886Y1120536D03*
X1332288D03*
X1330437Y1123725D03*
X1324886Y1126914D03*
X1332288D03*
X1324886Y1133292D03*
X1332288D03*
X1330439Y1130102D03*
X1324886Y1139669D03*
X1330437Y1136480D03*
X1332288Y1139669D03*
X1330437Y1142858D03*
X1332288Y1146047D03*
X1330437Y1149236D03*
X1324886Y1146047D03*
X1332288Y1165181D03*
X1323036Y1155614D03*
Y1161992D03*
X1332288Y1152425D03*
X1330437Y1155614D03*
X1324886Y1152425D03*
X1332288Y1158803D03*
X1328587D03*
X1324886D03*
X1330437Y1161992D03*
X1324886Y1165181D03*
X1322795Y1547243D03*
X1324189Y1540295D03*
X1327519Y1547243D03*
X1328914Y1540295D03*
X1332244Y1547243D03*
X1333638Y1540295D03*
X1321623Y1552195D03*
X1331914Y1554453D03*
X1327189D03*
X1322465D03*
X1332465Y1561853D03*
X1327740D03*
X1323016D03*
X1333638Y1575641D03*
X1331964Y1569063D03*
X1328914Y1575641D03*
X1327239Y1569063D03*
X1324189Y1575641D03*
X1322514Y1569063D03*
X1326499Y1625380D03*
X1322239D03*
X1334299D03*
X1320479Y1635380D03*
X1328259D03*
X1332539D03*
X1328259Y1647292D03*
X1320479D03*
X1332539D03*
X1322239Y1657292D03*
X1326499D03*
X1334299D03*
X1331691Y1679320D03*
Y1683857D03*
X1323817Y1684454D03*
Y1679920D03*
Y1675383D03*
X1331691Y1688391D03*
Y1693493D03*
Y1698030D03*
X1323817Y1698627D03*
Y1694093D03*
Y1689556D03*
X1331691Y1716737D03*
Y1702564D03*
Y1707666D03*
Y1712203D03*
X1323817Y1712800D03*
Y1708266D03*
Y1703729D03*
X1331691Y1721840D03*
Y1726377D03*
Y1730911D03*
X1323817Y1726974D03*
Y1722440D03*
Y1717903D03*
X1337839Y1028055D03*
Y1040811D03*
Y1034433D03*
X1343390Y1031244D03*
Y1044000D03*
X1345241Y1040811D03*
Y1034433D03*
X1337839Y1047189D03*
Y1053567D03*
Y1059945D03*
X1339689Y1056756D03*
X1343390Y1050378D03*
X1345241Y1053567D03*
X1341540Y1059945D03*
X1345241D03*
X1337839Y1072701D03*
Y1066323D03*
X1343390Y1063134D03*
Y1069512D03*
X1345241Y1072701D03*
X1337839Y1079079D03*
Y1085457D03*
X1345241Y1079079D03*
X1343390Y1088646D03*
Y1082268D03*
X1337839Y1091835D03*
Y1098213D03*
Y1104591D03*
X1345241Y1091835D03*
X1343390Y1101402D03*
X1345241Y1098213D03*
X1337839Y1110969D03*
Y1117347D03*
X1343390Y1107780D03*
X1345241Y1110969D03*
Y1117347D03*
X1337839Y1123725D03*
Y1130102D03*
X1343390Y1120536D03*
Y1126914D03*
X1345241Y1130102D03*
X1337839Y1136480D03*
Y1142858D03*
Y1149236D03*
X1343390Y1139669D03*
X1345241Y1136480D03*
Y1149236D03*
X1343390Y1146047D03*
X1337839Y1155614D03*
X1335989Y1158803D03*
X1337839Y1161992D03*
X1341540Y1155614D03*
X1339689Y1158803D03*
X1348941Y1155614D03*
X1345241D03*
X1339689Y1165181D03*
X1336968Y1547243D03*
X1338362Y1540295D03*
X1341693Y1547243D03*
X1343087Y1540295D03*
X1346417Y1547243D03*
X1347811Y1540295D03*
X1346087Y1554453D03*
X1341362D03*
X1336638D03*
X1346638Y1561853D03*
X1341913D03*
X1337189D03*
X1347811Y1575641D03*
X1343087D03*
X1338362D03*
X1336688Y1569063D03*
X1338559Y1625380D03*
X1346359D03*
X1340319Y1635380D03*
X1344599D03*
X1340319Y1647292D03*
X1344599D03*
X1338559Y1657292D03*
X1346359D03*
X1347439Y1679320D03*
Y1683857D03*
X1339565Y1684454D03*
Y1679920D03*
Y1675383D03*
X1347439Y1688391D03*
Y1693493D03*
Y1698030D03*
X1339565Y1698627D03*
Y1694093D03*
Y1689556D03*
X1347439Y1716737D03*
Y1702564D03*
Y1707666D03*
Y1712203D03*
X1339565Y1712800D03*
Y1708266D03*
Y1703729D03*
X1347439Y1721840D03*
Y1726377D03*
Y1730911D03*
X1339565Y1726974D03*
Y1722440D03*
Y1717903D03*
X1356343Y1028055D03*
X1363745D03*
X1350792Y1031244D03*
Y1044000D03*
Y1037622D03*
X1356343Y1034433D03*
Y1040811D03*
X1363745Y1034433D03*
Y1040811D03*
X1361894Y1044000D03*
Y1037622D03*
Y1031244D03*
X1354493Y1056756D03*
X1350792D03*
Y1050378D03*
X1352642Y1059945D03*
X1356343Y1047189D03*
X1363745D03*
X1356343Y1053567D03*
X1361894Y1050378D03*
X1356343Y1059945D03*
X1363745Y1053567D03*
X1350792Y1063134D03*
Y1069512D03*
X1358193Y1063134D03*
X1356343Y1072701D03*
X1363745Y1066323D03*
X1358193Y1069512D03*
X1360044Y1066323D03*
X1361894Y1069512D03*
Y1063134D03*
X1350792Y1075890D03*
Y1082268D03*
Y1088646D03*
X1358193Y1075890D03*
X1363745Y1079079D03*
X1360044D03*
X1356343Y1085457D03*
X1358193Y1088646D03*
Y1082268D03*
X1361894Y1075890D03*
Y1088646D03*
Y1082268D03*
X1350792Y1095024D03*
Y1101402D03*
X1356343Y1104591D03*
X1363745Y1091835D03*
X1360044D03*
X1358193Y1095024D03*
X1356343Y1098213D03*
X1363745Y1104591D03*
X1360044D03*
X1361894Y1095024D03*
X1350792Y1107780D03*
Y1114158D03*
X1358193Y1107780D03*
X1360044Y1110969D03*
X1363745D03*
X1356343Y1117347D03*
X1358193Y1114158D03*
X1350792Y1120536D03*
Y1126914D03*
Y1133292D03*
X1358193Y1126914D03*
X1363745Y1123725D03*
X1360044D03*
X1358193Y1120536D03*
X1356343Y1130102D03*
X1358193Y1133292D03*
X1350792Y1139669D03*
Y1146047D03*
X1358193Y1139669D03*
X1363745Y1136480D03*
X1360044D03*
X1356343Y1142858D03*
X1363745Y1149236D03*
X1360044D03*
X1358193Y1146047D03*
X1354493Y1158803D03*
X1350792Y1152425D03*
Y1158803D03*
X1352642Y1161992D03*
X1356343Y1155614D03*
X1363745D03*
X1360044D03*
X1363745Y1161992D03*
X1351141Y1547243D03*
X1352536Y1540295D03*
X1355866Y1547243D03*
X1357260Y1540295D03*
X1360590Y1547243D03*
X1361984Y1540295D03*
X1360260Y1554453D03*
X1355536D03*
X1350811D03*
X1360811Y1561853D03*
X1356087D03*
X1351362D03*
X1361984Y1575641D03*
X1360310Y1569063D03*
X1352536Y1575641D03*
X1350861Y1569063D03*
X1357260Y1575641D03*
X1350619Y1625380D03*
X1358419D03*
X1362679D03*
X1352379Y1635380D03*
X1356659D03*
X1364439D03*
X1356659Y1647292D03*
X1352379D03*
X1364439D03*
X1358419Y1657292D03*
X1350619D03*
X1362679D03*
X1363187Y1679320D03*
Y1683857D03*
X1355313Y1684454D03*
Y1679920D03*
Y1675383D03*
Y1694093D03*
Y1689556D03*
X1363187Y1688391D03*
Y1693493D03*
Y1698030D03*
X1355313Y1698627D03*
X1363187Y1716737D03*
Y1702564D03*
Y1707666D03*
Y1712203D03*
X1355313Y1712800D03*
Y1708266D03*
Y1703729D03*
X1363187Y1726377D03*
Y1730911D03*
X1355313Y1726974D03*
Y1722440D03*
Y1717903D03*
X1363187Y1721840D03*
X1371146Y1028055D03*
X1374847D03*
X1369296Y1044000D03*
Y1037622D03*
Y1031244D03*
X1371146Y1034433D03*
X1376697Y1037622D03*
X1378548Y1040811D03*
X1371146D03*
X1374847Y1034433D03*
X1376697Y1031244D03*
Y1044000D03*
X1378548Y1053567D03*
X1376697Y1050378D03*
X1367445Y1059945D03*
X1369296Y1056756D03*
Y1050378D03*
X1371146Y1047189D03*
X1378548D03*
X1376697Y1056756D03*
X1371146Y1053567D03*
X1378548Y1059945D03*
X1369296Y1063134D03*
Y1069512D03*
X1367445Y1066323D03*
Y1072701D03*
X1371146Y1066323D03*
X1378548D03*
X1374847D03*
X1378548Y1072701D03*
X1372997Y1069512D03*
Y1063134D03*
X1365595Y1069512D03*
Y1063134D03*
X1376697Y1069512D03*
Y1063134D03*
X1369296Y1075890D03*
X1367445Y1079079D03*
X1369296Y1088646D03*
X1367445Y1085457D03*
X1369296Y1082268D03*
X1371146Y1079079D03*
X1378548D03*
X1374847D03*
X1378548Y1085457D03*
X1372997Y1075890D03*
X1365595D03*
X1376697D03*
X1372997Y1088646D03*
Y1082268D03*
X1365595Y1088646D03*
Y1082268D03*
X1376697Y1088646D03*
Y1082268D03*
X1367445Y1091835D03*
X1369296Y1095024D03*
X1367445Y1104591D03*
Y1098213D03*
X1371146Y1091835D03*
X1378548D03*
X1374847D03*
X1371146Y1104591D03*
X1374847D03*
X1378548Y1098213D03*
Y1104591D03*
X1372997Y1095024D03*
X1365595D03*
X1376697D03*
X1369296Y1107780D03*
X1367445Y1110969D03*
X1369296Y1114158D03*
X1367445Y1117347D03*
X1371146Y1110969D03*
X1378548D03*
X1374847D03*
X1378548Y1117347D03*
X1367445Y1130103D03*
X1369296Y1126914D03*
Y1120536D03*
X1367445Y1123725D03*
X1369296Y1133292D03*
X1374847Y1123725D03*
X1371146D03*
X1378548D03*
Y1130102D03*
X1369296Y1139669D03*
X1367445Y1136480D03*
Y1142858D03*
X1369296Y1146047D03*
X1374847Y1136480D03*
X1371146D03*
X1378548D03*
Y1142858D03*
X1371146Y1149236D03*
X1374847D03*
X1367445Y1155614D03*
X1365595Y1158803D03*
X1371146Y1155614D03*
X1378548D03*
X1374847D03*
X1376697Y1158803D03*
Y1165181D03*
X1374847Y1161992D03*
X1365315Y1547243D03*
X1366709Y1540295D03*
X1370039Y1547243D03*
X1371433Y1540295D03*
X1374763Y1547243D03*
X1376158Y1540295D03*
X1379488Y1547243D03*
X1379158Y1554453D03*
X1374433D03*
X1369709D03*
X1364984D03*
X1374984Y1561853D03*
X1370260D03*
X1365535D03*
X1371433Y1575641D03*
X1366709D03*
X1376158D03*
X1374483Y1569063D03*
X1370479Y1625380D03*
X1374740D03*
X1368719Y1635380D03*
X1376499Y1635286D03*
X1368719Y1647292D03*
X1376499D03*
X1370479Y1657292D03*
X1374739D03*
X1385937Y1028063D03*
Y1034441D03*
X1393339Y1040819D03*
X1385937D03*
X1385949Y1047189D03*
Y1053567D03*
X1384099Y1056756D03*
Y1050378D03*
X1393351Y1047189D03*
Y1053567D03*
X1389650Y1059945D03*
X1391500Y1056756D03*
Y1050378D03*
X1389650Y1066323D03*
X1391500Y1069512D03*
X1389650Y1072701D03*
X1380398Y1063134D03*
X1385949Y1066323D03*
X1382249D03*
X1380398Y1069512D03*
X1391500Y1063134D03*
X1393351Y1066323D03*
X1384099Y1069512D03*
Y1063134D03*
X1387800Y1069512D03*
Y1063134D03*
X1380398Y1075890D03*
X1385949Y1079079D03*
X1382249D03*
X1380398Y1088646D03*
Y1082268D03*
X1391500Y1075890D03*
X1393351Y1079079D03*
X1389650D03*
X1391500Y1088646D03*
X1389650Y1085457D03*
X1391500Y1082268D03*
X1384099Y1075890D03*
X1387800D03*
X1384099Y1088646D03*
Y1082268D03*
X1387800Y1088646D03*
Y1082268D03*
X1385949Y1091835D03*
X1382249D03*
X1380398Y1095024D03*
X1393351Y1091835D03*
X1389650D03*
X1391500Y1095024D03*
Y1101402D03*
X1389650Y1098213D03*
X1393351Y1104591D03*
X1389650D03*
X1384099Y1095024D03*
X1387800D03*
X1385949Y1110969D03*
X1382249D03*
X1380398Y1107780D03*
Y1114158D03*
X1393351Y1110969D03*
X1389650D03*
X1391500Y1107780D03*
X1389650Y1117347D03*
X1391500Y1114158D03*
X1385949Y1123725D03*
X1382249D03*
X1380398Y1120536D03*
Y1126914D03*
Y1133292D03*
X1393351Y1123725D03*
X1389650D03*
X1391500Y1120536D03*
Y1126914D03*
Y1133292D03*
X1389650Y1130102D03*
X1380398Y1139669D03*
X1385949Y1136480D03*
X1382249D03*
X1385949Y1149236D03*
X1382249D03*
X1380398Y1146047D03*
X1391500Y1139669D03*
X1393351Y1136480D03*
X1389650D03*
Y1142858D03*
X1393351Y1149236D03*
X1391500Y1146047D03*
X1385949Y1155614D03*
X1382249D03*
X1385949Y1161992D03*
X1387800Y1158803D03*
X1393351Y1155614D03*
X1389650D03*
X1380882Y1540295D03*
X1384212Y1547243D03*
X1385606Y1540295D03*
X1390331D03*
X1393661Y1547243D03*
X1393331Y1554453D03*
X1388607D03*
X1383882D03*
X1393882Y1561853D03*
X1389158D03*
X1384433D03*
X1379709D03*
X1385606Y1575641D03*
X1383932Y1569063D03*
X1380882Y1575641D03*
X1390331D03*
X1393381Y1569063D03*
X1382539Y1625380D03*
X1388569Y1635380D03*
X1380779D03*
Y1647292D03*
X1388569D03*
X1382539Y1657292D03*
X1400740Y1040819D03*
X1400752Y1047189D03*
X1398902Y1056756D03*
X1400752Y1053567D03*
Y1059945D03*
X1398902Y1050378D03*
X1408154Y1047189D03*
Y1053567D03*
X1406304Y1056756D03*
Y1050378D03*
X1404453Y1059945D03*
X1408154D03*
X1402603Y1063134D03*
Y1069512D03*
X1397052Y1066323D03*
X1400752D03*
Y1072701D03*
X1406304Y1063134D03*
X1395201D03*
X1404453Y1072701D03*
Y1066323D03*
X1395201Y1069512D03*
X1398902Y1063134D03*
X1408154Y1072701D03*
Y1066323D03*
X1398902Y1069512D03*
X1402603Y1075890D03*
X1400752Y1079079D03*
X1397052D03*
X1402603Y1088646D03*
Y1082268D03*
X1400752Y1085457D03*
X1406304Y1075890D03*
Y1088646D03*
X1395201Y1075890D03*
X1404453Y1079079D03*
X1398902Y1075890D03*
X1408154Y1079079D03*
X1395201Y1082268D03*
X1404453Y1085457D03*
X1395201Y1088646D03*
X1398902Y1082268D03*
X1408154Y1085457D03*
X1398902Y1088646D03*
X1402603Y1095024D03*
X1400752Y1091835D03*
X1397052D03*
X1402603Y1101402D03*
X1400752Y1104591D03*
X1397052D03*
X1400752Y1098213D03*
X1406304Y1101402D03*
X1395201Y1095024D03*
Y1101402D03*
X1404453Y1098213D03*
Y1091835D03*
X1398902Y1095024D03*
Y1101402D03*
X1408154Y1098213D03*
Y1091835D03*
X1402603Y1107780D03*
X1397052Y1110969D03*
X1400752D03*
X1402603Y1114158D03*
X1400752Y1117347D03*
X1406304Y1107780D03*
X1402603Y1120536D03*
Y1126914D03*
X1397052Y1123725D03*
X1400752D03*
X1402603Y1133292D03*
X1406304Y1120536D03*
Y1133292D03*
X1400752Y1130103D03*
X1402603Y1139669D03*
X1397052Y1136480D03*
X1400752D03*
Y1142858D03*
X1402603Y1146047D03*
X1397052Y1149236D03*
X1408154D03*
X1404453D03*
X1398902Y1158803D03*
X1397052Y1155614D03*
X1400752D03*
X1397052Y1161992D03*
X1398902Y1165181D03*
X1406304Y1158803D03*
X1395055Y1540295D03*
X1398076Y1554453D03*
X1395055Y1575641D03*
X1398712Y1569063D03*
X1411855Y1059945D03*
X1422932Y1047189D03*
Y1059945D03*
Y1053567D03*
X1410004Y1063134D03*
X1411855Y1066323D03*
Y1072701D03*
X1422932D03*
Y1066323D03*
X1410004Y1075890D03*
X1411855Y1079079D03*
Y1085457D03*
X1410004Y1088646D03*
X1422932Y1079079D03*
Y1085457D03*
Y1091835D03*
Y1104591D03*
Y1098213D03*
X1411855Y1091835D03*
Y1104591D03*
Y1098213D03*
X1410004Y1101402D03*
Y1107780D03*
X1411855Y1110969D03*
Y1117347D03*
X1422932Y1110969D03*
Y1117347D03*
X1411855Y1123725D03*
X1410004Y1120536D03*
X1411855Y1130102D03*
X1410004Y1133292D03*
X1422932Y1123725D03*
Y1130102D03*
X1411855Y1136480D03*
Y1142858D03*
Y1149236D03*
X1422932Y1136480D03*
Y1142858D03*
Y1149236D03*
X1411855Y1155614D03*
Y1161992D03*
X1422932Y1155614D03*
Y1161992D03*
X1430346Y1040819D03*
X1437748D03*
X1430334Y1047189D03*
X1424783Y1056756D03*
X1434035Y1059945D03*
X1432184Y1056756D03*
X1430334Y1053567D03*
X1424783Y1050378D03*
X1432184D03*
X1437735Y1047189D03*
Y1053567D03*
X1430334Y1059945D03*
X1426633D03*
X1432184Y1063134D03*
X1428483D03*
X1424783D03*
X1432184Y1069512D03*
X1434035Y1072701D03*
Y1066323D03*
X1437735D03*
X1430334D03*
Y1072701D03*
X1426633Y1066323D03*
Y1072701D03*
X1435885Y1063134D03*
Y1069512D03*
X1437735Y1079079D03*
X1428483Y1075890D03*
X1432184D03*
X1424783D03*
X1434035Y1079079D03*
X1424783Y1088646D03*
X1432184Y1082268D03*
X1428483Y1088646D03*
X1432184D03*
X1434035Y1085457D03*
X1430334Y1079079D03*
X1426633D03*
X1435885Y1075890D03*
Y1088646D03*
X1430334Y1085457D03*
X1426633D03*
X1435885Y1082268D03*
X1432184Y1095024D03*
X1434035Y1091835D03*
Y1104591D03*
X1428483Y1101402D03*
X1432184D03*
X1434035Y1098213D03*
X1424783Y1101402D03*
X1437735Y1091835D03*
Y1104591D03*
X1435885Y1101402D03*
Y1095024D03*
X1430334Y1091835D03*
Y1098213D03*
X1426633Y1091835D03*
Y1098213D03*
X1428483Y1107780D03*
X1432184D03*
X1424783D03*
X1434035Y1110969D03*
Y1117347D03*
X1432184Y1114158D03*
X1437735Y1110969D03*
X1432184Y1126914D03*
Y1120536D03*
X1428483D03*
X1424783D03*
X1434035Y1123725D03*
X1424783Y1133292D03*
X1428483D03*
X1432184D03*
X1437735Y1123725D03*
X1434035Y1130103D03*
X1432184Y1139669D03*
X1434035Y1136480D03*
Y1142858D03*
X1430334Y1149236D03*
X1432184Y1146047D03*
X1426633Y1149236D03*
X1437735Y1136480D03*
Y1149236D03*
X1430333Y1155614D03*
X1435885Y1158803D03*
Y1152425D03*
X1452542Y1040819D03*
X1445149D03*
X1445137Y1047189D03*
X1446987Y1056756D03*
X1445137Y1059945D03*
X1439586Y1056756D03*
X1445137Y1053567D03*
X1439586Y1050378D03*
X1446987D03*
X1452539Y1047189D03*
Y1053567D03*
X1443287Y1063134D03*
X1445137Y1072701D03*
X1443287Y1069512D03*
X1448838Y1066323D03*
X1445137D03*
X1441436D03*
X1452539D03*
X1439586Y1063134D03*
Y1069512D03*
X1450688Y1063134D03*
Y1069512D03*
X1446987Y1063134D03*
Y1069512D03*
X1445137Y1079079D03*
X1448838D03*
X1441436D03*
X1443287Y1075890D03*
Y1088646D03*
X1445137Y1085457D03*
X1443287Y1082268D03*
X1452539Y1079079D03*
X1439586Y1075890D03*
X1450688D03*
X1446987D03*
X1439586Y1088646D03*
X1450688Y1082268D03*
X1446987D03*
X1439586D03*
X1450688Y1088646D03*
X1446987D03*
X1441436Y1091835D03*
X1448838D03*
X1445137D03*
X1443287Y1095024D03*
X1445137Y1104591D03*
X1443287Y1101402D03*
X1445137Y1098213D03*
X1441436Y1104591D03*
X1452539Y1091835D03*
X1439586Y1101402D03*
Y1095024D03*
X1450688D03*
X1446987D03*
X1441436Y1110969D03*
X1448838D03*
X1445137D03*
X1443287Y1107780D03*
X1445137Y1117347D03*
X1443287Y1114158D03*
X1452539Y1110969D03*
X1445137Y1123725D03*
X1448838D03*
X1443287Y1120536D03*
X1441436Y1123725D03*
X1443287Y1126914D03*
Y1133292D03*
X1445137Y1130102D03*
X1452539Y1123725D03*
X1448838Y1149236D03*
X1443287Y1146047D03*
X1441436Y1149236D03*
X1452539Y1136480D03*
Y1149236D03*
X1445137Y1142858D03*
X1443287Y1139669D03*
X1445137Y1136480D03*
X1448838D03*
X1441436D03*
X1446987Y1158803D03*
X1450688Y1152425D03*
X1441436Y1155614D03*
X1449626Y1556810D03*
Y1561725D03*
X1463641Y1028055D03*
X1456239D03*
X1459940Y1040811D03*
X1458090Y1031244D03*
X1463641Y1034433D03*
X1456239D03*
X1465491Y1031244D03*
X1454389Y1037622D03*
X1467342Y1040811D03*
X1454389Y1044000D03*
X1461791Y1037622D03*
Y1044000D03*
X1459940Y1047189D03*
X1456239Y1059945D03*
X1459940Y1053567D03*
X1454389Y1056756D03*
X1461791D03*
X1454389Y1050378D03*
X1461791D03*
X1467342Y1047189D03*
Y1059945D03*
Y1053567D03*
X1465491Y1063134D03*
X1454389D03*
X1456239Y1072701D03*
X1459940Y1066323D03*
X1463641D03*
X1465491Y1069512D03*
X1454389D03*
X1456239Y1066323D03*
X1467342Y1072701D03*
Y1066323D03*
X1461791Y1063134D03*
Y1069512D03*
X1458090Y1063134D03*
Y1069512D03*
X1459940Y1079079D03*
X1463641D03*
X1456239D03*
X1465491Y1075890D03*
X1454389D03*
X1465491Y1088646D03*
X1454389D03*
X1456239Y1085457D03*
X1465491Y1082268D03*
X1454389D03*
X1467342Y1079079D03*
Y1085457D03*
X1461791Y1075890D03*
X1458090D03*
X1461791Y1082268D03*
Y1088646D03*
X1458090Y1082268D03*
Y1088646D03*
X1456239Y1098213D03*
X1467342Y1091835D03*
Y1104591D03*
Y1098213D03*
X1463641Y1091835D03*
X1459940D03*
X1456239D03*
X1465491Y1095024D03*
X1454389D03*
X1459940Y1104591D03*
X1463641D03*
X1456239D03*
X1461791Y1095024D03*
X1458090D03*
X1465491Y1107780D03*
X1454389D03*
X1463641Y1110969D03*
X1459940D03*
X1456239D03*
Y1117347D03*
X1454389Y1114158D03*
X1465491D03*
X1467342Y1110969D03*
Y1117347D03*
X1454389Y1120536D03*
X1465491Y1126914D03*
X1454389D03*
X1459940Y1123725D03*
X1463641D03*
X1465491Y1120536D03*
X1456239Y1123725D03*
X1454389Y1133292D03*
X1456239Y1130102D03*
X1465491Y1133292D03*
X1467342Y1123725D03*
Y1130102D03*
X1456239Y1142858D03*
X1465491Y1139669D03*
X1459940Y1136480D03*
X1463641D03*
X1454389Y1139669D03*
X1456239Y1136480D03*
X1465491Y1146047D03*
X1459940Y1149236D03*
X1463641D03*
X1454389Y1146047D03*
X1467342Y1136480D03*
Y1142858D03*
X1463641Y1155614D03*
X1461791Y1152425D03*
X1458090Y1158803D03*
X1454994Y1540512D03*
X1458907Y1547243D03*
X1460301Y1540295D03*
X1463631Y1547243D03*
X1465026Y1540295D03*
X1468356Y1547243D03*
X1457735Y1552195D03*
X1468026Y1554453D03*
X1463301D03*
X1458577D03*
X1468577Y1561853D03*
X1463852D03*
X1459128D03*
X1455098Y1575425D03*
X1468076Y1569063D03*
X1463351D03*
X1460301Y1575641D03*
X1458626Y1569063D03*
X1465026Y1575641D03*
X1458013Y1625380D03*
X1465813D03*
X1464053Y1635380D03*
Y1647292D03*
X1465813Y1657292D03*
X1458013D03*
X1478444Y1028055D03*
X1471043D03*
X1472893Y1031244D03*
X1469192Y1037622D03*
Y1044000D03*
X1478444Y1034433D03*
X1476594Y1037622D03*
X1474743Y1040811D03*
X1476594Y1044000D03*
X1471043Y1034433D03*
X1474743Y1047189D03*
X1480295Y1056756D03*
X1482145Y1059945D03*
X1469192Y1050378D03*
X1476594D03*
Y1056756D03*
X1474743Y1053567D03*
X1478444Y1059945D03*
X1469192Y1056756D03*
X1476594Y1063134D03*
X1478444Y1072701D03*
X1476594Y1069512D03*
X1474743Y1066323D03*
X1471043D03*
X1472893Y1063134D03*
Y1069512D03*
X1469192Y1063134D03*
Y1069512D03*
X1476594Y1075890D03*
X1474743Y1079079D03*
X1471043D03*
X1478444Y1085457D03*
X1476594Y1088646D03*
Y1082268D03*
X1472893Y1075890D03*
X1469192D03*
X1472893Y1082268D03*
Y1088646D03*
X1469192Y1082268D03*
Y1088646D03*
X1474743Y1091835D03*
X1471043D03*
X1476594Y1095024D03*
X1478444Y1098213D03*
Y1104591D03*
X1474743D03*
X1471043D03*
X1472893Y1101402D03*
Y1095024D03*
X1469192D03*
X1476594Y1107780D03*
X1474743Y1110969D03*
X1471043D03*
X1476594Y1114158D03*
X1478444Y1117347D03*
X1476594Y1126914D03*
Y1120536D03*
X1474743Y1123725D03*
X1471043D03*
X1478444Y1130102D03*
X1476594Y1133292D03*
Y1139669D03*
X1474743Y1136480D03*
X1471043D03*
X1478444Y1142858D03*
X1476594Y1146047D03*
X1474743Y1149236D03*
X1471043D03*
X1474743Y1155614D03*
X1478444D03*
X1472893Y1152425D03*
X1480295Y1158803D03*
X1469192D03*
X1469750Y1540295D03*
X1473080Y1547243D03*
X1474474Y1540295D03*
X1477805Y1547243D03*
X1479199Y1540295D03*
X1482529Y1547243D03*
X1483923Y1540295D03*
X1482199Y1554453D03*
X1477474D03*
X1472750D03*
X1482750Y1561853D03*
X1478025D03*
X1473301D03*
X1469750Y1575641D03*
X1483923D03*
X1474474D03*
X1472800Y1569063D03*
X1479199Y1575641D03*
X1470073Y1625380D03*
X1482133D03*
X1477873D03*
X1471833Y1635380D03*
X1483893D03*
X1476113D03*
X1471833Y1647292D03*
X1483893D03*
X1476113D03*
X1470073Y1657292D03*
X1477873D03*
X1482133D03*
X1489547Y1028055D03*
X1496948D03*
X1483995Y1031244D03*
Y1037622D03*
Y1044000D03*
X1491397Y1031244D03*
X1489547Y1040811D03*
Y1034433D03*
X1491397Y1044000D03*
X1496948Y1034433D03*
Y1040811D03*
Y1047189D03*
X1483995Y1050378D03*
Y1056756D03*
X1489547Y1053567D03*
X1495098Y1056756D03*
X1491397Y1050378D03*
X1489547Y1059945D03*
X1493247D03*
X1496948Y1053567D03*
Y1059945D03*
X1483995Y1063134D03*
X1491397D03*
X1483995Y1069512D03*
X1489547Y1072701D03*
X1491397Y1069512D03*
X1496948Y1072701D03*
Y1066323D03*
X1483995Y1075890D03*
X1489547Y1079079D03*
X1496948D03*
X1483995Y1088646D03*
X1491397D03*
X1496948Y1085457D03*
X1483995Y1082268D03*
X1491397D03*
X1489547Y1091835D03*
X1496948D03*
X1483995Y1095024D03*
Y1101402D03*
X1489547Y1098213D03*
X1491397Y1101402D03*
X1496948Y1098213D03*
Y1104591D03*
X1489547Y1110969D03*
X1496948D03*
X1483995Y1107780D03*
X1491397D03*
X1483995Y1114158D03*
X1489547Y1117347D03*
X1496948D03*
X1483995Y1120536D03*
X1491397D03*
X1496948Y1123725D03*
X1483995Y1126914D03*
X1491397D03*
X1483995Y1133292D03*
X1496948Y1130102D03*
X1489547Y1130103D03*
X1483995Y1139669D03*
X1489547Y1136480D03*
X1491397Y1139669D03*
X1496948Y1136480D03*
Y1142858D03*
X1483995Y1146047D03*
X1489547Y1149236D03*
X1491397Y1146047D03*
X1496948Y1149236D03*
X1487696Y1165181D03*
X1498799Y1158803D03*
X1483995Y1152425D03*
X1485846Y1155614D03*
X1489547D03*
X1493247D03*
X1496948D03*
X1483995Y1158803D03*
X1491397D03*
X1493247Y1161992D03*
X1495111Y1165289D03*
X1491410D03*
X1498812D03*
X1488648Y1540295D03*
X1487253Y1547243D03*
X1491978D03*
X1493372Y1540295D03*
X1496702Y1547243D03*
X1498096Y1540295D03*
X1496372Y1554453D03*
X1491648D03*
X1486923D03*
X1496923Y1561853D03*
X1492199D03*
X1487474D03*
X1488648Y1575641D03*
X1493372D03*
X1498096D03*
X1496422Y1569063D03*
X1486973D03*
X1489933Y1625380D03*
X1494193D03*
X1495953Y1635380D03*
X1488173D03*
X1495953Y1647292D03*
X1488173D03*
X1494193Y1657292D03*
X1489933D03*
X1504350Y1028055D03*
X1502499Y1031244D03*
X1509901D03*
X1504350Y1040811D03*
X1502499Y1037622D03*
X1504350Y1034433D03*
X1502499Y1044000D03*
X1509901Y1037622D03*
Y1044000D03*
X1504350Y1047189D03*
Y1053567D03*
X1502499Y1050378D03*
X1509901Y1056756D03*
Y1050378D03*
X1504350Y1059945D03*
X1508050D03*
X1506200Y1056756D03*
X1502499D03*
Y1063134D03*
X1509901D03*
X1502499Y1069512D03*
X1504350Y1072701D03*
Y1066323D03*
X1509901Y1069512D03*
X1502499Y1075890D03*
X1509901D03*
X1504350Y1079079D03*
Y1085457D03*
X1502499Y1088646D03*
X1509901D03*
X1502499Y1082268D03*
X1509901D03*
X1504350Y1091835D03*
X1502499Y1095024D03*
X1509901D03*
X1504350Y1098213D03*
X1502499Y1101402D03*
X1509901D03*
X1504350Y1104591D03*
X1502499Y1107780D03*
X1509901D03*
X1504350Y1110969D03*
X1509901Y1114158D03*
X1504350Y1117347D03*
X1502499Y1114158D03*
Y1120536D03*
X1504350Y1123725D03*
X1509901Y1120536D03*
X1502499Y1126914D03*
X1509901D03*
Y1133292D03*
X1502499D03*
X1504350Y1130103D03*
X1502499Y1139669D03*
X1504350Y1136480D03*
X1509901Y1139669D03*
X1504350Y1142858D03*
Y1149236D03*
X1502499Y1146047D03*
X1509901D03*
X1504350Y1155614D03*
X1502499Y1152425D03*
X1509901D03*
X1511751Y1155614D03*
X1502499Y1158803D03*
X1506200D03*
X1509901D03*
X1509914Y1165289D03*
X1506213D03*
X1502821Y1540295D03*
X1501427Y1547243D03*
X1506151D03*
X1507545Y1540295D03*
X1510875Y1547243D03*
X1512270Y1540295D03*
X1510545Y1554453D03*
X1505821D03*
X1501096D03*
X1511096Y1561853D03*
X1506372D03*
X1501647D03*
X1507545Y1575641D03*
X1512270D03*
X1510595Y1569063D03*
X1502821Y1575641D03*
X1501993Y1625380D03*
X1506253D03*
X1508013Y1635380D03*
X1500233D03*
X1512293D03*
X1508013Y1647292D03*
X1500233D03*
X1512293D03*
X1501993Y1657292D03*
X1506253D03*
X1513187Y1679320D03*
Y1683857D03*
X1505313Y1684454D03*
Y1679920D03*
Y1675383D03*
X1513187Y1688391D03*
Y1693493D03*
Y1698030D03*
X1505313Y1698627D03*
Y1694093D03*
Y1689556D03*
X1513187Y1716737D03*
Y1702564D03*
Y1707666D03*
Y1712203D03*
X1505313Y1712800D03*
Y1708266D03*
Y1703729D03*
X1513187Y1721840D03*
Y1726377D03*
Y1730911D03*
X1505313Y1726974D03*
Y1722440D03*
Y1717903D03*
X1522854Y1028055D03*
X1515452D03*
X1522854Y1034433D03*
Y1040811D03*
X1517302Y1044000D03*
X1528405Y1037622D03*
Y1044000D03*
X1515452Y1040811D03*
Y1034433D03*
X1517302Y1031244D03*
X1528405D03*
X1515452Y1053567D03*
Y1059945D03*
X1522854Y1047189D03*
Y1053567D03*
X1521003Y1056756D03*
X1517302Y1050378D03*
X1522854Y1059945D03*
X1519153D03*
X1528405Y1050378D03*
Y1056756D03*
X1517302Y1063134D03*
X1528405D03*
X1515452Y1072701D03*
X1522854Y1066323D03*
Y1072701D03*
X1517302Y1069512D03*
X1528405D03*
Y1075890D03*
X1515452Y1079079D03*
X1522854D03*
X1517302Y1082268D03*
X1528405D03*
X1522854Y1085457D03*
X1517302Y1088646D03*
X1528405D03*
X1515452Y1091835D03*
X1522854D03*
X1528405Y1095024D03*
X1522854Y1104591D03*
X1528405Y1101402D03*
X1515452Y1098213D03*
X1522854D03*
X1517302Y1101402D03*
Y1107780D03*
X1528405D03*
X1522854Y1110969D03*
X1515452D03*
X1522854Y1117347D03*
X1528405Y1114158D03*
X1515452Y1117347D03*
X1522854Y1123725D03*
X1517302Y1120536D03*
X1528405D03*
X1517302Y1126914D03*
X1528405D03*
Y1133292D03*
X1515452Y1130102D03*
X1522854Y1130103D03*
Y1142858D03*
Y1136480D03*
X1517302Y1139669D03*
X1528405D03*
X1515452Y1136480D03*
X1528405Y1146047D03*
X1515452Y1149236D03*
X1522854D03*
X1517302Y1146047D03*
X1528405Y1152425D03*
X1524704Y1158803D03*
X1528405D03*
X1515452Y1155614D03*
X1519153D03*
X1522854D03*
X1519153Y1161992D03*
X1521718Y1540295D03*
X1515600Y1547243D03*
X1516994Y1540295D03*
X1520324Y1547243D03*
X1526443Y1540295D03*
X1524719Y1554453D03*
X1519994D03*
X1515270D03*
X1525270Y1561853D03*
X1520545D03*
X1515821D03*
X1516994Y1575641D03*
X1526443D03*
X1521718D03*
X1520044Y1569063D03*
X1514053Y1625380D03*
X1518313D03*
X1526113D03*
X1520073Y1635380D03*
X1524353D03*
X1520073Y1647292D03*
X1524353D03*
X1518313Y1657292D03*
X1514053D03*
X1526113D03*
X1521061Y1684454D03*
Y1679920D03*
Y1675383D03*
Y1698627D03*
Y1694093D03*
Y1689556D03*
Y1712800D03*
Y1708266D03*
Y1703729D03*
Y1726974D03*
Y1722440D03*
Y1717903D03*
X1530255Y1028055D03*
X1541358D03*
X1530255Y1034433D03*
Y1040811D03*
X1541357D03*
Y1034433D03*
X1543208Y1031244D03*
Y1044000D03*
X1535806Y1031244D03*
Y1037622D03*
Y1044000D03*
X1530255Y1047189D03*
Y1053567D03*
Y1059945D03*
X1541357Y1053567D03*
Y1059945D03*
X1543208Y1050378D03*
X1532106Y1056756D03*
X1535806D03*
Y1050378D03*
X1533956Y1059945D03*
X1530255Y1066323D03*
Y1072701D03*
X1543208Y1063134D03*
X1535806D03*
X1543208Y1069512D03*
X1541357Y1072701D03*
X1535806Y1069512D03*
X1530255Y1079079D03*
Y1085457D03*
X1535806Y1075890D03*
X1541357Y1079079D03*
X1543208Y1082268D03*
Y1088646D03*
X1535806D03*
Y1082268D03*
X1530255Y1098213D03*
Y1104591D03*
X1541357Y1091835D03*
X1535806Y1095024D03*
X1543208Y1101402D03*
X1541357Y1098213D03*
X1535806Y1101402D03*
X1530255Y1091835D03*
Y1110969D03*
Y1117347D03*
X1543208Y1107780D03*
X1535806D03*
X1541357Y1110969D03*
Y1117347D03*
X1535806Y1114158D03*
X1530255Y1123725D03*
Y1130102D03*
X1543208Y1120536D03*
X1535806D03*
X1543208Y1126914D03*
X1535806D03*
X1541357Y1130102D03*
X1535806Y1133292D03*
X1530255Y1142858D03*
Y1136480D03*
Y1149236D03*
X1541357Y1136480D03*
X1543208Y1139669D03*
X1535806D03*
X1543208Y1146047D03*
X1541357Y1149236D03*
X1535806Y1146047D03*
X1530255Y1155614D03*
X1537657D03*
X1541357D03*
X1535806Y1152425D03*
X1532106Y1158803D03*
X1535806D03*
X1541357Y1161992D03*
X1532106Y1165181D03*
X1531167Y1540295D03*
X1529773Y1547243D03*
X1534188Y1554453D03*
X1529443D03*
X1529994Y1561853D03*
X1534824Y1569063D03*
X1531167Y1575641D03*
X1529493Y1569063D03*
X1530373Y1625380D03*
X1542433D03*
X1538173D03*
X1532133Y1635380D03*
X1536413D03*
X1532133Y1647292D03*
X1536413D03*
X1530373Y1657292D03*
X1542433D03*
X1538173D03*
X1528935Y1679320D03*
Y1683857D03*
X1536809Y1684454D03*
Y1679920D03*
Y1675383D03*
X1528935Y1688391D03*
Y1693493D03*
Y1698030D03*
X1536809Y1698627D03*
Y1694093D03*
Y1689556D03*
X1528935Y1712203D03*
X1536809Y1712800D03*
Y1708266D03*
Y1703729D03*
X1528935Y1716737D03*
Y1702564D03*
Y1707666D03*
Y1721840D03*
Y1726377D03*
Y1730911D03*
X1536809Y1726974D03*
Y1722440D03*
Y1717903D03*
X1553870Y906181D03*
Y912559D03*
Y918937D03*
Y925315D03*
Y931693D03*
Y938071D03*
Y944449D03*
Y950827D03*
Y957205D03*
Y963583D03*
Y969961D03*
Y976339D03*
Y982717D03*
Y989095D03*
Y995473D03*
Y1008229D03*
Y1001851D03*
X1548759Y1028055D03*
X1555051Y1030197D03*
X1548759Y1040811D03*
Y1034433D03*
X1555051Y1042953D03*
Y1036575D03*
X1546909Y1056756D03*
X1545058Y1059945D03*
X1548759Y1047189D03*
X1555051Y1049331D03*
X1548759Y1053567D03*
Y1059945D03*
X1555051Y1055709D03*
Y1062087D03*
X1548759Y1072701D03*
Y1066323D03*
X1555051Y1068465D03*
Y1074843D03*
X1548759Y1079079D03*
X1555051Y1081221D03*
X1548759Y1085457D03*
X1555051Y1087599D03*
X1548759Y1091835D03*
X1555051Y1093977D03*
X1548759Y1098213D03*
Y1104591D03*
X1555051Y1100355D03*
Y1106733D03*
X1548759Y1110969D03*
X1555051Y1113111D03*
X1548759Y1117347D03*
X1555051Y1119489D03*
Y1132245D03*
X1548759Y1123725D03*
X1555051Y1125867D03*
X1548759Y1130102D03*
Y1136480D03*
X1555051Y1138622D03*
X1548759Y1142858D03*
X1555051Y1145000D03*
X1548759Y1149236D03*
X1545058Y1155614D03*
X1548759D03*
X1555051Y1151378D03*
X1550609Y1158803D03*
X1554310D03*
X1550233Y1625380D03*
X1554493D03*
X1544193Y1635380D03*
X1556253D03*
X1548473D03*
X1544193Y1647292D03*
X1556253D03*
X1548473D03*
X1554493Y1657292D03*
X1550233D03*
X1544683Y1679320D03*
Y1683857D03*
X1552557Y1684454D03*
Y1679920D03*
Y1675383D03*
X1544683Y1688391D03*
Y1693493D03*
Y1698030D03*
X1552557Y1698627D03*
Y1694093D03*
Y1689556D03*
X1544683Y1716737D03*
Y1702564D03*
Y1707666D03*
Y1712203D03*
X1552557Y1712800D03*
Y1708266D03*
Y1703729D03*
X1544683Y1721840D03*
Y1726377D03*
Y1730911D03*
X1552557Y1726974D03*
Y1722440D03*
Y1717903D03*
X1562293Y1625380D03*
X1566553D03*
X1568313Y1635380D03*
X1560533D03*
X1572593D03*
X1568313Y1647292D03*
X1560533D03*
X1572593D03*
X1562293Y1657292D03*
X1566553D03*
X1572243Y1684454D03*
Y1679920D03*
Y1675383D03*
X1560431Y1679320D03*
Y1683857D03*
X1572243Y1698627D03*
Y1694093D03*
Y1689556D03*
X1560431Y1688391D03*
Y1693493D03*
Y1698030D03*
X1572243Y1712800D03*
Y1708266D03*
Y1703729D03*
X1560431Y1716737D03*
Y1702564D03*
Y1707666D03*
Y1712203D03*
X1572243Y1726974D03*
Y1722440D03*
Y1717903D03*
X1560431Y1721840D03*
Y1726377D03*
Y1730911D03*
X1583056Y1540514D03*
X1586969Y1547243D03*
X1585797Y1552195D03*
X1586639Y1554453D03*
X1587190Y1561853D03*
X1577688Y1556810D03*
Y1561725D03*
X1586688Y1569063D03*
X1583160Y1575425D03*
X1574353Y1625380D03*
X1578613D03*
X1586413D03*
X1580373Y1635380D03*
X1584653D03*
X1580373Y1647292D03*
X1584653D03*
X1574353Y1657292D03*
X1578613D03*
X1586413D03*
X1580117Y1679320D03*
Y1683857D03*
X1587991Y1684454D03*
Y1679920D03*
Y1675383D03*
X1580117Y1688391D03*
Y1693493D03*
Y1698030D03*
X1587991Y1698627D03*
Y1694093D03*
Y1689556D03*
X1580117Y1716737D03*
Y1702564D03*
Y1707666D03*
Y1712203D03*
X1587991Y1712800D03*
Y1708266D03*
Y1703729D03*
X1580117Y1721840D03*
Y1726377D03*
Y1730911D03*
X1587991Y1726974D03*
Y1722440D03*
Y1717903D03*
X1588363Y1540295D03*
X1591693Y1547243D03*
X1593088Y1540295D03*
X1596418Y1547243D03*
X1597812Y1540295D03*
X1601142Y1547243D03*
X1602536Y1540295D03*
X1600812Y1554453D03*
X1596088D03*
X1591363D03*
X1601363Y1561853D03*
X1596639D03*
X1591914D03*
X1602536Y1575641D03*
X1600862Y1569063D03*
X1597812Y1575641D03*
X1596138Y1569063D03*
X1593088Y1575641D03*
X1591413Y1569063D03*
X1588363Y1575641D03*
X1590673Y1625380D03*
X1602733D03*
X1598473D03*
X1592433Y1635380D03*
X1596713D03*
X1592433Y1647292D03*
X1596713D03*
X1590673Y1657292D03*
X1598473D03*
X1602733D03*
X1595865Y1679320D03*
Y1683857D03*
Y1688391D03*
Y1693493D03*
Y1698030D03*
Y1716737D03*
Y1702564D03*
Y1707666D03*
Y1712203D03*
Y1721840D03*
Y1726377D03*
Y1730911D03*
X1605867Y1547243D03*
X1607261Y1540295D03*
X1610591Y1547243D03*
X1611985Y1540295D03*
X1615315Y1547243D03*
X1616710Y1540295D03*
X1614985Y1554453D03*
X1610261D03*
X1605536D03*
X1615536Y1561853D03*
X1610812D03*
X1606087D03*
X1616710Y1575641D03*
X1615035Y1569063D03*
X1611985Y1575641D03*
X1607261D03*
X1610533Y1625380D03*
X1614793D03*
X1604493Y1635380D03*
X1616553D03*
X1608773D03*
X1604493Y1647292D03*
X1616553D03*
X1608773D03*
X1614793Y1657292D03*
X1610533D03*
X1611613Y1679320D03*
Y1683857D03*
X1603739Y1684454D03*
Y1679920D03*
Y1675383D03*
X1611613Y1688391D03*
Y1693493D03*
Y1698030D03*
X1603739Y1698627D03*
Y1694093D03*
Y1689556D03*
X1611613Y1702564D03*
Y1707666D03*
Y1712203D03*
X1603739Y1712800D03*
Y1708266D03*
Y1703729D03*
X1611613Y1716737D03*
Y1721840D03*
Y1726377D03*
Y1730911D03*
X1603739Y1726974D03*
Y1722440D03*
Y1717903D03*
X1620040Y1547243D03*
X1621434Y1540295D03*
X1624764Y1547243D03*
X1626158Y1540295D03*
X1629489Y1547243D03*
X1630883Y1540295D03*
X1629158Y1554453D03*
X1624434D03*
X1619710D03*
X1629709Y1561853D03*
X1624985D03*
X1620261D03*
X1630883Y1575641D03*
X1626158D03*
X1624484Y1569063D03*
X1621434Y1575641D03*
X1622593Y1625380D03*
X1626853D03*
X1628613Y1635380D03*
X1620833D03*
X1632893D03*
X1628613Y1647292D03*
X1620833D03*
X1632893D03*
X1622593Y1657292D03*
X1626853D03*
X1627361Y1679320D03*
Y1683857D03*
X1619487Y1684454D03*
Y1679920D03*
Y1675383D03*
X1627361Y1688391D03*
Y1693493D03*
Y1698030D03*
X1619487Y1698627D03*
Y1694093D03*
Y1689556D03*
Y1708266D03*
Y1703729D03*
X1627361Y1716737D03*
Y1702564D03*
Y1707666D03*
Y1712203D03*
X1619487Y1712800D03*
X1627361Y1721840D03*
Y1726377D03*
Y1730911D03*
X1619487Y1726974D03*
Y1722440D03*
Y1717903D03*
X1634213Y1547243D03*
X1635607Y1540295D03*
X1638937Y1547243D03*
X1640332Y1540295D03*
X1643662Y1547243D03*
X1645056Y1540295D03*
X1643332Y1554453D03*
X1638607D03*
X1633883D03*
X1643883Y1561853D03*
X1639158D03*
X1634434D03*
X1645056Y1575641D03*
X1640332D03*
X1638657Y1569063D03*
X1635607Y1575641D03*
X1634653Y1625380D03*
X1638923D03*
X1646713D03*
X1640673Y1635286D03*
X1644953Y1635380D03*
X1640673Y1647292D03*
X1644953D03*
X1634653Y1657292D03*
X1638913D03*
X1646713D03*
X1648386Y1547243D03*
X1649780Y1540295D03*
X1654505D03*
X1657835Y1547243D03*
X1659229Y1540295D03*
X1662250Y1554453D03*
X1657505D03*
X1652781D03*
X1648056D03*
X1658056Y1561853D03*
X1653332D03*
X1648607D03*
X1649780Y1575641D03*
X1648106Y1569063D03*
X1654505Y1575641D03*
X1657555Y1569063D03*
X1659229Y1575641D03*
X1652743Y1635380D03*
Y1647292D03*
X1662886Y1569063D03*
G54D38*
X274913Y1019214D03*
X320189Y838505D03*
Y1199923D03*
X561133Y838505D03*
Y1199923D03*
X606409Y1019214D03*
X841240Y1420331D03*
X1016240D03*
X1251055Y1019213D03*
X1296331Y838504D03*
Y1199922D03*
X1537275Y838504D03*
Y1199922D03*
X1582551Y1019213D03*
G54D45*
X393287Y-28508D03*
Y-18508D03*
X731757Y-20090D03*
X735010Y-20104D03*
X728717Y-18895D03*
X734995Y-17589D03*
X731742Y-17575D03*
X735041Y-14717D03*
X735026Y-12202D03*
X734996Y-7172D03*
X728718Y-8478D03*
X735011Y-9687D03*
X731743Y-7158D03*
X731758Y-9673D03*
X844766Y-24648D03*
Y5352D03*
Y15352D03*
X1180124Y-35569D03*
X1183149Y-34249D03*
X1183164Y-36764D03*
X1183139Y-26179D03*
X1180099Y-14984D03*
X1183124Y-13664D03*
X1183139Y-16179D03*
X1183124Y-23664D03*
X1180099Y-24984D03*
X1183139Y-6179D03*
X1183124Y-3664D03*
X1180099Y-4984D03*
Y15016D03*
X1183124Y16336D03*
X1183139Y13821D03*
X1180099Y5016D03*
X1183124Y6336D03*
X1183139Y3821D03*
X1183140Y24187D03*
X1183125Y26702D03*
X1180100Y25382D03*
X1186402Y-34263D03*
X1186417Y-36778D03*
X1186448Y-31442D03*
X1186433Y-28927D03*
X1186392Y-26193D03*
X1186377Y-13678D03*
X1186392Y-16193D03*
X1186377Y-23678D03*
X1186392Y-6193D03*
X1186377Y-3678D03*
Y16322D03*
X1186392Y13807D03*
X1186377Y6322D03*
X1186392Y3807D03*
X1186423Y19143D03*
X1186408Y21658D03*
X1186393Y24173D03*
X1186378Y26688D03*
X1248286Y-34648D03*
Y-4648D03*
Y5352D03*
X1438983Y-35569D03*
X1438959Y25382D03*
X1445292Y-28927D03*
X1445307Y-31442D03*
X1442023Y-36764D03*
X1442008Y-34249D03*
X1445276Y-36778D03*
X1445261Y-34263D03*
X1441909Y-19948D03*
X1445171D03*
X1441909Y-9948D03*
X1445171D03*
X1441909Y52D03*
X1445171D03*
X1441909Y10052D03*
X1445171D03*
X1445237Y26688D03*
X1445252Y24173D03*
X1441984Y26702D03*
X1441999Y24187D03*
X1445267Y21658D03*
X1445282Y19143D03*
X1541580Y-38849D03*
Y-28849D03*
X1735374Y-27916D03*
X1732349Y-29236D03*
X1735389Y-30431D03*
X1735390Y-20014D03*
X1735375Y-17499D03*
X1732350Y-18819D03*
X1738627Y-27930D03*
X1738642Y-30445D03*
X1738643Y-20028D03*
X1738628Y-17513D03*
X1738673Y-25058D03*
X1738658Y-22543D03*
G54D79*
X1900275Y-39973D03*
X1910275D03*
X1931395Y572237D03*
X1921395D03*
X1929766Y1198160D03*
X1919766D03*
X1942395Y-39783D03*
X1952395D03*
X1963362Y572379D03*
X1961856Y1198170D03*
X1973362Y572379D03*
X1971856Y1198170D03*
X1984482Y-39811D03*
X1994482D03*
X2005452Y572389D03*
X2003823Y1198312D03*
X2015452Y572389D03*
X2013823Y1198312D03*
X2036452Y-39631D03*
X2026452D03*
X2047419Y572531D03*
X2057419D03*
G54D21*
X57646Y12480D03*
X137272D03*
X186622D03*
X266858D03*
X315598D03*
X502528Y33267D03*
X582154D03*
X631504D03*
X711740D03*
X760480D03*
X1532055Y12480D03*
X1611681D03*
X1661031D03*
X1741267D03*
X1790007D03*
G54D42*
X326731Y663237D03*
X363731D03*
X754645Y1436735D03*
X1166535Y1422322D03*
X1291146Y1385558D03*
X1320516D03*
X1487677Y649988D03*
X1524437Y650208D03*
X1701285Y208455D03*
X1700840Y1434362D03*
X1731660Y208455D03*
X1770442Y294777D03*
X1800002D03*
G54D63*
X1077638Y133866D03*
G54D26*
X77394Y734588D03*
Y1021399D03*
Y1277698D03*
X107095Y734588D03*
Y1021399D03*
Y1277698D03*
X136795Y734588D03*
Y1021399D03*
Y1277698D03*
X166496Y734588D03*
Y1021399D03*
Y1277698D03*
X196197Y734588D03*
Y1021399D03*
Y1277698D03*
X225898Y734588D03*
Y1021399D03*
Y1277698D03*
X655425Y734588D03*
Y1021399D03*
Y1277698D03*
X685126Y734588D03*
Y1021399D03*
Y1277698D03*
X714827Y734588D03*
Y1021399D03*
Y1277698D03*
X744528Y734588D03*
Y1021399D03*
Y1277698D03*
X774229Y734588D03*
Y1021399D03*
Y1277698D03*
X803929Y734588D03*
Y1021399D03*
Y1277698D03*
X1053536Y734587D03*
Y1021398D03*
Y1277697D03*
X1083237Y734587D03*
Y1021398D03*
Y1277697D03*
X1112937Y734587D03*
Y1021398D03*
Y1277697D03*
X1142638Y734587D03*
Y1021398D03*
Y1277697D03*
X1172339Y734587D03*
Y1021398D03*
Y1277697D03*
X1202040Y734587D03*
Y1021398D03*
Y1277697D03*
X1631567Y734587D03*
Y1021398D03*
Y1277697D03*
X1661268Y734587D03*
Y1021398D03*
Y1277697D03*
X1690969Y734587D03*
Y1021398D03*
Y1277697D03*
X1720670Y734587D03*
Y1021398D03*
Y1277697D03*
X1750371Y734587D03*
Y1021398D03*
Y1277697D03*
X1780071Y734587D03*
Y1021398D03*
Y1277697D03*
G54D57*
X887519Y1528191D03*
G54D69*
X1299439Y112812D03*
G54D70*
X1454797Y87432D03*
G54D71*
X1550377Y581353D03*
G54D49*
X549016Y274272D03*
G54D58*
X900197Y175177D03*
X944685Y155197D03*
G54D78*
X1864706Y1722195D03*
X1887340Y424013D03*
X1887240Y796658D03*
X1887579Y1171532D03*
G54D76*
X1865648Y796913D03*
X1866790Y1171255D03*
X1886177Y1722507D03*
X2076128Y424013D03*
%LPC*%
G75*
G54D83*
G01X-476840Y-884638D02*
Y2768362D01*
X5911000D01*
Y-884638D01*
X-476840D01*
G01X8000Y-625138D02*
Y-630138D01*
G01X6543Y-625138D02*
X9457D01*
G01X14367Y-630138D02*
X11833D01*
Y-625138D01*
X14367D01*
G01X13353Y-627555D02*
X11833D01*
G01X16933Y-625138D02*
Y-630138D01*
X19467D01*
G01X23300Y-630305D02*
X23173Y-630221D01*
Y-630055D01*
X23300Y-629971D01*
X23427Y-630055D01*
Y-630221D01*
X23300Y-630305D01*
G01Y-628055D02*
X23173Y-627971D01*
Y-627805D01*
X23300Y-627721D01*
X23427Y-627805D01*
Y-627971D01*
X23300Y-628055D01*
G01X28083Y-631805D02*
X27450Y-630971D01*
X27133Y-630138D01*
Y-626805D01*
X27450Y-625971D01*
X28083Y-625138D01*
G01X33500D02*
X32993Y-625305D01*
X32613Y-625721D01*
X32360Y-626221D01*
X32170Y-626888D01*
X32107Y-627638D01*
X32170Y-628388D01*
X32360Y-629055D01*
X32613Y-629555D01*
X32993Y-629971D01*
X33500Y-630138D01*
X34007Y-629971D01*
X34387Y-629555D01*
X34640Y-629055D01*
X34830Y-628388D01*
X34893Y-627638D01*
X34830Y-626888D01*
X34640Y-626221D01*
X34387Y-625721D01*
X34007Y-625305D01*
X33500Y-625138D01*
G01X37207Y-629138D02*
X37587Y-629721D01*
X38093Y-630055D01*
X38663Y-630138D01*
X39170Y-630055D01*
X39677Y-629638D01*
X39993Y-629138D01*
X40057Y-628638D01*
X39930Y-628055D01*
X39487Y-627638D01*
X39043Y-627471D01*
X38473D01*
G01X39043D02*
X39423Y-627221D01*
X39740Y-626805D01*
X39867Y-626305D01*
X39740Y-625805D01*
X39423Y-625388D01*
X38853Y-625138D01*
X38283Y-625221D01*
X37713Y-625555D01*
G01X44017Y-631805D02*
X44650Y-630971D01*
X44967Y-630138D01*
Y-626805D01*
X44650Y-625971D01*
X44017Y-625138D01*
G01X47407Y-629138D02*
X47787Y-629721D01*
X48293Y-630055D01*
X48863Y-630138D01*
X49370Y-630055D01*
X49877Y-629638D01*
X50193Y-629138D01*
X50257Y-628638D01*
X50130Y-628055D01*
X49687Y-627638D01*
X49243Y-627471D01*
X48673D01*
G01X49243D02*
X49623Y-627221D01*
X49940Y-626805D01*
X50067Y-626305D01*
X49940Y-625805D01*
X49623Y-625388D01*
X49053Y-625138D01*
X48483Y-625221D01*
X47913Y-625555D01*
G01X52697Y-625971D02*
X53077Y-625471D01*
X53520Y-625221D01*
X54027Y-625138D01*
X54660Y-625305D01*
X55103Y-625721D01*
X55230Y-626221D01*
X55167Y-626721D01*
X54913Y-627138D01*
X53647Y-627971D01*
X53077Y-628555D01*
X52697Y-629388D01*
X52570Y-630138D01*
X55230D01*
G01X58873D02*
X59000Y-629055D01*
X59190Y-628138D01*
X59443Y-627305D01*
X59760Y-626388D01*
X60267Y-625138D01*
X57733D01*
G01X63277Y-628471D02*
X64923D01*
G01X67997Y-625971D02*
X68377Y-625471D01*
X68820Y-625221D01*
X69327Y-625138D01*
X69960Y-625305D01*
X70403Y-625721D01*
X70530Y-626221D01*
X70467Y-626721D01*
X70213Y-627138D01*
X68947Y-627971D01*
X68377Y-628555D01*
X67997Y-629388D01*
X67870Y-630138D01*
X70530D01*
G01X72907Y-629138D02*
X73287Y-629721D01*
X73793Y-630055D01*
X74363Y-630138D01*
X74870Y-630055D01*
X75377Y-629638D01*
X75693Y-629138D01*
X75757Y-628638D01*
X75630Y-628055D01*
X75187Y-627638D01*
X74743Y-627471D01*
X74173D01*
G01X74743D02*
X75123Y-627221D01*
X75440Y-626805D01*
X75567Y-626305D01*
X75440Y-625805D01*
X75123Y-625388D01*
X74553Y-625138D01*
X73983Y-625221D01*
X73413Y-625555D01*
G01X80160Y-630138D02*
Y-625138D01*
X77817Y-628721D01*
X80983D01*
G01X83107Y-629388D02*
X83487Y-629805D01*
X83930Y-630055D01*
X84500Y-630138D01*
X85070Y-629971D01*
X85513Y-629638D01*
X85830Y-629055D01*
X85893Y-628388D01*
X85767Y-627721D01*
X85450Y-627305D01*
X85007Y-626971D01*
X84563Y-626888D01*
X84120Y-626971D01*
X83550Y-627305D01*
X83740Y-625138D01*
X85450D01*
G01X93497Y-630138D02*
Y-625138D01*
X95903D01*
G01X95017Y-627555D02*
X93497D01*
G01X98217Y-630138D02*
X99800Y-625138D01*
X101383Y-630138D01*
G01X100813Y-628388D02*
X98787D01*
G01X103570Y-630138D02*
X106230Y-625138D01*
G01X103570D02*
X106230Y-630138D01*
G01X110000Y-630305D02*
X109873Y-630221D01*
Y-630055D01*
X110000Y-629971D01*
X110127Y-630055D01*
Y-630221D01*
X110000Y-630305D01*
G01Y-628055D02*
X109873Y-627971D01*
Y-627805D01*
X110000Y-627721D01*
X110127Y-627805D01*
Y-627971D01*
X110000Y-628055D01*
G01X114783Y-631805D02*
X114150Y-630971D01*
X113833Y-630138D01*
Y-626805D01*
X114150Y-625971D01*
X114783Y-625138D01*
G01X120200D02*
X119693Y-625305D01*
X119313Y-625721D01*
X119060Y-626221D01*
X118870Y-626888D01*
X118807Y-627638D01*
X118870Y-628388D01*
X119060Y-629055D01*
X119313Y-629555D01*
X119693Y-629971D01*
X120200Y-630138D01*
X120707Y-629971D01*
X121087Y-629555D01*
X121340Y-629055D01*
X121530Y-628388D01*
X121593Y-627638D01*
X121530Y-626888D01*
X121340Y-626221D01*
X121087Y-625721D01*
X120707Y-625305D01*
X120200Y-625138D01*
G01X123907Y-629138D02*
X124287Y-629721D01*
X124793Y-630055D01*
X125363Y-630138D01*
X125870Y-630055D01*
X126377Y-629638D01*
X126693Y-629138D01*
X126757Y-628638D01*
X126630Y-628055D01*
X126187Y-627638D01*
X125743Y-627471D01*
X125173D01*
G01X125743D02*
X126123Y-627221D01*
X126440Y-626805D01*
X126567Y-626305D01*
X126440Y-625805D01*
X126123Y-625388D01*
X125553Y-625138D01*
X124983Y-625221D01*
X124413Y-625555D01*
G01X130717Y-631805D02*
X131350Y-630971D01*
X131667Y-630138D01*
Y-626805D01*
X131350Y-625971D01*
X130717Y-625138D01*
G01X134107Y-629138D02*
X134487Y-629721D01*
X134993Y-630055D01*
X135563Y-630138D01*
X136070Y-630055D01*
X136577Y-629638D01*
X136893Y-629138D01*
X136957Y-628638D01*
X136830Y-628055D01*
X136387Y-627638D01*
X135943Y-627471D01*
X135373D01*
G01X135943D02*
X136323Y-627221D01*
X136640Y-626805D01*
X136767Y-626305D01*
X136640Y-625805D01*
X136323Y-625388D01*
X135753Y-625138D01*
X135183Y-625221D01*
X134613Y-625555D01*
G01X139523Y-629555D02*
X139967Y-629971D01*
X140473Y-630138D01*
X140980Y-629971D01*
X141423Y-629471D01*
X141740Y-628721D01*
X141867Y-627971D01*
Y-627055D01*
X141740Y-626305D01*
X141423Y-625638D01*
X141043Y-625305D01*
X140600Y-625138D01*
X140093Y-625305D01*
X139713Y-625638D01*
X139460Y-626138D01*
X139333Y-626805D01*
X139460Y-627388D01*
X139777Y-627971D01*
X140157Y-628305D01*
X140600Y-628388D01*
X141107Y-628221D01*
X141487Y-627805D01*
X141867Y-627055D01*
G01X145573Y-630138D02*
X145700Y-629055D01*
X145890Y-628138D01*
X146143Y-627305D01*
X146460Y-626388D01*
X146967Y-625138D01*
X144433D01*
G01X149977Y-628471D02*
X151623D01*
G01X154507Y-629138D02*
X154887Y-629721D01*
X155393Y-630055D01*
X155963Y-630138D01*
X156470Y-630055D01*
X156977Y-629638D01*
X157293Y-629138D01*
X157357Y-628638D01*
X157230Y-628055D01*
X156787Y-627638D01*
X156343Y-627471D01*
X155773D01*
G01X156343D02*
X156723Y-627221D01*
X157040Y-626805D01*
X157167Y-626305D01*
X157040Y-625805D01*
X156723Y-625388D01*
X156153Y-625138D01*
X155583Y-625221D01*
X155013Y-625555D01*
G01X159797Y-628055D02*
X160240Y-627471D01*
X160620Y-627138D01*
X161127Y-626971D01*
X161570Y-627138D01*
X161887Y-627471D01*
X162140Y-627971D01*
X162203Y-628555D01*
X162140Y-629055D01*
X161887Y-629555D01*
X161507Y-629971D01*
X161063Y-630138D01*
X160557Y-629971D01*
X160113Y-629471D01*
X159860Y-628721D01*
X159797Y-627888D01*
X159923Y-626805D01*
X160113Y-626221D01*
X160430Y-625638D01*
X160873Y-625221D01*
X161317Y-625138D01*
X161760Y-625305D01*
X162077Y-625721D01*
G01X166100Y-630138D02*
Y-625138D01*
X165340Y-626138D01*
G01Y-630138D02*
X166860D01*
G01X171960D02*
Y-625138D01*
X169617Y-628721D01*
X172783D01*
G01X-4000Y-560138D02*
Y-635138D01*
X496000D01*
Y-560138D01*
X-4000D01*
G01X191000D02*
Y-635138D01*
G01Y-610138D02*
X294000D01*
Y-585138D01*
G01X191000D02*
X294000D01*
G01X296000Y-560138D02*
Y-635138D01*
G01X294000Y-560138D02*
Y-635138D01*
G01X301507Y-620138D02*
Y-615138D01*
X302773D01*
X303280Y-615388D01*
X303660Y-615721D01*
X303977Y-616221D01*
X304230Y-616805D01*
X304293Y-617638D01*
X304230Y-618471D01*
X303977Y-619055D01*
X303660Y-619555D01*
X303280Y-619888D01*
X302773Y-620138D01*
X301507D01*
G01X306417D02*
X308000Y-615138D01*
X309583Y-620138D01*
G01X309013Y-618388D02*
X306987D01*
G01X313100Y-615138D02*
Y-620138D01*
G01X311643Y-615138D02*
X314557D01*
G01X319467Y-620138D02*
X316933D01*
Y-615138D01*
X319467D01*
G01X318453Y-617555D02*
X316933D01*
G01X323300Y-620305D02*
X323173Y-620221D01*
Y-620055D01*
X323300Y-619971D01*
X323427Y-620055D01*
Y-620221D01*
X323300Y-620305D01*
G01Y-618055D02*
X323173Y-617971D01*
Y-617805D01*
X323300Y-617721D01*
X323427Y-617805D01*
Y-617971D01*
X323300Y-618055D01*
G01X296000Y-610138D02*
X496000D01*
G01X301633Y-595138D02*
Y-590138D01*
X303153D01*
X303660Y-590388D01*
X304040Y-590971D01*
X304167Y-591638D01*
X304040Y-592305D01*
X303723Y-592805D01*
X303153Y-593055D01*
X301633D01*
G01X306860Y-595305D02*
X309140Y-590138D01*
G01X311643Y-595138D02*
Y-590138D01*
X314557Y-595138D01*
Y-590138D01*
G01X318200Y-595305D02*
X318073Y-595221D01*
Y-595055D01*
X318200Y-594971D01*
X318327Y-595055D01*
Y-595221D01*
X318200Y-595305D01*
G01Y-593055D02*
X318073Y-592971D01*
Y-592805D01*
X318200Y-592721D01*
X318327Y-592805D01*
Y-592971D01*
X318200Y-593055D01*
G01X296000Y-585138D02*
X496000D01*
G01X301633Y-570138D02*
Y-565138D01*
X303153D01*
X303660Y-565388D01*
X304040Y-565971D01*
X304167Y-566638D01*
X304040Y-567305D01*
X303723Y-567805D01*
X303153Y-568055D01*
X301633D01*
G01X306733Y-570138D02*
Y-565138D01*
X308317D01*
X308823Y-565388D01*
X309140Y-565721D01*
X309267Y-566388D01*
X309140Y-567055D01*
X308760Y-567471D01*
X308317Y-567721D01*
X306733D01*
G01X308317D02*
X309267Y-570138D01*
G01X313100D02*
X312593Y-570055D01*
X312150Y-569721D01*
X311770Y-569221D01*
X311517Y-568638D01*
X311390Y-567971D01*
Y-567305D01*
X311517Y-566638D01*
X311770Y-566055D01*
X312150Y-565555D01*
X312593Y-565221D01*
X313100Y-565138D01*
X313607Y-565221D01*
X314050Y-565555D01*
X314430Y-566055D01*
X314683Y-566638D01*
X314810Y-567305D01*
Y-567971D01*
X314683Y-568638D01*
X314430Y-569221D01*
X314050Y-569721D01*
X313607Y-570055D01*
X313100Y-570138D01*
G01X316933Y-569138D02*
X317250Y-569638D01*
X317630Y-569971D01*
X318073Y-570138D01*
X318580Y-569971D01*
X318960Y-569638D01*
X319340Y-569138D01*
X319467Y-568471D01*
Y-565138D01*
G01X324567Y-570138D02*
X322033D01*
Y-565138D01*
X324567D01*
G01X323553Y-567555D02*
X322033D01*
G01X329793Y-565555D02*
X329413Y-565305D01*
X328970Y-565138D01*
X328463D01*
X327893Y-565388D01*
X327450Y-565805D01*
X327133Y-566305D01*
X326880Y-567138D01*
X326817Y-567888D01*
X326943Y-568638D01*
X327133Y-569138D01*
X327513Y-569638D01*
X327957Y-569971D01*
X328400Y-570138D01*
X328843D01*
X329287Y-569971D01*
X329667Y-569721D01*
X329983Y-569388D01*
G01X333500Y-565138D02*
Y-570138D01*
G01X332043Y-565138D02*
X334957D01*
G01X338600Y-570305D02*
X338473Y-570221D01*
Y-570055D01*
X338600Y-569971D01*
X338727Y-570055D01*
Y-570221D01*
X338600Y-570305D01*
G01Y-568055D02*
X338473Y-567971D01*
Y-567805D01*
X338600Y-567721D01*
X338727Y-567805D01*
Y-567971D01*
X338600Y-568055D01*
G01X411000Y-610138D02*
Y-635138D01*
G01X413633Y-612638D02*
Y-617638D01*
X416167D01*
G01X419240Y-612638D02*
X420760D01*
G01X420000D02*
Y-617638D01*
G01X419240D02*
X420760D01*
G01X425607Y-614971D02*
X425860Y-614721D01*
X426050Y-614305D01*
X426177Y-613721D01*
X426050Y-613221D01*
X425797Y-612888D01*
X425353Y-612638D01*
X423643D01*
Y-617638D01*
X425733D01*
X426177Y-617305D01*
X426430Y-616805D01*
X426557Y-616221D01*
X426430Y-615638D01*
X426050Y-615138D01*
X425607Y-614971D01*
X423643D01*
G01X430200Y-617805D02*
X430073Y-617721D01*
Y-617555D01*
X430200Y-617471D01*
X430327Y-617555D01*
Y-617721D01*
X430200Y-617805D01*
G01Y-615555D02*
X430073Y-615471D01*
Y-615305D01*
X430200Y-615221D01*
X430327Y-615305D01*
Y-615471D01*
X430200Y-615555D01*
G01X454000Y-610138D02*
Y-635138D01*
G01Y-585138D02*
Y-610138D01*
G01X459013Y-637305D02*
X459120Y-637180D01*
X459200Y-636971D01*
X459253Y-636680D01*
X459200Y-636430D01*
X459093Y-636263D01*
X458907Y-636138D01*
X458187D01*
Y-638638D01*
X459067D01*
X459253Y-638471D01*
X459360Y-638221D01*
X459413Y-637930D01*
X459360Y-637638D01*
X459200Y-637388D01*
X459013Y-637305D01*
X458187D01*
G01X461480Y-638638D02*
Y-636971D01*
G01Y-637263D02*
X461373Y-637096D01*
X461213Y-637013D01*
X461027Y-636971D01*
X460840Y-637055D01*
X460680Y-637221D01*
X460573Y-637471D01*
X460520Y-637805D01*
X460573Y-638138D01*
X460680Y-638388D01*
X460840Y-638555D01*
X461027Y-638638D01*
X461213Y-638596D01*
X461373Y-638471D01*
X461480Y-638305D01*
G01X462800Y-638346D02*
X462933Y-638513D01*
X463120Y-638638D01*
X463280D01*
X463440Y-638555D01*
X463547Y-638430D01*
X463600Y-638263D01*
X463573Y-638013D01*
X463467Y-637888D01*
X462987Y-637638D01*
X462880Y-637346D01*
X462933Y-637138D01*
X463040Y-637013D01*
X463200Y-636971D01*
X463360Y-637013D01*
X463520Y-637138D01*
G01X465000Y-637513D02*
X465853D01*
X465773Y-637221D01*
X465640Y-637055D01*
X465453Y-636971D01*
X465267Y-637013D01*
X465107Y-637138D01*
X465000Y-637430D01*
X464947Y-637680D01*
Y-637930D01*
X465000Y-638180D01*
X465133Y-638430D01*
X465293Y-638596D01*
X465480Y-638638D01*
X465667Y-638555D01*
X465853Y-638305D01*
G01X467120Y-638638D02*
Y-636138D01*
G01Y-637388D02*
X467253Y-637138D01*
X467413Y-637013D01*
X467573Y-636971D01*
X467813Y-637055D01*
X467973Y-637221D01*
X468080Y-637513D01*
Y-637846D01*
X468027Y-638180D01*
X467920Y-638430D01*
X467733Y-638596D01*
X467573Y-638638D01*
X467413Y-638596D01*
X467253Y-638471D01*
X467120Y-638263D01*
G01X469800Y-638638D02*
X469640Y-638596D01*
X469480Y-638430D01*
X469373Y-638138D01*
X469320Y-637805D01*
X469373Y-637471D01*
X469480Y-637180D01*
X469640Y-637013D01*
X469800Y-636971D01*
X469960Y-637013D01*
X470120Y-637180D01*
X470227Y-637471D01*
X470253Y-637805D01*
X470227Y-638138D01*
X470120Y-638430D01*
X469960Y-638596D01*
X469800Y-638638D01*
G01X472480D02*
Y-636971D01*
G01Y-637263D02*
X472373Y-637096D01*
X472213Y-637013D01*
X472027Y-636971D01*
X471840Y-637055D01*
X471680Y-637221D01*
X471573Y-637471D01*
X471520Y-637805D01*
X471573Y-638138D01*
X471680Y-638388D01*
X471840Y-638555D01*
X472027Y-638638D01*
X472213Y-638596D01*
X472373Y-638471D01*
X472480Y-638305D01*
G01X473827Y-638638D02*
Y-636971D01*
G01Y-637305D02*
X473960Y-637138D01*
X474093Y-637013D01*
X474280Y-636971D01*
X474413Y-637013D01*
X474573Y-637138D01*
G01X476880Y-636138D02*
Y-638638D01*
G01Y-638263D02*
X476773Y-638471D01*
X476613Y-638596D01*
X476427Y-638638D01*
X476213Y-638555D01*
X476053Y-638346D01*
X475947Y-638096D01*
X475920Y-637805D01*
X475947Y-637513D01*
X476053Y-637263D01*
X476213Y-637055D01*
X476427Y-636971D01*
X476613Y-637013D01*
X476747Y-637096D01*
X476880Y-637263D01*
G01X480267Y-638638D02*
Y-636138D01*
X480933D01*
X481147Y-636263D01*
X481280Y-636430D01*
X481333Y-636763D01*
X481280Y-637096D01*
X481120Y-637305D01*
X480933Y-637430D01*
X480267D01*
G01X480933D02*
X481333Y-638638D01*
G01X482600Y-637513D02*
X483453D01*
X483373Y-637221D01*
X483240Y-637055D01*
X483053Y-636971D01*
X482867Y-637013D01*
X482707Y-637138D01*
X482600Y-637430D01*
X482547Y-637680D01*
Y-637930D01*
X482600Y-638180D01*
X482733Y-638430D01*
X482893Y-638596D01*
X483080Y-638638D01*
X483267Y-638555D01*
X483453Y-638305D01*
G01X484720Y-636971D02*
X485200Y-638638D01*
X485680Y-636971D01*
G01X487400Y-638721D02*
X487347Y-638680D01*
Y-638596D01*
X487400Y-638555D01*
X487453Y-638596D01*
Y-638680D01*
X487400Y-638721D01*
G01X489147Y-638346D02*
X489333Y-638555D01*
X489547Y-638638D01*
X489760Y-638555D01*
X489947Y-638305D01*
X490080Y-637930D01*
X490133Y-637555D01*
Y-637096D01*
X490080Y-636721D01*
X489947Y-636388D01*
X489787Y-636221D01*
X489600Y-636138D01*
X489387Y-636221D01*
X489227Y-636388D01*
X489120Y-636638D01*
X489067Y-636971D01*
X489120Y-637263D01*
X489253Y-637555D01*
X489413Y-637721D01*
X489600Y-637763D01*
X489813Y-637680D01*
X489973Y-637471D01*
X490133Y-637096D01*
G01X492013Y-637305D02*
X492120Y-637180D01*
X492200Y-636971D01*
X492253Y-636680D01*
X492200Y-636430D01*
X492093Y-636263D01*
X491907Y-636138D01*
X491187D01*
Y-638638D01*
X492067D01*
X492253Y-638471D01*
X492360Y-638221D01*
X492413Y-637930D01*
X492360Y-637638D01*
X492200Y-637388D01*
X492013Y-637305D01*
X491187D01*
G01X457900Y-612638D02*
Y-617638D01*
G01X456443Y-612638D02*
X459357D01*
G01X463000Y-617638D02*
X462620Y-617555D01*
X462240Y-617221D01*
X461987Y-616638D01*
X461860Y-615971D01*
X461987Y-615305D01*
X462240Y-614721D01*
X462620Y-614388D01*
X463000Y-614305D01*
X463380Y-614388D01*
X463760Y-614721D01*
X464013Y-615305D01*
X464077Y-615971D01*
X464013Y-616638D01*
X463760Y-617221D01*
X463380Y-617555D01*
X463000Y-617638D01*
G01X468100D02*
X467720Y-617555D01*
X467340Y-617221D01*
X467087Y-616638D01*
X466960Y-615971D01*
X467087Y-615305D01*
X467340Y-614721D01*
X467720Y-614388D01*
X468100Y-614305D01*
X468480Y-614388D01*
X468860Y-614721D01*
X469113Y-615305D01*
X469177Y-615971D01*
X469113Y-616638D01*
X468860Y-617221D01*
X468480Y-617555D01*
X468100Y-617638D01*
G01X473200D02*
Y-612638D01*
G01X478300Y-617805D02*
X478173Y-617721D01*
Y-617555D01*
X478300Y-617471D01*
X478427Y-617555D01*
Y-617721D01*
X478300Y-617805D01*
G01Y-615555D02*
X478173Y-615471D01*
Y-615305D01*
X478300Y-615221D01*
X478427Y-615305D01*
Y-615471D01*
X478300Y-615555D01*
G01X456633Y-592638D02*
Y-587638D01*
X458217D01*
X458723Y-587888D01*
X459040Y-588221D01*
X459167Y-588888D01*
X459040Y-589555D01*
X458660Y-589971D01*
X458217Y-590221D01*
X456633D01*
G01X458217D02*
X459167Y-592638D01*
G01X464267D02*
X461733D01*
Y-587638D01*
X464267D01*
G01X463253Y-590055D02*
X461733D01*
G01X466517Y-587638D02*
X468100Y-592638D01*
X469683Y-587638D01*
G01X473200Y-592805D02*
X473073Y-592721D01*
Y-592555D01*
X473200Y-592471D01*
X473327Y-592555D01*
Y-592721D01*
X473200Y-592805D01*
G01Y-590555D02*
X473073Y-590471D01*
Y-590305D01*
X473200Y-590221D01*
X473327Y-590305D01*
Y-590471D01*
X473200Y-590555D01*
G01X-476840Y-884638D02*
Y2768362D01*
X5911000D01*
Y-884638D01*
X-476840D01*
G01X8820Y-607488D02*
X10387D01*
Y-609378D01*
X9917Y-610008D01*
X9368Y-610428D01*
X8585Y-610638D01*
X7802Y-610428D01*
X7253Y-610008D01*
X6783Y-609378D01*
X6470Y-608643D01*
X6313Y-607803D01*
Y-607068D01*
X6470Y-606438D01*
X6783Y-605703D01*
X7253Y-605073D01*
X7723Y-604653D01*
X8350Y-604338D01*
X8898D01*
X9525Y-604548D01*
X9995Y-604968D01*
G01X12927Y-604338D02*
Y-608853D01*
X13240Y-609798D01*
X13867Y-610428D01*
X14650Y-610638D01*
X15433Y-610428D01*
X16060Y-609798D01*
X16373Y-608853D01*
Y-604338D01*
G01X20010D02*
X21890D01*
G01X20950D02*
Y-610638D01*
G01X20010D02*
X21890D01*
G01X25605Y-609798D02*
X26232Y-610323D01*
X26937Y-610638D01*
X27563D01*
X28190Y-610323D01*
X28660Y-609798D01*
X28895Y-609063D01*
X28738Y-608328D01*
X28347Y-607698D01*
X27642Y-607278D01*
X26702Y-607068D01*
X26153Y-606648D01*
X25918Y-605913D01*
X26075Y-605178D01*
X26467Y-604653D01*
X27015Y-604338D01*
X27563D01*
X28112Y-604548D01*
X28582Y-605073D01*
G01X31905Y-610638D02*
Y-604338D01*
G01X35195D02*
Y-610638D01*
G01Y-607488D02*
X31905D01*
G01X37892Y-610638D02*
X39850Y-604338D01*
X41808Y-610638D01*
G01X41103Y-608433D02*
X38597D01*
G01X44348Y-610638D02*
Y-604338D01*
X47952Y-610638D01*
Y-604338D01*
G01X57027Y-610638D02*
Y-604338D01*
X58593D01*
X59220Y-604653D01*
X59690Y-605073D01*
X60082Y-605703D01*
X60395Y-606438D01*
X60473Y-607488D01*
X60395Y-608538D01*
X60082Y-609273D01*
X59690Y-609903D01*
X59220Y-610323D01*
X58593Y-610638D01*
X57027D01*
G01X64110Y-604338D02*
X65990D01*
G01X65050D02*
Y-610638D01*
G01X64110D02*
X65990D01*
G01X69705Y-609798D02*
X70332Y-610323D01*
X71037Y-610638D01*
X71663D01*
X72290Y-610323D01*
X72760Y-609798D01*
X72995Y-609063D01*
X72838Y-608328D01*
X72447Y-607698D01*
X71742Y-607278D01*
X70802Y-607068D01*
X70253Y-606648D01*
X70018Y-605913D01*
X70175Y-605178D01*
X70567Y-604653D01*
X71115Y-604338D01*
X71663D01*
X72212Y-604548D01*
X72682Y-605073D01*
G01X77650Y-604338D02*
Y-610638D01*
G01X75848Y-604338D02*
X79452D01*
G01X83950Y-610848D02*
X83793Y-610743D01*
Y-610533D01*
X83950Y-610428D01*
X84107Y-610533D01*
Y-610743D01*
X83950Y-610848D01*
G01X90093Y-611793D02*
X90407Y-610428D01*
G01X96550Y-604338D02*
Y-610638D01*
G01X94748Y-604338D02*
X98352D01*
G01X100892Y-610638D02*
X102850Y-604338D01*
X104808Y-610638D01*
G01X104103Y-608433D02*
X101597D01*
G01X109150Y-610638D02*
X108523Y-610533D01*
X107975Y-610113D01*
X107505Y-609483D01*
X107192Y-608748D01*
X107035Y-607908D01*
Y-607068D01*
X107192Y-606228D01*
X107505Y-605493D01*
X107975Y-604863D01*
X108523Y-604443D01*
X109150Y-604338D01*
X109777Y-604443D01*
X110325Y-604863D01*
X110795Y-605493D01*
X111108Y-606228D01*
X111265Y-607068D01*
Y-607908D01*
X111108Y-608748D01*
X110795Y-609483D01*
X110325Y-610113D01*
X109777Y-610533D01*
X109150Y-610638D01*
G01X115450D02*
Y-607803D01*
X113883Y-604338D01*
G01X117017D02*
X115450Y-607803D01*
G01X120027Y-604338D02*
Y-608853D01*
X120340Y-609798D01*
X120967Y-610428D01*
X121750Y-610638D01*
X122533Y-610428D01*
X123160Y-609798D01*
X123473Y-608853D01*
Y-604338D01*
G01X126092Y-610638D02*
X128050Y-604338D01*
X130008Y-610638D01*
G01X129303Y-608433D02*
X126797D01*
G01X132548Y-610638D02*
Y-604338D01*
X136152Y-610638D01*
Y-604338D01*
G01X10073Y-614863D02*
X9603Y-614548D01*
X9055Y-614338D01*
X8428D01*
X7723Y-614653D01*
X7175Y-615178D01*
X6783Y-615808D01*
X6470Y-616858D01*
X6392Y-617803D01*
X6548Y-618748D01*
X6783Y-619378D01*
X7253Y-620008D01*
X7802Y-620428D01*
X8350Y-620638D01*
X8898D01*
X9447Y-620428D01*
X9917Y-620113D01*
X10308Y-619693D01*
G01X13710Y-614338D02*
X15590D01*
G01X14650D02*
Y-620638D01*
G01X13710D02*
X15590D01*
G01X20950Y-614338D02*
Y-620638D01*
G01X19148Y-614338D02*
X22752D01*
G01X27250Y-620638D02*
Y-617803D01*
X25683Y-614338D01*
G01X28817D02*
X27250Y-617803D01*
G01X38127Y-619378D02*
X38597Y-620113D01*
X39223Y-620533D01*
X39928Y-620638D01*
X40555Y-620533D01*
X41182Y-620008D01*
X41573Y-619378D01*
X41652Y-618748D01*
X41495Y-618013D01*
X40947Y-617488D01*
X40398Y-617278D01*
X39693D01*
G01X40398D02*
X40868Y-616963D01*
X41260Y-616438D01*
X41417Y-615808D01*
X41260Y-615178D01*
X40868Y-614653D01*
X40163Y-614338D01*
X39458Y-614443D01*
X38753Y-614863D01*
G01X44427Y-619378D02*
X44897Y-620113D01*
X45523Y-620533D01*
X46228Y-620638D01*
X46855Y-620533D01*
X47482Y-620008D01*
X47873Y-619378D01*
X47952Y-618748D01*
X47795Y-618013D01*
X47247Y-617488D01*
X46698Y-617278D01*
X45993D01*
G01X46698D02*
X47168Y-616963D01*
X47560Y-616438D01*
X47717Y-615808D01*
X47560Y-615178D01*
X47168Y-614653D01*
X46463Y-614338D01*
X45758Y-614443D01*
X45053Y-614863D01*
G01X50727Y-619378D02*
X51197Y-620113D01*
X51823Y-620533D01*
X52528Y-620638D01*
X53155Y-620533D01*
X53782Y-620008D01*
X54173Y-619378D01*
X54252Y-618748D01*
X54095Y-618013D01*
X53547Y-617488D01*
X52998Y-617278D01*
X52293D01*
G01X52998D02*
X53468Y-616963D01*
X53860Y-616438D01*
X54017Y-615808D01*
X53860Y-615178D01*
X53468Y-614653D01*
X52763Y-614338D01*
X52058Y-614443D01*
X51353Y-614863D01*
G01X58593Y-620638D02*
X58750Y-619273D01*
X58985Y-618118D01*
X59298Y-617068D01*
X59690Y-615913D01*
X60317Y-614338D01*
X57183D01*
G01X64893Y-620638D02*
X65050Y-619273D01*
X65285Y-618118D01*
X65598Y-617068D01*
X65990Y-615913D01*
X66617Y-614338D01*
X63483D01*
G01X71193Y-621793D02*
X71507Y-620428D01*
G01X77650Y-614338D02*
Y-620638D01*
G01X75848Y-614338D02*
X79452D01*
G01X81992Y-620638D02*
X83950Y-614338D01*
X85908Y-620638D01*
G01X85203Y-618433D02*
X82697D01*
G01X89310Y-614338D02*
X91190D01*
G01X90250D02*
Y-620638D01*
G01X89310D02*
X91190D01*
G01X94200Y-614338D02*
X95297Y-620638D01*
X96550Y-614338D01*
X97803Y-620638D01*
X98900Y-614338D01*
G01X100892Y-620638D02*
X102850Y-614338D01*
X104808Y-620638D01*
G01X104103Y-618433D02*
X101597D01*
G01X107348Y-620638D02*
Y-614338D01*
X110952Y-620638D01*
Y-614338D01*
G01X121358Y-622738D02*
X120575Y-621688D01*
X120183Y-620638D01*
Y-616438D01*
X120575Y-615388D01*
X121358Y-614338D01*
G01X132783Y-620638D02*
Y-614338D01*
X134742D01*
X135368Y-614653D01*
X135760Y-615073D01*
X135917Y-615913D01*
X135760Y-616753D01*
X135290Y-617278D01*
X134742Y-617593D01*
X132783D01*
G01X134742D02*
X135917Y-620638D01*
G01X140650Y-620848D02*
X140493Y-620743D01*
Y-620533D01*
X140650Y-620428D01*
X140807Y-620533D01*
Y-620743D01*
X140650Y-620848D01*
G01X146950Y-620638D02*
X146323Y-620533D01*
X145775Y-620113D01*
X145305Y-619483D01*
X144992Y-618748D01*
X144835Y-617908D01*
Y-617068D01*
X144992Y-616228D01*
X145305Y-615493D01*
X145775Y-614863D01*
X146323Y-614443D01*
X146950Y-614338D01*
X147577Y-614443D01*
X148125Y-614863D01*
X148595Y-615493D01*
X148908Y-616228D01*
X149065Y-617068D01*
Y-617908D01*
X148908Y-618748D01*
X148595Y-619483D01*
X148125Y-620113D01*
X147577Y-620533D01*
X146950Y-620638D01*
G01X153250Y-620848D02*
X153093Y-620743D01*
Y-620533D01*
X153250Y-620428D01*
X153407Y-620533D01*
Y-620743D01*
X153250Y-620848D01*
G01X161273Y-614863D02*
X160803Y-614548D01*
X160255Y-614338D01*
X159628D01*
X158923Y-614653D01*
X158375Y-615178D01*
X157983Y-615808D01*
X157670Y-616858D01*
X157592Y-617803D01*
X157748Y-618748D01*
X157983Y-619378D01*
X158453Y-620008D01*
X159002Y-620428D01*
X159550Y-620638D01*
X160098D01*
X160647Y-620428D01*
X161117Y-620113D01*
X161508Y-619693D01*
G01X165850Y-620848D02*
X165693Y-620743D01*
Y-620533D01*
X165850Y-620428D01*
X166007Y-620533D01*
Y-620743D01*
X165850Y-620848D01*
G01X172542Y-622738D02*
X173325Y-621688D01*
X173717Y-620638D01*
Y-616438D01*
X173325Y-615388D01*
X172542Y-614338D01*
G01X6548Y-600638D02*
Y-594338D01*
X10152Y-600638D01*
Y-594338D01*
G01X14650Y-600638D02*
X14023Y-600533D01*
X13475Y-600113D01*
X13005Y-599483D01*
X12692Y-598748D01*
X12535Y-597908D01*
Y-597068D01*
X12692Y-596228D01*
X13005Y-595493D01*
X13475Y-594863D01*
X14023Y-594443D01*
X14650Y-594338D01*
X15277Y-594443D01*
X15825Y-594863D01*
X16295Y-595493D01*
X16608Y-596228D01*
X16765Y-597068D01*
Y-597908D01*
X16608Y-598748D01*
X16295Y-599483D01*
X15825Y-600113D01*
X15277Y-600533D01*
X14650Y-600638D01*
G01X20950Y-600848D02*
X20793Y-600743D01*
Y-600533D01*
X20950Y-600428D01*
X21107Y-600533D01*
Y-600743D01*
X20950Y-600848D01*
G01X25762Y-595388D02*
X26232Y-594758D01*
X26780Y-594443D01*
X27407Y-594338D01*
X28190Y-594548D01*
X28738Y-595073D01*
X28895Y-595703D01*
X28817Y-596333D01*
X28503Y-596858D01*
X26937Y-597908D01*
X26232Y-598643D01*
X25762Y-599693D01*
X25605Y-600638D01*
X28895D01*
G01X33550D02*
Y-594338D01*
X32610Y-595598D01*
G01Y-600638D02*
X34490D01*
G01X39850D02*
Y-594338D01*
X38910Y-595598D01*
G01Y-600638D02*
X40790D01*
G01X45993Y-601793D02*
X46307Y-600428D01*
G01X50100Y-594338D02*
X51197Y-600638D01*
X52450Y-594338D01*
X53703Y-600638D01*
X54800Y-594338D01*
G01X60317Y-600638D02*
X57183D01*
Y-594338D01*
X60317D01*
G01X59063Y-597383D02*
X57183D01*
G01X63248Y-600638D02*
Y-594338D01*
X66852Y-600638D01*
Y-594338D01*
G01X69705Y-600638D02*
Y-594338D01*
G01X72995D02*
Y-600638D01*
G01Y-597488D02*
X69705D01*
G01X75927Y-594338D02*
Y-598853D01*
X76240Y-599798D01*
X76867Y-600428D01*
X77650Y-600638D01*
X78433Y-600428D01*
X79060Y-599798D01*
X79373Y-598853D01*
Y-594338D01*
G01X81992Y-600638D02*
X83950Y-594338D01*
X85908Y-600638D01*
G01X85203Y-598433D02*
X82697D01*
G01X95062Y-595388D02*
X95532Y-594758D01*
X96080Y-594443D01*
X96707Y-594338D01*
X97490Y-594548D01*
X98038Y-595073D01*
X98195Y-595703D01*
X98117Y-596333D01*
X97803Y-596858D01*
X96237Y-597908D01*
X95532Y-598643D01*
X95062Y-599693D01*
X94905Y-600638D01*
X98195D01*
G01X101048D02*
Y-594338D01*
X104652Y-600638D01*
Y-594338D01*
G01X107427Y-600638D02*
Y-594338D01*
X108993D01*
X109620Y-594653D01*
X110090Y-595073D01*
X110482Y-595703D01*
X110795Y-596438D01*
X110873Y-597488D01*
X110795Y-598538D01*
X110482Y-599273D01*
X110090Y-599903D01*
X109620Y-600323D01*
X108993Y-600638D01*
X107427D01*
G01X120183D02*
Y-594338D01*
X122142D01*
X122768Y-594653D01*
X123160Y-595073D01*
X123317Y-595913D01*
X123160Y-596753D01*
X122690Y-597278D01*
X122142Y-597593D01*
X120183D01*
G01X122142D02*
X123317Y-600638D01*
G01X126327D02*
Y-594338D01*
X127893D01*
X128520Y-594653D01*
X128990Y-595073D01*
X129382Y-595703D01*
X129695Y-596438D01*
X129773Y-597488D01*
X129695Y-598538D01*
X129382Y-599273D01*
X128990Y-599903D01*
X128520Y-600323D01*
X127893Y-600638D01*
X126327D01*
G01X134350Y-600848D02*
X134193Y-600743D01*
Y-600533D01*
X134350Y-600428D01*
X134507Y-600533D01*
Y-600743D01*
X134350Y-600848D01*
G01X30650Y-589938D02*
X28130Y-589521D01*
X25925Y-587855D01*
X24035Y-585355D01*
X22775Y-582438D01*
X22145Y-579105D01*
Y-575771D01*
X22775Y-572438D01*
X24035Y-569521D01*
X25925Y-567022D01*
X28130Y-565355D01*
X30650Y-564938D01*
X33170Y-565355D01*
X35375Y-567022D01*
X37265Y-569521D01*
X38525Y-572438D01*
X39155Y-575771D01*
Y-579105D01*
X38525Y-582438D01*
X37265Y-585355D01*
X35375Y-587855D01*
X33170Y-589521D01*
X30650Y-589938D01*
G01X33170Y-583271D02*
X36950Y-589938D01*
G01X50495Y-573272D02*
Y-584938D01*
X51755Y-587855D01*
X53645Y-589521D01*
X55850Y-589938D01*
X58055Y-589521D01*
X59945Y-587855D01*
X61205Y-584938D01*
G01Y-589938D02*
Y-573272D01*
G01X86720Y-589938D02*
Y-573272D01*
G01Y-576188D02*
X85460Y-574522D01*
X83570Y-573688D01*
X81365Y-573272D01*
X79160Y-574105D01*
X77270Y-575771D01*
X76010Y-578272D01*
X75380Y-581605D01*
X76010Y-584938D01*
X77270Y-587439D01*
X79160Y-589105D01*
X81365Y-589938D01*
X83570Y-589521D01*
X85460Y-588272D01*
X86720Y-586605D01*
G01X100895Y-589938D02*
Y-573272D01*
G01Y-577438D02*
X102155Y-575355D01*
X104045Y-573688D01*
X106565Y-573272D01*
X108770Y-573688D01*
X110660Y-575355D01*
X111605Y-578272D01*
Y-589938D01*
G01X131450Y-564938D02*
Y-589938D01*
G01X127040Y-573272D02*
X135860D01*
G01X162320Y-589938D02*
Y-573272D01*
G01Y-576188D02*
X161060Y-574522D01*
X159170Y-573688D01*
X156965Y-573272D01*
X154760Y-574105D01*
X152870Y-575771D01*
X151610Y-578272D01*
X150980Y-581605D01*
X151610Y-584938D01*
X152870Y-587439D01*
X154760Y-589105D01*
X156965Y-589938D01*
X159170Y-589521D01*
X161060Y-588272D01*
X162320Y-586605D01*
G01X202000Y-569638D02*
Y-577638D01*
X206000D01*
G01X213800D02*
Y-572305D01*
G01Y-573238D02*
X213400Y-572705D01*
X212800Y-572438D01*
X212100Y-572305D01*
X211400Y-572571D01*
X210800Y-573105D01*
X210400Y-573905D01*
X210200Y-574971D01*
X210400Y-576038D01*
X210800Y-576838D01*
X211400Y-577371D01*
X212100Y-577638D01*
X212800Y-577505D01*
X213400Y-577105D01*
X213800Y-576572D01*
G01X217900Y-580038D02*
X218500Y-580305D01*
X219300Y-580038D01*
X219800Y-579505D01*
X220200Y-578838D01*
X220800Y-576705D01*
X222100Y-572305D01*
G01X218900D02*
X220800Y-576705D01*
G01X226500Y-574038D02*
X229700D01*
X229400Y-573105D01*
X228900Y-572571D01*
X228200Y-572305D01*
X227500Y-572438D01*
X226900Y-572838D01*
X226500Y-573771D01*
X226300Y-574572D01*
Y-575371D01*
X226500Y-576171D01*
X227000Y-576971D01*
X227600Y-577505D01*
X228300Y-577638D01*
X229000Y-577371D01*
X229700Y-576572D01*
G01X234600Y-577638D02*
Y-572305D01*
G01Y-573371D02*
X235100Y-572838D01*
X235600Y-572438D01*
X236300Y-572305D01*
X236800Y-572438D01*
X237400Y-572838D01*
G01X226000Y-626038D02*
X226500Y-626838D01*
X227100Y-627371D01*
X227800Y-627638D01*
X228600Y-627371D01*
X229200Y-626838D01*
X229800Y-626038D01*
X230000Y-624971D01*
Y-619638D01*
G01X237800Y-627638D02*
Y-622305D01*
G01Y-623238D02*
X237400Y-622705D01*
X236800Y-622438D01*
X236100Y-622305D01*
X235400Y-622571D01*
X234800Y-623105D01*
X234400Y-623905D01*
X234200Y-624971D01*
X234400Y-626038D01*
X234800Y-626838D01*
X235400Y-627371D01*
X236100Y-627638D01*
X236800Y-627505D01*
X237400Y-627105D01*
X237800Y-626572D01*
G01X245600Y-622971D02*
X244900Y-622438D01*
X244300Y-622305D01*
X243500Y-622571D01*
X242900Y-623105D01*
X242500Y-624038D01*
X242400Y-624971D01*
X242500Y-625905D01*
X242900Y-626705D01*
X243500Y-627371D01*
X244300Y-627638D01*
X245000Y-627371D01*
X245600Y-626838D01*
G01X250300Y-627638D02*
Y-619638D01*
G01X253500Y-622305D02*
X250300Y-625371D01*
G01X251600Y-624171D02*
X253700Y-627638D01*
G01X229800Y-598038D02*
X231800D01*
Y-600438D01*
X231200Y-601238D01*
X230500Y-601771D01*
X229500Y-602038D01*
X228500Y-601771D01*
X227800Y-601238D01*
X227200Y-600438D01*
X226800Y-599505D01*
X226600Y-598438D01*
Y-597505D01*
X226800Y-596705D01*
X227200Y-595771D01*
X227800Y-594971D01*
X228400Y-594438D01*
X229200Y-594038D01*
X229900D01*
X230700Y-594305D01*
X231300Y-594838D01*
G01X234900Y-602038D02*
Y-594038D01*
X239500Y-602038D01*
Y-594038D01*
G01X243000Y-602038D02*
Y-594038D01*
X245000D01*
X245800Y-594438D01*
X246400Y-594971D01*
X246900Y-595771D01*
X247300Y-596705D01*
X247400Y-598038D01*
X247300Y-599371D01*
X246900Y-600305D01*
X246400Y-601105D01*
X245800Y-601638D01*
X245000Y-602038D01*
X243000D01*
G01X254400D02*
Y-594038D01*
X250700Y-599771D01*
X255700D01*
G01X264000Y-578338D02*
Y-570338D01*
X262800Y-571938D01*
G01Y-578338D02*
X265200D01*
G01X272000D02*
Y-570338D01*
X270800Y-571938D01*
G01Y-578338D02*
X273200D01*
G01X328600Y-620971D02*
X329200Y-620171D01*
X329900Y-619771D01*
X330700Y-619638D01*
X331700Y-619905D01*
X332400Y-620571D01*
X332600Y-621371D01*
X332500Y-622172D01*
X332100Y-622838D01*
X330100Y-624171D01*
X329200Y-625105D01*
X328600Y-626438D01*
X328400Y-627638D01*
X332600D01*
G01X338500Y-619638D02*
X337700Y-619905D01*
X337100Y-620571D01*
X336700Y-621371D01*
X336400Y-622438D01*
X336300Y-623638D01*
X336400Y-624838D01*
X336700Y-625905D01*
X337100Y-626705D01*
X337700Y-627371D01*
X338500Y-627638D01*
X339300Y-627371D01*
X339900Y-626705D01*
X340300Y-625905D01*
X340600Y-624838D01*
X340700Y-623638D01*
X340600Y-622438D01*
X340300Y-621371D01*
X339900Y-620571D01*
X339300Y-619905D01*
X338500Y-619638D01*
G01X344600Y-620971D02*
X345200Y-620171D01*
X345900Y-619771D01*
X346700Y-619638D01*
X347700Y-619905D01*
X348400Y-620571D01*
X348600Y-621371D01*
X348500Y-622172D01*
X348100Y-622838D01*
X346100Y-624171D01*
X345200Y-625105D01*
X344600Y-626438D01*
X344400Y-627638D01*
X348600D01*
G01X352300Y-626038D02*
X352900Y-626971D01*
X353700Y-627505D01*
X354600Y-627638D01*
X355400Y-627505D01*
X356200Y-626838D01*
X356700Y-626038D01*
X356800Y-625238D01*
X356600Y-624305D01*
X355900Y-623638D01*
X355200Y-623371D01*
X354300D01*
G01X355200D02*
X355800Y-622971D01*
X356300Y-622305D01*
X356500Y-621505D01*
X356300Y-620705D01*
X355800Y-620038D01*
X354900Y-619638D01*
X354000Y-619771D01*
X353100Y-620305D01*
G01X360700Y-627905D02*
X364300Y-619638D01*
G01X370500D02*
X369700Y-619905D01*
X369100Y-620571D01*
X368700Y-621371D01*
X368400Y-622438D01*
X368300Y-623638D01*
X368400Y-624838D01*
X368700Y-625905D01*
X369100Y-626705D01*
X369700Y-627371D01*
X370500Y-627638D01*
X371300Y-627371D01*
X371900Y-626705D01*
X372300Y-625905D01*
X372600Y-624838D01*
X372700Y-623638D01*
X372600Y-622438D01*
X372300Y-621371D01*
X371900Y-620571D01*
X371300Y-619905D01*
X370500Y-619638D01*
G01X379700Y-627638D02*
Y-619638D01*
X376000Y-625371D01*
X381000D01*
G01X384700Y-627905D02*
X388300Y-619638D01*
G01X394500Y-627638D02*
Y-619638D01*
X393300Y-621238D01*
G01Y-627638D02*
X395700D01*
G01X402300D02*
X402500Y-625905D01*
X402800Y-624438D01*
X403200Y-623105D01*
X403700Y-621638D01*
X404500Y-619638D01*
X400500D01*
G01X328300Y-602638D02*
Y-594638D01*
X330300D01*
X331100Y-595038D01*
X331700Y-595571D01*
X332200Y-596371D01*
X332600Y-597305D01*
X332700Y-598638D01*
X332600Y-599971D01*
X332200Y-600905D01*
X331700Y-601705D01*
X331100Y-602238D01*
X330300Y-602638D01*
X328300D01*
G01X336000D02*
X338500Y-594638D01*
X341000Y-602638D01*
G01X340100Y-599838D02*
X336900D01*
G01X344600Y-602638D02*
Y-594638D01*
X348400D01*
G01X347000Y-598505D02*
X344600D01*
G01X354500Y-594638D02*
X353700Y-594905D01*
X353100Y-595571D01*
X352700Y-596371D01*
X352400Y-597438D01*
X352300Y-598638D01*
X352400Y-599838D01*
X352700Y-600905D01*
X353100Y-601705D01*
X353700Y-602371D01*
X354500Y-602638D01*
X355300Y-602371D01*
X355900Y-601705D01*
X356300Y-600905D01*
X356600Y-599838D01*
X356700Y-598638D01*
X356600Y-597438D01*
X356300Y-596371D01*
X355900Y-595571D01*
X355300Y-594905D01*
X354500Y-594638D01*
G01X362500D02*
Y-602638D01*
G01X360200Y-594638D02*
X364800D01*
G01X367900Y-602638D02*
Y-594638D01*
X370500Y-601305D01*
X373100Y-594638D01*
Y-602638D01*
G01X379300Y-598371D02*
X379700Y-597971D01*
X380000Y-597305D01*
X380200Y-596371D01*
X380000Y-595571D01*
X379600Y-595038D01*
X378900Y-594638D01*
X376200D01*
Y-602638D01*
X379500D01*
X380200Y-602105D01*
X380600Y-601305D01*
X380800Y-600371D01*
X380600Y-599438D01*
X380000Y-598638D01*
X379300Y-598371D01*
X376200D01*
G01X384300Y-601038D02*
X384900Y-601971D01*
X385700Y-602505D01*
X386600Y-602638D01*
X387400Y-602505D01*
X388200Y-601838D01*
X388700Y-601038D01*
X388800Y-600238D01*
X388600Y-599305D01*
X387900Y-598638D01*
X387200Y-598371D01*
X386300D01*
G01X387200D02*
X387800Y-597971D01*
X388300Y-597305D01*
X388500Y-596505D01*
X388300Y-595705D01*
X387800Y-595038D01*
X386900Y-594638D01*
X386000Y-594771D01*
X385100Y-595305D01*
G01X393300Y-594638D02*
X395700D01*
G01X394500D02*
Y-602638D01*
G01X393300D02*
X395700D01*
G01X404700Y-595305D02*
X404100Y-594905D01*
X403400Y-594638D01*
X402600D01*
X401700Y-595038D01*
X401000Y-595705D01*
X400500Y-596505D01*
X400100Y-597838D01*
X400000Y-599038D01*
X400200Y-600238D01*
X400500Y-601038D01*
X401100Y-601838D01*
X401800Y-602371D01*
X402500Y-602638D01*
X403200D01*
X403900Y-602371D01*
X404500Y-601971D01*
X405000Y-601438D01*
G01X410500Y-594638D02*
X409700Y-594905D01*
X409100Y-595571D01*
X408700Y-596371D01*
X408400Y-597438D01*
X408300Y-598638D01*
X408400Y-599838D01*
X408700Y-600905D01*
X409100Y-601705D01*
X409700Y-602371D01*
X410500Y-602638D01*
X411300Y-602371D01*
X411900Y-601705D01*
X412300Y-600905D01*
X412600Y-599838D01*
X412700Y-598638D01*
X412600Y-597438D01*
X412300Y-596371D01*
X411900Y-595571D01*
X411300Y-594905D01*
X410500Y-594638D01*
G01X346100Y-577638D02*
Y-569638D01*
X349900D01*
G01X348500Y-573505D02*
X346100D01*
G01X356000Y-569638D02*
X355200Y-569905D01*
X354600Y-570571D01*
X354200Y-571371D01*
X353900Y-572438D01*
X353800Y-573638D01*
X353900Y-574838D01*
X354200Y-575905D01*
X354600Y-576705D01*
X355200Y-577371D01*
X356000Y-577638D01*
X356800Y-577371D01*
X357400Y-576705D01*
X357800Y-575905D01*
X358100Y-574838D01*
X358200Y-573638D01*
X358100Y-572438D01*
X357800Y-571371D01*
X357400Y-570571D01*
X356800Y-569905D01*
X356000Y-569638D01*
G01X364000D02*
Y-577638D01*
G01X361700Y-569638D02*
X366300D01*
G01X372600Y-573638D02*
X374600D01*
Y-576038D01*
X374000Y-576838D01*
X373300Y-577371D01*
X372300Y-577638D01*
X371300Y-577371D01*
X370600Y-576838D01*
X370000Y-576038D01*
X369600Y-575105D01*
X369400Y-574038D01*
Y-573105D01*
X369600Y-572305D01*
X370000Y-571371D01*
X370600Y-570571D01*
X371200Y-570038D01*
X372000Y-569638D01*
X372700D01*
X373500Y-569905D01*
X374100Y-570438D01*
G01X377000Y-580305D02*
X383000D01*
G01X385400Y-577638D02*
Y-569638D01*
X388000Y-576305D01*
X390600Y-569638D01*
Y-577638D01*
G01X396800Y-573371D02*
X397200Y-572971D01*
X397500Y-572305D01*
X397700Y-571371D01*
X397500Y-570571D01*
X397100Y-570038D01*
X396400Y-569638D01*
X393700D01*
Y-577638D01*
X397000D01*
X397700Y-577105D01*
X398100Y-576305D01*
X398300Y-575371D01*
X398100Y-574438D01*
X397500Y-573638D01*
X396800Y-573371D01*
X393700D01*
G01X417000Y-630638D02*
Y-622638D01*
X415800Y-624238D01*
G01Y-630638D02*
X418200D01*
G01X423100Y-627305D02*
X423800Y-626371D01*
X424400Y-625838D01*
X425200Y-625571D01*
X425900Y-625838D01*
X426400Y-626371D01*
X426800Y-627171D01*
X426900Y-628105D01*
X426800Y-628905D01*
X426400Y-629705D01*
X425800Y-630371D01*
X425100Y-630638D01*
X424300Y-630371D01*
X423600Y-629572D01*
X423200Y-628371D01*
X423100Y-627038D01*
X423300Y-625305D01*
X423600Y-624371D01*
X424100Y-623438D01*
X424800Y-622771D01*
X425500Y-622638D01*
X426200Y-622905D01*
X426700Y-623571D01*
G01X433000Y-630905D02*
X432800Y-630771D01*
Y-630505D01*
X433000Y-630371D01*
X433200Y-630505D01*
Y-630771D01*
X433000Y-630905D01*
G01X439100Y-627305D02*
X439800Y-626371D01*
X440400Y-625838D01*
X441200Y-625571D01*
X441900Y-625838D01*
X442400Y-626371D01*
X442800Y-627171D01*
X442900Y-628105D01*
X442800Y-628905D01*
X442400Y-629705D01*
X441800Y-630371D01*
X441100Y-630638D01*
X440300Y-630371D01*
X439600Y-629572D01*
X439200Y-628371D01*
X439100Y-627038D01*
X439300Y-625305D01*
X439600Y-624371D01*
X440100Y-623438D01*
X440800Y-622771D01*
X441500Y-622638D01*
X442200Y-622905D01*
X442700Y-623571D01*
G01X462000Y-630638D02*
Y-622638D01*
X460800Y-624238D01*
G01Y-630638D02*
X463200D01*
G01X469800D02*
X470000Y-628905D01*
X470300Y-627438D01*
X470700Y-626105D01*
X471200Y-624638D01*
X472000Y-622638D01*
X468000D01*
G01X478000Y-630905D02*
X477800Y-630771D01*
Y-630505D01*
X478000Y-630371D01*
X478200Y-630505D01*
Y-630771D01*
X478000Y-630905D01*
G01X484100Y-623971D02*
X484700Y-623171D01*
X485400Y-622771D01*
X486200Y-622638D01*
X487200Y-622905D01*
X487900Y-623571D01*
X488100Y-624371D01*
X488000Y-625172D01*
X487600Y-625838D01*
X485600Y-627171D01*
X484700Y-628105D01*
X484100Y-629438D01*
X483900Y-630638D01*
X488100D01*
G01X486200Y-598305D02*
X485600Y-597905D01*
X484900Y-597638D01*
X484100D01*
X483200Y-598038D01*
X482500Y-598705D01*
X482000Y-599505D01*
X481600Y-600838D01*
X481500Y-602038D01*
X481700Y-603238D01*
X482000Y-604038D01*
X482600Y-604838D01*
X483300Y-605371D01*
X484000Y-605638D01*
X484700D01*
X485400Y-605371D01*
X486000Y-604971D01*
X486500Y-604438D01*
M02*
